FILE_TYPE=CROSS_REFERENCE;
ROOT_DRAWING='S9S_MB_2U';
RUN_TIME='Nov 24 16:42:27 2020';
PROGRAM_VERSION='16.20-p001';
**** Part Type '10M04SAU324I7G' ('10M04SAU324I7G-10M04SAU324I7G,A') ****
**** Part Type '74CBTLV3126PW' ('74CBTLV3126PW-74CBTLV3126PW,SMA') ****
**** Part Type '74CBTLV3126PW' ('74CBTLV3126PW-74CBTLV3126PW,SMB') ****
**** Part Type '74HC1G126GW' ('74HC1G126GW-74HC1G126GW,SMLF,IA') ****
**** Part Type '74LVC1G02GW' ('74LVC1G02GW_SMLF-74LVC1G02GW,IA') ****
**** Part Type '74LVC1G07GV' ('74LVC1G07GV-74LVC1G07GV,SMLF,IA') ****
**** Part Type '74LVC1G126GW' ('74LVC1G126GW_SMLF-74LVC1G126GWA') ****
**** Part Type '9QXL2001BNHGI8' ('9QXL2001BNHGI8-9QXL2001BNHGI8,A') ****
**** Part Type '9SQ440NQQI8' ('9SQ440NQQI8-9SQ440NQQI8,SMLF,IA') ****
**** Part Type 'ADM1086AKSZREEL7' ('ADM1086AKSZREEL7-ADM1086AKSZ-RA') ****
**** Part Type 'ADS1015IDGSR' ('ADS1015IDGSR-ADS1015IDGSR,SMLFA') ****
**** Part Type 'APX80929SAG7' ('APX80929SAG7-APX809-29SAG-7,SMA') ****
**** Part Type 'BAS70057F' ('BAS70057F-BAS70-05-7-F,SMLF,ICA') ****
**** Part Type 'BAT547F' ('BAT547F-BAT547F,SMLF,IC,BC0BATA') ****
**** Part Type 'CONN10_10142708102011LF' ('CONN10_10142708102011LF-CONN10A') ****
**** Part Type 'CONN10_G2100HT0038071' ('CONN10_G2100HT0038071-CONN10_GA') ****
**** Part Type 'CONN24_52SH90245BRD' ('CONN24_52SH90245BRD-CONN24_52SA') ****
**** Part Type 'CONN2_AAABAT029P15' ('CONN2_AAABAT029P15-CONN2_AAA-BA') ****
**** Part Type 'CONN3_210HP1030BR1' ('CONN3_210HP1030BR1-CONN3_210-HA') ****
**** Part Type 'CONN3_HFK1030G000LAF' ('CONN3_HFK1030G000LAF-CONN3_HFKA') ****
**** Part Type 'CONN56_ME2005602311011' ('CONN56_ME2005602311011-CONN56_A') ****
**** Part Type 'CONN7_ABASAT054KA1' ('CONN7_ABASAT054KA1-CONN7_ABA-SA') ****
**** Part Type 'CONN9_2UB3903013101F' ('CONN9_2UB3903013101F-CONN9_2UBA') ****
**** Part Type 'DELTA_L' ('DELTA_L-DELTA-L,THLF,EMPTY,TP24') ****
**** Part Type 'DIODE_TVS' ('DIODE_TVS-SMF14A,SMLF,IC,BCSMFA') ****
**** Part Type 'DUMMY_SYMBOL' ('DUMMY_SYMBOL-BARCODE,MECH,EMPTA') ****
**** Part Type 'DUMMY_SYMBOL' ('DUMMY_SYMBOL-BATTERY_SYMBOL,MEA') ****
**** Part Type 'DUMMY_SYMBOL' ('DUMMY_SYMBOL-EFI BIOS LABEL,MEA') ****
**** Part Type 'DUMMY_SYMBOL' ('DUMMY_SYMBOL-MECHANIC_SYMBOL,MA') ****
**** Part Type 'DUMMY_SYMBOL' ('DUMMY_SYMBOL-PB-E1_SMALL,MECH,A') ****
**** Part Type 'DUMMY_SYMBOL' ('DUMMY_SYMBOL-PCBA_LABEL_15X5,MA') ****
**** Part Type 'DUMMY_SYMBOL' ('DUMMY_SYMBOL-PCB_VENDOR_LOGO_1A') ****
**** Part Type 'DUMMY_SYMBOL' ('DUMMY_SYMBOL-QUANTA_LOGO_7X26,A') ****
**** Part Type 'DUMMY_SYMBOL' ('DUMMY_SYMBOL-WEEE,MECH,EMPTY,DA') ****
**** Part Type 'EMMITSBURG_REV0P9' ('EMMITSBURG_REV0P9-GFNOCPU04302A') ****
**** Part Type 'GTL2014PW' ('GTL2014PW-GTL2014PW,SMLF,IC,ALA') ****
**** Part Type 'HOLE' ('HOLE_TH-EMPTY,DUMMY50') ****
**** Part Type 'HOLE' ('HOLE_TH-EMPTY,HOLE491') ****
**** Part Type 'HOLE' ('HOLE_TH-EMPTY,HOLE1068') ****
**** Part Type 'HOLE' ('HOLE_TH-EMPTY,HOLE1079') ****
**** Part Type 'HOLE' ('HOLE_TH-EMPTY,HOLE1087') ****
**** Part Type 'HOLE' ('HOLE_TH-EMPTY,HOLE1098') ****
**** Part Type 'HOLE' ('HOLE_TH-EMPTY,HOLE1212') ****
**** Part Type 'HOLE' ('HOLE_TH-EMPTY,HOLE1214') ****
**** Part Type 'HOLE' ('HOLE_TH-EMPTY,HOLE1222') ****
**** Part Type 'HOLE' ('HOLE_TH-EMPTY,TMP-Q_HOLE78') ****
**** Part Type 'IDTQS3VH257QG' ('IDTQS3VH257QG_SMLF-IDTQS3VH257A') ****
**** Part Type 'ISL69260IRAZT' ('ISL69260IRAZT-ISL69260IRAZ-T,SA') ****
**** Part Type 'ISL99390FRZTR5935' ('ISL99390FRZTR5935-ISL99390FRZ-A') ****
**** Part Type 'ISL99390FRZTR5935' ('ISL99390FRZTR5935-ISL99390FRZ-B') ****
**** Part Type 'M24128BWDW6TP' ('M24128BWDW6TP-M24128-BWDW6TP,SA') ****
**** Part Type 'MAX11607EUAT' ('MAX11607EUAT-MAX11607EUA+T,SMLA') ****
**** Part Type 'MAX9634FEUKT' ('MAX9634FEUKT-MAX9634FEUK+T,SMLA') ****
**** Part Type 'ME_DUMMY_SYMBOL' ('ME_DUMMY_SYMBOL-PICKUP_SMDC10,A') ****
**** Part Type 'ME_DUMMY_SYMBOL' ('ME_DUMMY_SYMBOL-PICKUP_SMDC20,A') ****
**** Part Type 'MOSFET_NCH_1D3S' ('MOSFET_NCH_1D3S-PSMNR58-30YLH,A') ****
**** Part Type 'MOSFET_NCH_DUAL' ('MOSFET_NCH_DUAL-2N7002KDW,SMLFA') ****
**** Part Type 'MOSFET_N_GSD' ('MOSFET_N_GSD-NX7002AK,SMLF,IC,A') ****
**** Part Type 'MOSFET_N' ('MOSFET_N_SMLF-BSS138K,BSS138K,A') ****
**** Part Type 'MOSFET_N' ('MOSFET_N_SMLF-BSS138K,BSS138K,B') ****
**** Part Type 'MOSFET_PCH_GDS_ESD_PROTECTED' ('MOSFET_PCH_GDS_ESD_PROTECTED-PA') ****
**** Part Type 'MP5981GLUZ' ('MP5981GLUZ-MP5981GLU-Z,SMLF,ICA') ****
**** Part Type 'MPQ8626GDZ' ('MPQ8626GDZ-MPQ8626GD-Z,SMLF,ICA') ****
**** Part Type 'MPQ8633AGLEC807Z' ('MPQ8633AGLEC807Z-MPQ8633AGLE-CA') ****
**** Part Type 'MPQ8633AGLEC807Z' ('MPQ8633AGLEC807Z-MPQ8633AGLE-CB') ****
**** Part Type 'MPQ8633BGLEC838Z' ('MPQ8633BGLEC838Z-MPQ8633BGLE-CA') ****
**** Part Type 'NB695GDZ' ('NB695GDZ-NB695GD-Z,SMLF,IC,AL0A') ****
**** Part Type 'NC7SB3157' ('NC7SB3157_SMLF-NC7SB3157P6X,NCA') ****
**** Part Type 'NC7SZ66M5X' ('NC7SZ66M5X_SMLF-NC7SZ66M5X,NC7A') ****
**** Part Type 'NCP3284MNTXG' ('NCP3284MNTXG-NCP3284MNTXG,SMLFA') ****
**** Part Type 'OSC4_SIT1602AI2233E50000000D' ('OSC4_SIT1602AI2233E50000000D-5A') ****
**** Part Type 'PCA9306DCTR' ('PCA9306DCTR-PCA9306DCTR,SMLF,IA') ****
**** Part Type 'PCA9546APWR' ('PCA9546APWR-PCA9546APWR,SMLF,IA') ****
**** Part Type 'PCA9548APW' ('PCA9548APW-PCA9548APW,SMLF,IC,A') ****
**** Part Type 'PCA9555PW' ('PCA9555PW_SMLF-PCA9555PW,IC,TMA') ****
**** Part Type 'PCA9617ADP' ('PCA9617ADP-PCA9617ADP,SMLF,IC,A') ****
**** Part Type 'PI6CV304LE' ('PI6CV304LE-PI6CV304LE,SMLF,IC,A') ****
**** Part Type 'Q_CAPP' ('Q_CAPP_RDLLF-270UF,16V,20%,OSCA') ****
**** Part Type 'Q_CAPP' ('Q_CAPP_SMLF-100UF,16V,20%,OSCOA') ****
**** Part Type 'Q_CAPP' ('Q_CAPP_SMLF-100UF,16V,20%,POSCA') ****
**** Part Type 'Q_CAPP' ('Q_CAPP_SMLF-220UF,6.3V,20%,ALUA') ****
**** Part Type 'Q_CAPP' ('Q_CAPP_SMLF-330UF,2V,35%,SPCAPA') ****
**** Part Type 'Q_CAPP' ('Q_CAPP_SMLF-470UF,2.5V,20%,EMPA') ****
**** Part Type 'Q_CAPP' ('Q_CAPP_SMLF-470UF,2.5V,20%,SPCA') ****
**** Part Type 'Q_CAPP' ('Q_CAPP_SMLF-470UF,2V,20%,EMPTYA') ****
**** Part Type 'Q_CAPP' ('Q_CAPP_SMLF-470UF,2V,20%,POSCAA') ****
**** Part Type 'Q_CAPP' ('Q_CAPP_THLF-270UF,16V,20%,OSCOA') ****
**** Part Type 'Q_CAPP' ('Q_CAPP_THLF-560UF,2.5V,20%,EMPA') ****
**** Part Type 'Q_CAPP' ('Q_CAPP_THLF-560UF,2.5V,20%,OSCA') ****
**** Part Type 'Q_CAPP' ('Q_CAPP_THLF-560UF,6.3V,20%,EMPA') ****
**** Part Type 'Q_CAPP' ('Q_CAPP_THLF-560UF,6.3V,20%,OSCA') ****
**** Part Type 'Q_CAP' ('Q_CAP_0402-0.01UF,25V,10%,X7R,A') ****
**** Part Type 'Q_CAP' ('Q_CAP_0402-0.022UF,16V,10%,EMPA') ****
**** Part Type 'Q_CAP' ('Q_CAP_0402-0.022UF,16V,10%,X7RA') ****
**** Part Type 'Q_CAP' ('Q_CAP_0402-0.1UF,25V,10%,EMPTYA') ****
**** Part Type 'Q_CAP' ('Q_CAP_0402-0.1UF,25V,10%,X7R,CA') ****
**** Part Type 'Q_CAP' ('Q_CAP_0402-0.22UF,16V,10%,EMPTA') ****
**** Part Type 'Q_CAP' ('Q_CAP_0402-0.22UF,16V,10%,X7R,A') ****
**** Part Type 'Q_CAP' ('Q_CAP_0402-1000PF,50V,5%,EMPTYA') ****
**** Part Type 'Q_CAP' ('Q_CAP_0402-1000PF,50V,5%,X7R,TA') ****
**** Part Type 'Q_CAP' ('Q_CAP_0402-100PF,50V,5%,EMPTY,A') ****
**** Part Type 'Q_CAP' ('Q_CAP_0402-100PF,50V,5%,NPO,CHA') ****
**** Part Type 'Q_CAP' ('Q_CAP_0402-100PF,50V,5%,X7R,CHA') ****
**** Part Type 'Q_CAP' ('Q_CAP_0402-10PF,50V,1%,NPO,TMPA') ****
**** Part Type 'Q_CAP' ('Q_CAP_0402-15PF,50V,5%,C0G,CH0A') ****
**** Part Type 'Q_CAP' ('Q_CAP_0402-1NF,50V,10%,X7R,CH2A') ****
**** Part Type 'Q_CAP' ('Q_CAP_0402-1UF,6.3V,10%,EMPTY,A') ****
**** Part Type 'Q_CAP' ('Q_CAP_0402-27PF  ,50V ,5% ,EMPA') ****
**** Part Type 'Q_CAP' ('Q_CAP_0402-27PF  ,50V ,5% ,NPOA') ****
**** Part Type 'Q_CAP' ('Q_CAP_0402-3300PF,50V,10%,EMPTA') ****
**** Part Type 'Q_CAP' ('Q_CAP_0402-3300PF,50V,10%,X7R,A') ****
**** Part Type 'Q_CAP' ('Q_CAP_0402-4.7UF,6.3V,20%,X6S,A') ****
**** Part Type 'Q_CAP' ('Q_CAP_0402-470PF,50V,10%,X7R,TA') ****
**** Part Type 'Q_CAP' ('Q_CAP_0402-47PF,50V,5%,NPO,TMPA') ****
**** Part Type 'Q_CAP' ('Q_CAP_0402-680PF,50V,10%,X7R,TA') ****
**** Part Type 'Q_CAP' ('Q_CAP_0805-22UF,4V,20%,EMPTY,TA') ****
**** Part Type 'Q_CAP' ('Q_CAP_0805-22UF,4V,20%,X6S,TMPA') ****
**** Part Type 'Q_CAP' ('Q_CAP_0805-47UF,4V,20%,X6S,CH6A') ****
**** Part Type 'Q_CAP' ('Q_CAP_C0201-0.22UF,6.3V,10%,X6A') ****
**** Part Type 'Q_CAP' ('Q_CAP_C0402-0.047UF,25V,10%,X7A') ****
**** Part Type 'Q_CAP' ('Q_CAP_C0402-100NF,50V,10%,EMPTA') ****
**** Part Type 'Q_CAP' ('Q_CAP_C0402-100NF,50V,10%,X7R,A') ****
**** Part Type 'Q_CAP' ('Q_CAP_C0402-10UF,6.3V,20%,X6S,A') ****
**** Part Type 'Q_CAP' ('Q_CAP_C0402-1UF,16V,10%,EMPTY,A') ****
**** Part Type 'Q_CAP' ('Q_CAP_C0402-1UF,16V,10%,X6S,CHA') ****
**** Part Type 'Q_CAP' ('Q_CAP_C0402-1UF,25V,10%,EMPTY,A') ****
**** Part Type 'Q_CAP' ('Q_CAP_C0402-1UF,25V,10%,X6S,CHA') ****
**** Part Type 'Q_CAP' ('Q_CAP_C0402-2.2UF,10V,10%,EMPTA') ****
**** Part Type 'Q_CAP' ('Q_CAP_C0402-2.2UF,10V,10%,X6S,A') ****
**** Part Type 'Q_CAP' ('Q_CAP_C0402-2.2UF,6.3V,20%,EMPA') ****
**** Part Type 'Q_CAP' ('Q_CAP_C0402-2.2UF,6.3V,20%,X6SA') ****
**** Part Type 'Q_CAP' ('Q_CAP_C0402-22UF,4V,20%,X6S,CHA') ****
**** Part Type 'Q_CAP' ('Q_CAP_C0402-3900PF,50V,10%,X7RA') ****
**** Part Type 'Q_CAP' ('Q_CAP_C0402-470PF,50V,5%,NPO,CA') ****
**** Part Type 'Q_CAP' ('Q_CAP_C0603-10UF,4V,20%,EMPTY,A') ****
**** Part Type 'Q_CAP' ('Q_CAP_C0603-10UF,6.3V,20%,X6S,A') ****
**** Part Type 'Q_CAP' ('Q_CAP_C0603-2.2UF,16V,10%,X6S,A') ****
**** Part Type 'Q_CAP' ('Q_CAP_C0603-22UF,4V,20%,X6S,CHA') ****
**** Part Type 'Q_CAP' ('Q_CAP_C0603-22UF,6.3V,20%,X6S,A') ****
**** Part Type 'Q_CAP' ('Q_CAP_C0603-4.7UF,16V,10%,X6S,A') ****
**** Part Type 'Q_CAP' ('Q_CAP_C0603-47UF,2.5V,20%,X6S,A') ****
**** Part Type 'Q_CAP' ('Q_CAP_C0805-100UF,4V,20%,X6S,CA') ****
**** Part Type 'Q_CAP' ('Q_CAP_C0805-10UF,16V,10%,EMPTYA') ****
**** Part Type 'Q_CAP' ('Q_CAP_C0805-10UF,16V,10%,X6S,CA') ****
**** Part Type 'Q_CAP' ('Q_CAP_C0805-10UF,16V,10%,X7R,CA') ****
**** Part Type 'Q_CAP' ('Q_CAP_C0805-10UF,25V,10%,X6S,CA') ****
**** Part Type 'Q_CAP' ('Q_CAP_C0805-22UF,10V,20%,X6S,CA') ****
**** Part Type 'Q_CAP' ('Q_CAP_C0805-22UF,16V,20%,EMPTYA') ****
**** Part Type 'Q_CAP' ('Q_CAP_C0805-22UF,16V,20%,X6S,CA') ****
**** Part Type 'Q_CAP' ('Q_CAP_C0805-22UF,25V,20%,X5R,CA') ****
**** Part Type 'Q_CAP_DIFFBUS' ('Q_CAP_DIFFBUS_C0201-DIFF BUS_0A') ****
**** Part Type 'Q_CAP_DIFFBUS' ('Q_CAP_DIFFBUS_C0201-DIFF BUS_0B') ****
**** Part Type 'Q_CAP_DIFFBUS' ('Q_CAP_DIFFBUS_C0402-DIFF BUS_0A') ****
**** Part Type 'Q_CAP_SATA6G' ('Q_CAP_SATA6G_C0402-SATA6G_0.01A') ****
**** Part Type 'Q_CRYSTAL' ('Q_CRYSTAL_SMLF-32.768KHZ,IC,BGA') ****
**** Part Type 'Q_INDUCTOR4P_12' ('Q_INDUCTOR4P_12-67/320MA,320MAA') ****
**** Part Type 'Q_INDUCTOR4P_14' ('Q_INDUCTOR4P_14-150NH,SMLF,INDA') ****
**** Part Type 'Q_INDUCTOR' ('Q_INDUCTOR_SMLF-1.5UH/53A,IND,A') ****
**** Part Type 'Q_INDUCTOR' ('Q_INDUCTOR_SMLF-100NH/16A,IND,A') ****
**** Part Type 'Q_INDUCTOR' ('Q_INDUCTOR_SMLF-120NH/76A,IND,A') ****
**** Part Type 'Q_INDUCTOR' ('Q_INDUCTOR_SMLF-120NH/94A,IND,A') ****
**** Part Type 'Q_INDUCTOR' ('Q_INDUCTOR_SMLF-130NH/106A,EMPA') ****
**** Part Type 'Q_INDUCTOR' ('Q_INDUCTOR_SMLF-130NH/106A,INDA') ****
**** Part Type 'Q_INDUCTOR' ('Q_INDUCTOR_SMLF-1UH,EMPTY,CV-1A') ****
**** Part Type 'Q_INDUCTOR' ('Q_INDUCTOR_SMLF-1UH,IND,CV-10BA') ****
**** Part Type 'Q_INDUCTOR' ('Q_INDUCTOR_SMLF-3.3UH/10A,IND,A') ****
**** Part Type 'Q_INDUCTOR' ('Q_INDUCTOR_SMLF-300NH/33A,IND,A') ****
**** Part Type 'Q_INDUCTOR' ('Q_INDUCTOR_SMLF-50NH/148A,IND,A') ****
**** Part Type 'Q_INDUCTOR' ('Q_INDUCTOR_SMLF-BLM15AG121SN1DA') ****
**** Part Type 'Q_INDUCTOR' ('Q_INDUCTOR_SMLF-BLM18PG121SN1DA') ****
**** Part Type 'Q_INDUCTOR' ('Q_INDUCTOR_SMLF-BLM18SG331TN1DA') ****
**** Part Type 'Q_INDUCTOR' ('Q_INDUCTOR_SMLF-BLM18SN220TN1DA') ****
**** Part Type 'Q_INDUCTOR' ('Q_INDUCTOR_SMLF-FCM2012KF-601TA') ****
**** Part Type 'Q_LED' ('Q_LED_SMLF-LED_GREEN,19-213/GVA') ****
**** Part Type 'Q_LED' ('Q_LED_SMLF-LED_RED,19-217/R6C-A') ****
**** Part Type 'Q_OSC4P' ('Q_OSC4P_SMLF-25MHZ,OSC,BF62500A') ****
**** Part Type 'Q_RES' ('Q_RES_0402LF -9.53K,1%,1/16W ,A') ****
**** Part Type 'Q_RES' ('Q_RES_0402LF-0,1%,1/16W,CHIP,TA') ****
**** Part Type 'Q_RES' ('Q_RES_0402LF-0,5%,1/16W,CHIP,CA') ****
**** Part Type 'Q_RES' ('Q_RES_0402LF-0,5%,1/16W,EMPTY,A') ****
**** Part Type 'Q_RES' ('Q_RES_0402LF-1,1%,1/16W,CHIP,CA') ****
**** Part Type 'Q_RES' ('Q_RES_0402LF-1.33K,1%,1/16W,CHA') ****
**** Part Type 'Q_RES' ('Q_RES_0402LF-1.5K,1%,1/16W,EMPA') ****
**** Part Type 'Q_RES' ('Q_RES_0402LF-10,1%,1/16W,CHIP,A') ****
**** Part Type 'Q_RES' ('Q_RES_0402LF-100,1%,1/16W,CHIPA') ****
**** Part Type 'Q_RES' ('Q_RES_0402LF-100,1%,1/16W,CHIPB') ****
**** Part Type 'Q_RES' ('Q_RES_0402LF-100,1%,1/16W,EMPTA') ****
**** Part Type 'Q_RES' ('Q_RES_0402LF-100K,1%,1/16W,CHIA') ****
**** Part Type 'Q_RES' ('Q_RES_0402LF-100K,1%,1/16W,EMPA') ****
**** Part Type 'Q_RES' ('Q_RES_0402LF-100K,1%,1/16W,EMPB') ****
**** Part Type 'Q_RES' ('Q_RES_0402LF-100K,5%,1/16W,CHIA') ****
**** Part Type 'Q_RES' ('Q_RES_0402LF-10K,1%,1/16W,CHIPA') ****
**** Part Type 'Q_RES' ('Q_RES_0402LF-10K,1%,1/16W,EMPTA') ****
**** Part Type 'Q_RES' ('Q_RES_0402LF-10K,1%,1/16W,EMPTB') ****
**** Part Type 'Q_RES' ('Q_RES_0402LF-10K,5%,1/16W,CHIPA') ****
**** Part Type 'Q_RES' ('Q_RES_0402LF-10K,5%,1/16W,EMPTA') ****
**** Part Type 'Q_RES' ('Q_RES_0402LF-11.8K,1%,1/16W,CHA') ****
**** Part Type 'Q_RES' ('Q_RES_0402LF-113,1%,1/16W,CHIPA') ****
**** Part Type 'Q_RES' ('Q_RES_0402LF-12.4K,1%,1/16W,CHA') ****
**** Part Type 'Q_RES' ('Q_RES_0402LF-120,1%,1/16W,CHIPA') ****
**** Part Type 'Q_RES' ('Q_RES_0402LF-120K,1%,1/16W,CHIA') ****
**** Part Type 'Q_RES' ('Q_RES_0402LF-127K,1%,1/16W,CHIA') ****
**** Part Type 'Q_RES' ('Q_RES_0402LF-12K,1%,1/16W,EMPTA') ****
**** Part Type 'Q_RES' ('Q_RES_0402LF-15.4K,1%,1/16W,CHA') ****
**** Part Type 'Q_RES' ('Q_RES_0402LF-150,1%,1/16W,CHIPA') ****
**** Part Type 'Q_RES' ('Q_RES_0402LF-150,5%,1/16W,CHIPA') ****
**** Part Type 'Q_RES' ('Q_RES_0402LF-150K,1%,1/16W,CHIA') ****
**** Part Type 'Q_RES' ('Q_RES_0402LF-15K,1%,1/16W,CHIPA') ****
**** Part Type 'Q_RES' ('Q_RES_0402LF-18.2K,0.1%,1/16W,A') ****
**** Part Type 'Q_RES' ('Q_RES_0402LF-18.2K,0.1%,1/16W,B') ****
**** Part Type 'Q_RES' ('Q_RES_0402LF-196K,1%,1/16W,CHIA') ****
**** Part Type 'Q_RES' ('Q_RES_0402LF-1K,0.1%,1/16W,CHIA') ****
**** Part Type 'Q_RES' ('Q_RES_0402LF-1K,1%,1/16W,CHIP,A') ****
**** Part Type 'Q_RES' ('Q_RES_0402LF-1K,1%,1/16W,EMPTYA') ****
**** Part Type 'Q_RES' ('Q_RES_0402LF-1K,5%,1/16W,CHIP,A') ****
**** Part Type 'Q_RES' ('Q_RES_0402LF-1K,5%,1/16W,EMPTYA') ****
**** Part Type 'Q_RES' ('Q_RES_0402LF-2.2,1%,1/16W,CHIPA') ****
**** Part Type 'Q_RES' ('Q_RES_0402LF-2.2,1%,1/16W,EMPTA') ****
**** Part Type 'Q_RES' ('Q_RES_0402LF-2.21K    ,1%  ,1/A') ****
**** Part Type 'Q_RES' ('Q_RES_0402LF-2.2K ,5%,1/16W,CHA') ****
**** Part Type 'Q_RES' ('Q_RES_0402LF-2.2K ,5%,1/16W,EMA') ****
**** Part Type 'Q_RES' ('Q_RES_0402LF-2.49K,1%,1/16W,CHA') ****
**** Part Type 'Q_RES' ('Q_RES_0402LF-2.4K,1%,1/16W,CHIA') ****
**** Part Type 'Q_RES' ('Q_RES_0402LF-200,1%,1/16W,CHIPA') ****
**** Part Type 'Q_RES' ('Q_RES_0402LF-200,1%,1/16W,EMPTA') ****
**** Part Type 'Q_RES' ('Q_RES_0402LF-200K,1%,1/16W,CHIA') ****
**** Part Type 'Q_RES' ('Q_RES_0402LF-20K,1%,1/16W,CHIPA') ****
**** Part Type 'Q_RES' ('Q_RES_0402LF-20K,5%,1/16W,CHIPA') ****
**** Part Type 'Q_RES' ('Q_RES_0402LF-20K,5%,1/16W,EMPTA') ****
**** Part Type 'Q_RES' ('Q_RES_0402LF-21.5K,1%,1/16W,CHA') ****
**** Part Type 'Q_RES' ('Q_RES_0402LF-22,1%,1/16W,CHIP,A') ****
**** Part Type 'Q_RES' ('Q_RES_0402LF-23.2K,1%,1/16W,CHA') ****
**** Part Type 'Q_RES' ('Q_RES_0402LF-240,1%,1/16W,CHIPA') ****
**** Part Type 'Q_RES' ('Q_RES_0402LF-240,1%,1/16W,EMPTA') ****
**** Part Type 'Q_RES' ('Q_RES_0402LF-249,1%,1/16W,CHIPA') ****
**** Part Type 'Q_RES' ('Q_RES_0402LF-26.1K,1%,1/16W,CHA') ****
**** Part Type 'Q_RES' ('Q_RES_0402LF-26.1K,1%,1/16W,EMA') ****
**** Part Type 'Q_RES' ('Q_RES_0402LF-27.4,1%,1/16W,CHIA') ****
**** Part Type 'Q_RES' ('Q_RES_0402LF-28K,1%,1/16W,EMPTA') ****
**** Part Type 'Q_RES' ('Q_RES_0402LF-2K,1%,1/16W,CHIP,A') ****
**** Part Type 'Q_RES' ('Q_RES_0402LF-2K,1%,1/16W,EMPTYA') ****
**** Part Type 'Q_RES' ('Q_RES_0402LF-3.3,1%,1/16W,CHIPA') ****
**** Part Type 'Q_RES' ('Q_RES_0402LF-3.3,1%,1/16W,EMPTA') ****
**** Part Type 'Q_RES' ('Q_RES_0402LF-30.1K    ,1%  ,1/A') ****
**** Part Type 'Q_RES' ('Q_RES_0402LF-301,1%,1/16W,CHIPA') ****
**** Part Type 'Q_RES' ('Q_RES_0402LF-31.6K,1%,1/16W,CHA') ****
**** Part Type 'Q_RES' ('Q_RES_0402LF-33,5%,1/16W,CHIP,A') ****
**** Part Type 'Q_RES' ('Q_RES_0402LF-33.2,1%,1/16W,CHIA') ****
**** Part Type 'Q_RES' ('Q_RES_0402LF-332,1%,1/16W,CHIPA') ****
**** Part Type 'Q_RES' ('Q_RES_0402LF-33K    ,1%  ,1/16A') ****
**** Part Type 'Q_RES' ('Q_RES_0402LF-35.7K,1%,1/16W,CHA') ****
**** Part Type 'Q_RES' ('Q_RES_0402LF-36K,1%,1/16W,CHIPA') ****
**** Part Type 'Q_RES' ('Q_RES_0402LF-36K,1%,1/16W,EMPTA') ****
**** Part Type 'Q_RES' ('Q_RES_0402LF-4.32K,1%,1/16W,CHA') ****
**** Part Type 'Q_RES' ('Q_RES_0402LF-4.64K,0.5%,1/16W,A') ****
**** Part Type 'Q_RES' ('Q_RES_0402LF-4.7,1%,1/16W,CHIPA') ****
**** Part Type 'Q_RES' ('Q_RES_0402LF-4.75K,1%,1/16W,CHA') ****
**** Part Type 'Q_RES' ('Q_RES_0402LF-4.75K,1%,1/16W,EMA') ****
**** Part Type 'Q_RES' ('Q_RES_0402LF-4.7K,1%,1/16W,CHIA') ****
**** Part Type 'Q_RES' ('Q_RES_0402LF-4.7K,1%,1/16W,EMPA') ****
**** Part Type 'Q_RES' ('Q_RES_0402LF-4.7K,5%,1/16W,CHIA') ****
**** Part Type 'Q_RES' ('Q_RES_0402LF-4.7K,5%,1/16W,EMPA') ****
**** Part Type 'Q_RES' ('Q_RES_0402LF-412,1%,1/16W,CHIPA') ****
**** Part Type 'Q_RES' ('Q_RES_0402LF-49.9     ,1%  ,1/A') ****
**** Part Type 'Q_RES' ('Q_RES_0402LF-49.9     ,1%  ,1/B') ****
**** Part Type 'Q_RES' ('Q_RES_0402LF-499,1%,1/16W,CHIPA') ****
**** Part Type 'Q_RES' ('Q_RES_0402LF-5.1,5%,1/16W,CHIPA') ****
**** Part Type 'Q_RES' ('Q_RES_0402LF-5.11K,1%,1/16W,CHA') ****
**** Part Type 'Q_RES' ('Q_RES_0402LF-5.23K,1%,1/16W,CHA') ****
**** Part Type 'Q_RES' ('Q_RES_0402LF-510K,5%,1/16W,CHIA') ****
**** Part Type 'Q_RES' ('Q_RES_0402LF-54.9K,1%,1/16W,CHA') ****
**** Part Type 'Q_RES' ('Q_RES_0402LF-562,1%,1/16W,CHIPA') ****
**** Part Type 'Q_RES' ('Q_RES_0402LF-576,1%,1/16W,CHIPA') ****
**** Part Type 'Q_RES' ('Q_RES_0402LF-6.19K,1%,1/16W,CHA') ****
**** Part Type 'Q_RES' ('Q_RES_0402LF-6.81K,1%,1/16W,CHA') ****
**** Part Type 'Q_RES' ('Q_RES_0402LF-60.4,1%,1/16W,CHIA') ****
**** Part Type 'Q_RES' ('Q_RES_0402LF-60.4K,1%,1/16W,CHA') ****
**** Part Type 'Q_RES' ('Q_RES_0402LF-7.32K,1%,1/16W,CHA') ****
**** Part Type 'Q_RES' ('Q_RES_0402LF-7.5K,1%,1/16W,CHIA') ****
**** Part Type 'Q_RES' ('Q_RES_0402LF-75,1%,1/16W,CHIP,A') ****
**** Part Type 'Q_RES' ('Q_RES_0402LF-75,1%,1/16W,EMPTYA') ****
**** Part Type 'Q_RES' ('Q_RES_0402LF-750,1%,1/16W,CHIPA') ****
**** Part Type 'Q_RES' ('Q_RES_0402LF-75K,1%,1/16W,CHIPA') ****
**** Part Type 'Q_RES' ('Q_RES_0402LF-8.25K,1%,1/16W,CHA') ****
**** Part Type 'Q_RES' ('Q_RES_0402LF-8.87K,1%,1/16W,EMA') ****
**** Part Type 'Q_RES' ('Q_RES_0402LF-84.5K,1%,1/16W,CHA') ****
**** Part Type 'Q_RES' ('Q_RES_0402LF-86.6K,1%,1/16W,CHA') ****
**** Part Type 'Q_RES' ('Q_RES_0402LF-9.09K,1%,1/16W,CHA') ****
**** Part Type 'Q_RES' ('Q_RES_0402LF-9.31K,1%,1/16W,CHA') ****
**** Part Type 'Q_RES' ('Q_RES_0603LF-1,1%,1/10W,CHIP,CA') ****
**** Part Type 'Q_RES' ('Q_RES_0603LF-10M,1%,1/10W,CHIPA') ****
**** Part Type 'Q_RES' ('Q_RES_0603LF-2.2,1%,1/10W,CHIPA') ****
**** Part Type 'Q_RES' ('Q_RES_0603LF-200K,0.1%,1/10W,EA') ****
**** Part Type 'Q_RES' ('Q_RES_0805LF-0,5%,1/8W,CHIP,CSA') ****
**** Part Type 'Q_RES' ('Q_RES_0805LF-0,5%,1/8W,EMPTY,CA') ****
**** Part Type 'Q_RES' ('Q_RES_1206LF-0,,1/2W,CHIP,CS00A') ****
**** Part Type 'Q_RES' ('Q_RES_1206LF-0,,1/2W,EMPTY,CS0A') ****
**** Part Type 'Q_RES' ('Q_RES_1206LF-0,5%,1/4W,CHIP,CSA') ****
**** Part Type 'Q_RES' ('Q_RES_1206LF-0,5%,1/4W,EMPTY,CA') ****
**** Part Type 'Q_RES_4P_12' ('Q_RES_4P_12-0.001,1%,3W,SMLF,CA') ****
**** Part Type 'Q_RES' ('Q_RES_R0402LF-887,1%,1/16W,CHIA') ****
**** Part Type 'Q_SHORT' ('Q_SHORT_SM-EMPTY,SHORT6') ****
**** Part Type 'Q_XTAL_4P_13BI_24GND' ('Q_XTAL_4P_13BI_24GND-25MHZ,SMLA') ****
**** Part Type 'Q_XTAL_4P_13' ('Q_XTAL_4P_13_SMLF-25MHZ,IC,BG6A') ****
**** Part Type 'RAA2213404GNPHB0' ('RAA2213404GNPHB0-RAA2213404GNPA') ****
**** Part Type 'RAA229126GNPHA0' ('RAA229126GNPHA0-RAA229126GNP#HA') ****
**** Part Type 'RT9818C44GV' ('RT9818C44GV-RT9818C-44GV,SMLF,A') ****
**** Part Type 'S9S_MB_2U' ('S9S_MB_2U') ****

PART CROSS REFERENCE (forward interface)

CONN2_AAABAT029P15  I63  BT1    [CONN2_AAABAT029P15-CONN2_AAA-BA]
    1  P3V_BAT            1  @S9S_MB_2U_LIB.S9S_MB_2U(SCH_1):P3V_BAT
    2  GND                2  @S9S_MB_2U_LIB.S9S_MB_2U(SCH_1):GND

Q_CAP  I15  C1     [Q_CAP_C0402-10UF,6.3V,20%,X6S,A]
    1  P3V3_AUX           A  @S9S_MB_2U_LIB.S9S_MB_2U(SCH_1):P3V3_AUX
    2  GND                B  @S9S_MB_2U_LIB.S9S_MB_2U(SCH_1):GND

Q_CAP  I192  C2     [Q_CAP_C0402-2.2UF,6.3V,20%,X6SA]
    1  P3V3_AUX           A  @S9S_MB_2U_LIB.S9S_MB_2U(SCH_1):P3V3_AUX
    2  GND                B  @S9S_MB_2U_LIB.S9S_MB_2U(SCH_1):GND

Q_CAP  I188  C3     [Q_CAP_C0805-10UF,16V,10%,X7R,CA]
    1  P12V_S3_AUX_CPU0_NVDIMM      A  @S9S_MB_2U_LIB.S9S_MB_2U(SCH_1):P12V_S3_AUX_CPU0_NVDIMM
    2  GND                B  @S9S_MB_2U_LIB.S9S_MB_2U(SCH_1):GND

Q_CAP  I190  C4     [Q_CAP_C0805-10UF,16V,10%,X7R,CA]
    1  P12V_S3_AUX_CPU0_NVDIMM      A  @S9S_MB_2U_LIB.S9S_MB_2U(SCH_1):P12V_S3_AUX_CPU0_NVDIMM
    2  GND                B  @S9S_MB_2U_LIB.S9S_MB_2U(SCH_1):GND

Q_CAP  I120  C5     [Q_CAP_C0402-2.2UF,6.3V,20%,X6SA]
    1  P3V3_AUX           A  @S9S_MB_2U_LIB.S9S_MB_2U(SCH_1):P3V3_AUX
    2  GND                B  @S9S_MB_2U_LIB.S9S_MB_2U(SCH_1):GND

Q_CAP  I122  C6     [Q_CAP_C0805-10UF,16V,10%,X7R,CA]
    1  P12V_S3_AUX_CPU0_NVDIMM      A  @S9S_MB_2U_LIB.S9S_MB_2U(SCH_1):P12V_S3_AUX_CPU0_NVDIMM
    2  GND                B  @S9S_MB_2U_LIB.S9S_MB_2U(SCH_1):GND

Q_CAP  I144  C7     [Q_CAP_C0805-10UF,16V,10%,X7R,CA]
    1  P12V_S3_AUX_CPU0_NVDIMM      A  @S9S_MB_2U_LIB.S9S_MB_2U(SCH_1):P12V_S3_AUX_CPU0_NVDIMM
    2  GND                B  @S9S_MB_2U_LIB.S9S_MB_2U(SCH_1):GND

Q_CAP  I121  C8     [Q_CAP_C0402-2.2UF,6.3V,20%,X6SA]
    1  P3V3_AUX           A  @S9S_MB_2U_LIB.S9S_MB_2U(SCH_1):P3V3_AUX
    2  GND                B  @S9S_MB_2U_LIB.S9S_MB_2U(SCH_1):GND

Q_CAP  I122  C9     [Q_CAP_C0805-10UF,16V,10%,X7R,CA]
    1  P12V_S3_AUX_CPU0_NVDIMM      A  @S9S_MB_2U_LIB.S9S_MB_2U(SCH_1):P12V_S3_AUX_CPU0_NVDIMM
    2  GND                B  @S9S_MB_2U_LIB.S9S_MB_2U(SCH_1):GND

Q_CAP  I144  C10    [Q_CAP_C0805-10UF,16V,10%,X7R,CA]
    1  P12V_S3_AUX_CPU0_NVDIMM      A  @S9S_MB_2U_LIB.S9S_MB_2U(SCH_1):P12V_S3_AUX_CPU0_NVDIMM
    2  GND                B  @S9S_MB_2U_LIB.S9S_MB_2U(SCH_1):GND

Q_CAP  I121  C11    [Q_CAP_C0402-2.2UF,6.3V,20%,X6SA]
    1  P3V3_AUX           A  @S9S_MB_2U_LIB.S9S_MB_2U(SCH_1):P3V3_AUX
    2  GND                B  @S9S_MB_2U_LIB.S9S_MB_2U(SCH_1):GND

Q_CAP  I125  C12    [Q_CAP_C0805-10UF,16V,10%,X7R,CA]
    1  P12V_S3_AUX_CPU0_NVDIMM      A  @S9S_MB_2U_LIB.S9S_MB_2U(SCH_1):P12V_S3_AUX_CPU0_NVDIMM
    2  GND                B  @S9S_MB_2U_LIB.S9S_MB_2U(SCH_1):GND

Q_CAP  I127  C13    [Q_CAP_C0805-10UF,16V,10%,X7R,CA]
    1  P12V_S3_AUX_CPU0_NVDIMM      A  @S9S_MB_2U_LIB.S9S_MB_2U(SCH_1):P12V_S3_AUX_CPU0_NVDIMM
    2  GND                B  @S9S_MB_2U_LIB.S9S_MB_2U(SCH_1):GND

Q_CAP  I120  C14    [Q_CAP_C0402-2.2UF,6.3V,20%,X6SA]
    1  P3V3_AUX           A  @S9S_MB_2U_LIB.S9S_MB_2U(SCH_1):P3V3_AUX
    2  GND                B  @S9S_MB_2U_LIB.S9S_MB_2U(SCH_1):GND

Q_CAP  I121  C15    [Q_CAP_C0805-10UF,16V,10%,X7R,CA]
    1  P12V_S3_AUX_CPU0_NVDIMM      A  @S9S_MB_2U_LIB.S9S_MB_2U(SCH_1):P12V_S3_AUX_CPU0_NVDIMM
    2  GND                B  @S9S_MB_2U_LIB.S9S_MB_2U(SCH_1):GND

Q_CAP  I123  C16    [Q_CAP_C0805-10UF,16V,10%,X7R,CA]
    1  P12V_S3_AUX_CPU0_NVDIMM      A  @S9S_MB_2U_LIB.S9S_MB_2U(SCH_1):P12V_S3_AUX_CPU0_NVDIMM
    2  GND                B  @S9S_MB_2U_LIB.S9S_MB_2U(SCH_1):GND

Q_CAP  I120  C17    [Q_CAP_C0402-2.2UF,6.3V,20%,X6SA]
    1  P3V3_AUX           A  @S9S_MB_2U_LIB.S9S_MB_2U(SCH_1):P3V3_AUX
    2  GND                B  @S9S_MB_2U_LIB.S9S_MB_2U(SCH_1):GND

Q_CAP  I124  C18    [Q_CAP_C0805-10UF,16V,10%,X7R,CA]
    1  P12V_S3_AUX_CPU0_NVDIMM      A  @S9S_MB_2U_LIB.S9S_MB_2U(SCH_1):P12V_S3_AUX_CPU0_NVDIMM
    2  GND                B  @S9S_MB_2U_LIB.S9S_MB_2U(SCH_1):GND

Q_CAP  I127  C19    [Q_CAP_C0805-10UF,16V,10%,X7R,CA]
    1  P12V_S3_AUX_CPU0_NVDIMM      A  @S9S_MB_2U_LIB.S9S_MB_2U(SCH_1):P12V_S3_AUX_CPU0_NVDIMM
    2  GND                B  @S9S_MB_2U_LIB.S9S_MB_2U(SCH_1):GND

Q_CAP  I123  C20    [Q_CAP_C0402-2.2UF,6.3V,20%,X6SA]
    1  P3V3_AUX           A  @S9S_MB_2U_LIB.S9S_MB_2U(SCH_1):P3V3_AUX
    2  GND                B  @S9S_MB_2U_LIB.S9S_MB_2U(SCH_1):GND

Q_CAP  I126  C21    [Q_CAP_C0805-10UF,16V,10%,X7R,CA]
    1  P12V_S3_AUX_CPU0_NVDIMM      A  @S9S_MB_2U_LIB.S9S_MB_2U(SCH_1):P12V_S3_AUX_CPU0_NVDIMM
    2  GND                B  @S9S_MB_2U_LIB.S9S_MB_2U(SCH_1):GND

Q_CAP  I166  C22    [Q_CAP_C0805-10UF,16V,10%,X7R,CA]
    1  P12V_S3_AUX_CPU0_NVDIMM      A  @S9S_MB_2U_LIB.S9S_MB_2U(SCH_1):P12V_S3_AUX_CPU0_NVDIMM
    2  GND                B  @S9S_MB_2U_LIB.S9S_MB_2U(SCH_1):GND

Q_CAP  I121  C23    [Q_CAP_C0402-2.2UF,6.3V,20%,X6SA]
    1  P3V3_AUX           A  @S9S_MB_2U_LIB.S9S_MB_2U(SCH_1):P3V3_AUX
    2  GND                B  @S9S_MB_2U_LIB.S9S_MB_2U(SCH_1):GND

Q_CAP  I125  C24    [Q_CAP_C0805-10UF,16V,10%,X7R,CA]
    1  P12V_S3_AUX_CPU0_NVDIMM      A  @S9S_MB_2U_LIB.S9S_MB_2U(SCH_1):P12V_S3_AUX_CPU0_NVDIMM
    2  GND                B  @S9S_MB_2U_LIB.S9S_MB_2U(SCH_1):GND

Q_CAP  I127  C25    [Q_CAP_C0805-22UF,16V,20%,X6S,CA]
    1  P12V_S3_AUX_CPU0_NVDIMM      A  @S9S_MB_2U_LIB.S9S_MB_2U(SCH_1):P12V_S3_AUX_CPU0_NVDIMM
    2  GND                B  @S9S_MB_2U_LIB.S9S_MB_2U(SCH_1):GND

Q_CAP  I122  C26    [Q_CAP_C0402-2.2UF,6.3V,20%,X6SA]
    1  P3V3_AUX           A  @S9S_MB_2U_LIB.S9S_MB_2U(SCH_1):P3V3_AUX
    2  GND                B  @S9S_MB_2U_LIB.S9S_MB_2U(SCH_1):GND

Q_CAP  I123  C27    [Q_CAP_C0805-10UF,16V,10%,X7R,CA]
    1  P12V_S3_AUX_CPU0_NVDIMM      A  @S9S_MB_2U_LIB.S9S_MB_2U(SCH_1):P12V_S3_AUX_CPU0_NVDIMM
    2  GND                B  @S9S_MB_2U_LIB.S9S_MB_2U(SCH_1):GND

Q_CAP  I145  C28    [Q_CAP_C0805-10UF,16V,10%,X7R,CA]
    1  P12V_S3_AUX_CPU0_NVDIMM      A  @S9S_MB_2U_LIB.S9S_MB_2U(SCH_1):P12V_S3_AUX_CPU0_NVDIMM
    2  GND                B  @S9S_MB_2U_LIB.S9S_MB_2U(SCH_1):GND

Q_CAP  I123  C29    [Q_CAP_C0402-2.2UF,6.3V,20%,X6SA]
    1  P3V3_AUX           A  @S9S_MB_2U_LIB.S9S_MB_2U(SCH_1):P3V3_AUX
    2  GND                B  @S9S_MB_2U_LIB.S9S_MB_2U(SCH_1):GND

Q_CAP  I124  C30    [Q_CAP_C0805-10UF,16V,10%,X7R,CA]
    1  P12V_S3_AUX_CPU0_NVDIMM      A  @S9S_MB_2U_LIB.S9S_MB_2U(SCH_1):P12V_S3_AUX_CPU0_NVDIMM
    2  GND                B  @S9S_MB_2U_LIB.S9S_MB_2U(SCH_1):GND

Q_CAP  I146  C31    [Q_CAP_C0805-10UF,16V,10%,X7R,CA]
    1  P12V_S3_AUX_CPU0_NVDIMM      A  @S9S_MB_2U_LIB.S9S_MB_2U(SCH_1):P12V_S3_AUX_CPU0_NVDIMM
    2  GND                B  @S9S_MB_2U_LIB.S9S_MB_2U(SCH_1):GND

Q_CAP  I122  C32    [Q_CAP_C0402-2.2UF,6.3V,20%,X6SA]
    1  P3V3_AUX           A  @S9S_MB_2U_LIB.S9S_MB_2U(SCH_1):P3V3_AUX
    2  GND                B  @S9S_MB_2U_LIB.S9S_MB_2U(SCH_1):GND

Q_CAP  I127  C33    [Q_CAP_C0805-10UF,16V,10%,X7R,CA]
    1  P12V_S3_AUX_CPU0_NVDIMM      A  @S9S_MB_2U_LIB.S9S_MB_2U(SCH_1):P12V_S3_AUX_CPU0_NVDIMM
    2  GND                B  @S9S_MB_2U_LIB.S9S_MB_2U(SCH_1):GND

Q_CAP  I130  C34    [Q_CAP_C0805-10UF,16V,10%,X7R,CA]
    1  P12V_S3_AUX_CPU0_NVDIMM      A  @S9S_MB_2U_LIB.S9S_MB_2U(SCH_1):P12V_S3_AUX_CPU0_NVDIMM
    2  GND                B  @S9S_MB_2U_LIB.S9S_MB_2U(SCH_1):GND

Q_CAP  I122  C35    [Q_CAP_C0402-2.2UF,6.3V,20%,X6SA]
    1  P3V3_AUX           A  @S9S_MB_2U_LIB.S9S_MB_2U(SCH_1):P3V3_AUX
    2  GND                B  @S9S_MB_2U_LIB.S9S_MB_2U(SCH_1):GND

Q_CAP  I126  C36    [Q_CAP_C0805-10UF,16V,10%,X7R,CA]
    1  P12V_S3_AUX_CPU0_NVDIMM      A  @S9S_MB_2U_LIB.S9S_MB_2U(SCH_1):P12V_S3_AUX_CPU0_NVDIMM
    2  GND                B  @S9S_MB_2U_LIB.S9S_MB_2U(SCH_1):GND

Q_CAP  I128  C37    [Q_CAP_C0805-10UF,16V,10%,X7R,CA]
    1  P12V_S3_AUX_CPU0_NVDIMM      A  @S9S_MB_2U_LIB.S9S_MB_2U(SCH_1):P12V_S3_AUX_CPU0_NVDIMM
    2  GND                B  @S9S_MB_2U_LIB.S9S_MB_2U(SCH_1):GND

Q_CAP  I123  C38    [Q_CAP_C0402-2.2UF,6.3V,20%,X6SA]
    1  P3V3_AUX           A  @S9S_MB_2U_LIB.S9S_MB_2U(SCH_1):P3V3_AUX
    2  GND                B  @S9S_MB_2U_LIB.S9S_MB_2U(SCH_1):GND

Q_CAP  I125  C39    [Q_CAP_C0805-10UF,16V,10%,X7R,CA]
    1  P12V_S3_AUX_CPU0_NVDIMM      A  @S9S_MB_2U_LIB.S9S_MB_2U(SCH_1):P12V_S3_AUX_CPU0_NVDIMM
    2  GND                B  @S9S_MB_2U_LIB.S9S_MB_2U(SCH_1):GND

Q_CAP  I162  C40    [Q_CAP_C0805-10UF,16V,10%,X7R,CA]
    1  P12V_S3_AUX_CPU0_NVDIMM      A  @S9S_MB_2U_LIB.S9S_MB_2U(SCH_1):P12V_S3_AUX_CPU0_NVDIMM
    2  GND                B  @S9S_MB_2U_LIB.S9S_MB_2U(SCH_1):GND

Q_CAP  I121  C41    [Q_CAP_C0402-2.2UF,6.3V,20%,X6SA]
    1  P3V3_AUX           A  @S9S_MB_2U_LIB.S9S_MB_2U(SCH_1):P3V3_AUX
    2  GND                B  @S9S_MB_2U_LIB.S9S_MB_2U(SCH_1):GND

Q_CAP  I125  C42    [Q_CAP_C0805-10UF,16V,10%,X7R,CA]
    1  P12V_S3_AUX_CPU0_NVDIMM      A  @S9S_MB_2U_LIB.S9S_MB_2U(SCH_1):P12V_S3_AUX_CPU0_NVDIMM
    2  GND                B  @S9S_MB_2U_LIB.S9S_MB_2U(SCH_1):GND

Q_CAP  I128  C43    [Q_CAP_C0805-10UF,16V,10%,X7R,CA]
    1  P12V_S3_AUX_CPU0_NVDIMM      A  @S9S_MB_2U_LIB.S9S_MB_2U(SCH_1):P12V_S3_AUX_CPU0_NVDIMM
    2  GND                B  @S9S_MB_2U_LIB.S9S_MB_2U(SCH_1):GND

Q_CAP  I121  C44    [Q_CAP_C0402-2.2UF,6.3V,20%,X6SA]
    1  P3V3_AUX           A  @S9S_MB_2U_LIB.S9S_MB_2U(SCH_1):P3V3_AUX
    2  GND                B  @S9S_MB_2U_LIB.S9S_MB_2U(SCH_1):GND

Q_CAP  I125  C45    [Q_CAP_C0805-10UF,16V,10%,X7R,CA]
    1  P12V_S3_AUX_CPU0_NVDIMM      A  @S9S_MB_2U_LIB.S9S_MB_2U(SCH_1):P12V_S3_AUX_CPU0_NVDIMM
    2  GND                B  @S9S_MB_2U_LIB.S9S_MB_2U(SCH_1):GND

Q_CAP  I127  C46    [Q_CAP_C0805-10UF,16V,10%,X7R,CA]
    1  P12V_S3_AUX_CPU0_NVDIMM      A  @S9S_MB_2U_LIB.S9S_MB_2U(SCH_1):P12V_S3_AUX_CPU0_NVDIMM
    2  GND                B  @S9S_MB_2U_LIB.S9S_MB_2U(SCH_1):GND

Q_CAP  I56  C47    [Q_CAP_C0402-2.2UF,6.3V,20%,X6SA]
    1  P3V3_AUX           A  @S9S_MB_2U_LIB.S9S_MB_2U(SCH_1):P3V3_AUX
    2  GND                B  @S9S_MB_2U_LIB.S9S_MB_2U(SCH_1):GND

Q_CAP  I59  C48    [Q_CAP_C0805-10UF,16V,10%,X7R,CA]
    1  P12V_S3_AUX_CPU0_NVDIMM      A  @S9S_MB_2U_LIB.S9S_MB_2U(SCH_1):P12V_S3_AUX_CPU0_NVDIMM
    2  GND                B  @S9S_MB_2U_LIB.S9S_MB_2U(SCH_1):GND

Q_CAP  I62  C49    [Q_CAP_C0805-10UF,16V,10%,X7R,CA]
    1  P12V_S3_AUX_CPU0_NVDIMM      A  @S9S_MB_2U_LIB.S9S_MB_2U(SCH_1):P12V_S3_AUX_CPU0_NVDIMM
    2  GND                B  @S9S_MB_2U_LIB.S9S_MB_2U(SCH_1):GND

Q_CAP  I122  C50    [Q_CAP_C0402-2.2UF,6.3V,20%,X6SA]
    1  P3V3_AUX           A  @S9S_MB_2U_LIB.S9S_MB_2U(SCH_1):P3V3_AUX
    2  GND                B  @S9S_MB_2U_LIB.S9S_MB_2U(SCH_1):GND

Q_CAP  I123  C51    [Q_CAP_C0805-10UF,16V,10%,X7R,CA]
    1  P12V_S3_AUX_CPU1_NVDIMM      A  @S9S_MB_2U_LIB.S9S_MB_2U(SCH_1):P12V_S3_AUX_CPU1_NVDIMM
    2  GND                B  @S9S_MB_2U_LIB.S9S_MB_2U(SCH_1):GND

Q_CAP  I145  C52    [Q_CAP_C0805-10UF,16V,10%,X7R,CA]
    1  P12V_S3_AUX_CPU1_NVDIMM      A  @S9S_MB_2U_LIB.S9S_MB_2U(SCH_1):P12V_S3_AUX_CPU1_NVDIMM
    2  GND                B  @S9S_MB_2U_LIB.S9S_MB_2U(SCH_1):GND

Q_CAP  I122  C53    [Q_CAP_C0402-2.2UF,6.3V,20%,X6SA]
    1  P3V3_AUX           A  @S9S_MB_2U_LIB.S9S_MB_2U(SCH_1):P3V3_AUX
    2  GND                B  @S9S_MB_2U_LIB.S9S_MB_2U(SCH_1):GND

Q_CAP  I126  C54    [Q_CAP_C0805-10UF,16V,10%,X7R,CA]
    1  P12V_S3_AUX_CPU1_NVDIMM      A  @S9S_MB_2U_LIB.S9S_MB_2U(SCH_1):P12V_S3_AUX_CPU1_NVDIMM
    2  GND                B  @S9S_MB_2U_LIB.S9S_MB_2U(SCH_1):GND

Q_CAP  I128  C55    [Q_CAP_C0805-10UF,16V,10%,X7R,CA]
    1  P12V_S3_AUX_CPU1_NVDIMM      A  @S9S_MB_2U_LIB.S9S_MB_2U(SCH_1):P12V_S3_AUX_CPU1_NVDIMM
    2  GND                B  @S9S_MB_2U_LIB.S9S_MB_2U(SCH_1):GND

Q_CAP  I121  C56    [Q_CAP_C0402-2.2UF,6.3V,20%,X6SA]
    1  P3V3_AUX           A  @S9S_MB_2U_LIB.S9S_MB_2U(SCH_1):P3V3_AUX
    2  GND                B  @S9S_MB_2U_LIB.S9S_MB_2U(SCH_1):GND

Q_CAP  I122  C57    [Q_CAP_C0805-10UF,16V,10%,X7R,CA]
    1  P12V_S3_AUX_CPU1_NVDIMM      A  @S9S_MB_2U_LIB.S9S_MB_2U(SCH_1):P12V_S3_AUX_CPU1_NVDIMM
    2  GND                B  @S9S_MB_2U_LIB.S9S_MB_2U(SCH_1):GND

Q_CAP  I124  C58    [Q_CAP_C0805-10UF,16V,10%,X7R,CA]
    1  P12V_S3_AUX_CPU1_NVDIMM      A  @S9S_MB_2U_LIB.S9S_MB_2U(SCH_1):P12V_S3_AUX_CPU1_NVDIMM
    2  GND                B  @S9S_MB_2U_LIB.S9S_MB_2U(SCH_1):GND

Q_CAP  I121  C59    [Q_CAP_C0402-2.2UF,6.3V,20%,X6SA]
    1  P3V3_AUX           A  @S9S_MB_2U_LIB.S9S_MB_2U(SCH_1):P3V3_AUX
    2  GND                B  @S9S_MB_2U_LIB.S9S_MB_2U(SCH_1):GND

Q_CAP  I125  C60    [Q_CAP_C0805-10UF,16V,10%,X7R,CA]
    1  P12V_S3_AUX_CPU1_NVDIMM      A  @S9S_MB_2U_LIB.S9S_MB_2U(SCH_1):P12V_S3_AUX_CPU1_NVDIMM
    2  GND                B  @S9S_MB_2U_LIB.S9S_MB_2U(SCH_1):GND

Q_CAP  I127  C61    [Q_CAP_C0805-10UF,16V,10%,X7R,CA]
    1  P12V_S3_AUX_CPU1_NVDIMM      A  @S9S_MB_2U_LIB.S9S_MB_2U(SCH_1):P12V_S3_AUX_CPU1_NVDIMM
    2  GND                B  @S9S_MB_2U_LIB.S9S_MB_2U(SCH_1):GND

Q_CAP  I124  C62    [Q_CAP_C0402-2.2UF,6.3V,20%,X6SA]
    1  P3V3_AUX           A  @S9S_MB_2U_LIB.S9S_MB_2U(SCH_1):P3V3_AUX
    2  GND                B  @S9S_MB_2U_LIB.S9S_MB_2U(SCH_1):GND

Q_CAP  I127  C63    [Q_CAP_C0805-10UF,16V,10%,X7R,CA]
    1  P12V_S3_AUX_CPU1_NVDIMM      A  @S9S_MB_2U_LIB.S9S_MB_2U(SCH_1):P12V_S3_AUX_CPU1_NVDIMM
    2  GND                B  @S9S_MB_2U_LIB.S9S_MB_2U(SCH_1):GND

Q_CAP  I167  C64    [Q_CAP_C0805-10UF,16V,10%,X7R,CA]
    1  P12V_S3_AUX_CPU1_NVDIMM      A  @S9S_MB_2U_LIB.S9S_MB_2U(SCH_1):P12V_S3_AUX_CPU1_NVDIMM
    2  GND                B  @S9S_MB_2U_LIB.S9S_MB_2U(SCH_1):GND

Q_CAP  I122  C65    [Q_CAP_C0402-2.2UF,6.3V,20%,X6SA]
    1  P3V3_AUX           A  @S9S_MB_2U_LIB.S9S_MB_2U(SCH_1):P3V3_AUX
    2  GND                B  @S9S_MB_2U_LIB.S9S_MB_2U(SCH_1):GND

Q_CAP  I126  C66    [Q_CAP_C0805-10UF,16V,10%,X7R,CA]
    1  P12V_S3_AUX_CPU1_NVDIMM      A  @S9S_MB_2U_LIB.S9S_MB_2U(SCH_1):P12V_S3_AUX_CPU1_NVDIMM
    2  GND                B  @S9S_MB_2U_LIB.S9S_MB_2U(SCH_1):GND

Q_CAP  I128  C67    [Q_CAP_C0805-10UF,16V,10%,X7R,CA]
    1  P12V_S3_AUX_CPU1_NVDIMM      A  @S9S_MB_2U_LIB.S9S_MB_2U(SCH_1):P12V_S3_AUX_CPU1_NVDIMM
    2  GND                B  @S9S_MB_2U_LIB.S9S_MB_2U(SCH_1):GND

Q_CAP  I122  C68    [Q_CAP_C0402-2.2UF,6.3V,20%,X6SA]
    1  P3V3_AUX           A  @S9S_MB_2U_LIB.S9S_MB_2U(SCH_1):P3V3_AUX
    2  GND                B  @S9S_MB_2U_LIB.S9S_MB_2U(SCH_1):GND

Q_CAP  I127  C69    [Q_CAP_C0805-10UF,16V,10%,X7R,CA]
    1  P12V_S3_AUX_CPU1_NVDIMM      A  @S9S_MB_2U_LIB.S9S_MB_2U(SCH_1):P12V_S3_AUX_CPU1_NVDIMM
    2  GND                B  @S9S_MB_2U_LIB.S9S_MB_2U(SCH_1):GND

Q_CAP  I129  C70    [Q_CAP_C0805-10UF,16V,10%,X7R,CA]
    1  P12V_S3_AUX_CPU1_NVDIMM      A  @S9S_MB_2U_LIB.S9S_MB_2U(SCH_1):P12V_S3_AUX_CPU1_NVDIMM
    2  GND                B  @S9S_MB_2U_LIB.S9S_MB_2U(SCH_1):GND

Q_CAP  I4   C71    [Q_CAP_C0402-10UF,6.3V,20%,X6S,A]
    1  P3V3_AUX           A  @S9S_MB_2U_LIB.S9S_MB_2U(SCH_1):P3V3_AUX
    2  GND                B  @S9S_MB_2U_LIB.S9S_MB_2U(SCH_1):GND

Q_CAP  I116  C72    [Q_CAP_C0402-2.2UF,6.3V,20%,X6SA]
    1  P3V3_AUX           A  @S9S_MB_2U_LIB.S9S_MB_2U(SCH_1):P3V3_AUX
    2  GND                B  @S9S_MB_2U_LIB.S9S_MB_2U(SCH_1):GND

Q_CAP  I120  C73    [Q_CAP_C0805-10UF,16V,10%,X7R,CA]
    1  P12V_S3_AUX_CPU1_NVDIMM      A  @S9S_MB_2U_LIB.S9S_MB_2U(SCH_1):P12V_S3_AUX_CPU1_NVDIMM
    2  GND                B  @S9S_MB_2U_LIB.S9S_MB_2U(SCH_1):GND

Q_CAP  I122  C74    [Q_CAP_C0805-10UF,16V,10%,X7R,CA]
    1  P12V_S3_AUX_CPU1_NVDIMM      A  @S9S_MB_2U_LIB.S9S_MB_2U(SCH_1):P12V_S3_AUX_CPU1_NVDIMM
    2  GND                B  @S9S_MB_2U_LIB.S9S_MB_2U(SCH_1):GND

Q_CAP  I124  C75    [Q_CAP_C0402-2.2UF,6.3V,20%,X6SA]
    1  P3V3_AUX           A  @S9S_MB_2U_LIB.S9S_MB_2U(SCH_1):P3V3_AUX
    2  GND                B  @S9S_MB_2U_LIB.S9S_MB_2U(SCH_1):GND

Q_CAP  I125  C76    [Q_CAP_C0805-10UF,16V,10%,X7R,CA]
    1  P12V_S3_AUX_CPU1_NVDIMM      A  @S9S_MB_2U_LIB.S9S_MB_2U(SCH_1):P12V_S3_AUX_CPU1_NVDIMM
    2  GND                B  @S9S_MB_2U_LIB.S9S_MB_2U(SCH_1):GND

Q_CAP  I126  C77    [Q_CAP_C0805-10UF,16V,10%,X7R,CA]
    1  P12V_S3_AUX_CPU1_NVDIMM      A  @S9S_MB_2U_LIB.S9S_MB_2U(SCH_1):P12V_S3_AUX_CPU1_NVDIMM
    2  GND                B  @S9S_MB_2U_LIB.S9S_MB_2U(SCH_1):GND

Q_CAP  I54  C78    [Q_CAP_C0402-2.2UF,6.3V,20%,X6SA]
    1  P3V3_AUX           A  @S9S_MB_2U_LIB.S9S_MB_2U(SCH_1):P3V3_AUX
    2  GND                B  @S9S_MB_2U_LIB.S9S_MB_2U(SCH_1):GND

Q_CAP  I56  C79    [Q_CAP_C0805-10UF,16V,10%,X7R,CA]
    1  P12V_S3_AUX_CPU1_NVDIMM      A  @S9S_MB_2U_LIB.S9S_MB_2U(SCH_1):P12V_S3_AUX_CPU1_NVDIMM
    2  GND                B  @S9S_MB_2U_LIB.S9S_MB_2U(SCH_1):GND

Q_CAP  I59  C80    [Q_CAP_C0805-10UF,16V,10%,X7R,CA]
    1  P12V_S3_AUX_CPU1_NVDIMM      A  @S9S_MB_2U_LIB.S9S_MB_2U(SCH_1):P12V_S3_AUX_CPU1_NVDIMM
    2  GND                B  @S9S_MB_2U_LIB.S9S_MB_2U(SCH_1):GND

Q_CAP  I120  C81    [Q_CAP_C0402-2.2UF,6.3V,20%,X6SA]
    1  P3V3_AUX           A  @S9S_MB_2U_LIB.S9S_MB_2U(SCH_1):P3V3_AUX
    2  GND                B  @S9S_MB_2U_LIB.S9S_MB_2U(SCH_1):GND

Q_CAP  I124  C82    [Q_CAP_C0805-10UF,16V,10%,X7R,CA]
    1  P12V_S3_AUX_CPU1_NVDIMM      A  @S9S_MB_2U_LIB.S9S_MB_2U(SCH_1):P12V_S3_AUX_CPU1_NVDIMM
    2  GND                B  @S9S_MB_2U_LIB.S9S_MB_2U(SCH_1):GND

Q_CAP  I126  C83    [Q_CAP_C0805-10UF,16V,10%,X7R,CA]
    1  P12V_S3_AUX_CPU1_NVDIMM      A  @S9S_MB_2U_LIB.S9S_MB_2U(SCH_1):P12V_S3_AUX_CPU1_NVDIMM
    2  GND                B  @S9S_MB_2U_LIB.S9S_MB_2U(SCH_1):GND

Q_CAP  I121  C84    [Q_CAP_C0402-2.2UF,6.3V,20%,X6SA]
    1  P3V3_AUX           A  @S9S_MB_2U_LIB.S9S_MB_2U(SCH_1):P3V3_AUX
    2  GND                B  @S9S_MB_2U_LIB.S9S_MB_2U(SCH_1):GND

Q_CAP  I125  C85    [Q_CAP_C0805-10UF,16V,10%,X7R,CA]
    1  P12V_S3_AUX_CPU1_NVDIMM      A  @S9S_MB_2U_LIB.S9S_MB_2U(SCH_1):P12V_S3_AUX_CPU1_NVDIMM
    2  GND                B  @S9S_MB_2U_LIB.S9S_MB_2U(SCH_1):GND

Q_CAP  I128  C86    [Q_CAP_C0805-10UF,16V,10%,X7R,CA]
    1  P12V_S3_AUX_CPU1_NVDIMM      A  @S9S_MB_2U_LIB.S9S_MB_2U(SCH_1):P12V_S3_AUX_CPU1_NVDIMM
    2  GND                B  @S9S_MB_2U_LIB.S9S_MB_2U(SCH_1):GND

Q_CAP  I121  C87    [Q_CAP_C0402-2.2UF,6.3V,20%,X6SA]
    1  P3V3_AUX           A  @S9S_MB_2U_LIB.S9S_MB_2U(SCH_1):P3V3_AUX
    2  GND                B  @S9S_MB_2U_LIB.S9S_MB_2U(SCH_1):GND

Q_CAP  I123  C88    [Q_CAP_C0805-10UF,16V,10%,X7R,CA]
    1  P12V_S3_AUX_CPU1_NVDIMM      A  @S9S_MB_2U_LIB.S9S_MB_2U(SCH_1):P12V_S3_AUX_CPU1_NVDIMM
    2  GND                B  @S9S_MB_2U_LIB.S9S_MB_2U(SCH_1):GND

Q_CAP  I160  C89    [Q_CAP_C0805-10UF,16V,10%,X7R,CA]
    1  P12V_S3_AUX_CPU1_NVDIMM      A  @S9S_MB_2U_LIB.S9S_MB_2U(SCH_1):P12V_S3_AUX_CPU1_NVDIMM
    2  GND                B  @S9S_MB_2U_LIB.S9S_MB_2U(SCH_1):GND

Q_CAP  I122  C90    [Q_CAP_C0402-2.2UF,6.3V,20%,X6SA]
    1  P3V3_AUX           A  @S9S_MB_2U_LIB.S9S_MB_2U(SCH_1):P3V3_AUX
    2  GND                B  @S9S_MB_2U_LIB.S9S_MB_2U(SCH_1):GND

Q_CAP  I126  C91    [Q_CAP_C0805-10UF,16V,10%,X7R,CA]
    1  P12V_S3_AUX_CPU1_NVDIMM      A  @S9S_MB_2U_LIB.S9S_MB_2U(SCH_1):P12V_S3_AUX_CPU1_NVDIMM
    2  GND                B  @S9S_MB_2U_LIB.S9S_MB_2U(SCH_1):GND

Q_CAP  I128  C92    [Q_CAP_C0805-10UF,16V,10%,X7R,CA]
    1  P12V_S3_AUX_CPU1_NVDIMM      A  @S9S_MB_2U_LIB.S9S_MB_2U(SCH_1):P12V_S3_AUX_CPU1_NVDIMM
    2  GND                B  @S9S_MB_2U_LIB.S9S_MB_2U(SCH_1):GND

Q_CAP  I122  C93    [Q_CAP_C0402-2.2UF,6.3V,20%,X6SA]
    1  P3V3_AUX           A  @S9S_MB_2U_LIB.S9S_MB_2U(SCH_1):P3V3_AUX
    2  GND                B  @S9S_MB_2U_LIB.S9S_MB_2U(SCH_1):GND

Q_CAP  I127  C94    [Q_CAP_C0805-10UF,16V,10%,X7R,CA]
    1  P12V_S3_AUX_CPU1_NVDIMM      A  @S9S_MB_2U_LIB.S9S_MB_2U(SCH_1):P12V_S3_AUX_CPU1_NVDIMM
    2  GND                B  @S9S_MB_2U_LIB.S9S_MB_2U(SCH_1):GND

Q_CAP  I130  C95    [Q_CAP_C0805-10UF,16V,10%,X7R,CA]
    1  P12V_S3_AUX_CPU1_NVDIMM      A  @S9S_MB_2U_LIB.S9S_MB_2U(SCH_1):P12V_S3_AUX_CPU1_NVDIMM
    2  GND                B  @S9S_MB_2U_LIB.S9S_MB_2U(SCH_1):GND

Q_CAP  I123  C96    [Q_CAP_C0402-2.2UF,6.3V,20%,X6SA]
    1  P3V3_AUX           A  @S9S_MB_2U_LIB.S9S_MB_2U(SCH_1):P3V3_AUX
    2  GND                B  @S9S_MB_2U_LIB.S9S_MB_2U(SCH_1):GND

Q_CAP  I124  C97    [Q_CAP_C0805-10UF,16V,10%,X7R,CA]
    1  P12V_S3_AUX_CPU1_NVDIMM      A  @S9S_MB_2U_LIB.S9S_MB_2U(SCH_1):P12V_S3_AUX_CPU1_NVDIMM
    2  GND                B  @S9S_MB_2U_LIB.S9S_MB_2U(SCH_1):GND

Q_CAP  I146  C98    [Q_CAP_C0805-10UF,16V,10%,X7R,CA]
    1  P12V_S3_AUX_CPU1_NVDIMM      A  @S9S_MB_2U_LIB.S9S_MB_2U(SCH_1):P12V_S3_AUX_CPU1_NVDIMM
    2  GND                B  @S9S_MB_2U_LIB.S9S_MB_2U(SCH_1):GND

Q_CAP  I148  C101   [Q_CAP_0805-47UF,4V,20%,X6S,CH6A]
    1  PVCCIN_CPU0        A  @S9S_MB_2U_LIB.S9S_MB_2U(SCH_1):PVCCIN_CPU0
    2  GND                B  @S9S_MB_2U_LIB.S9S_MB_2U(SCH_1):GND

Q_CAP  I77  C103   [Q_CAP_0402-27PF  ,50V ,5% ,EMPA]
    1  XTAL_PCH_25M_IN_R      A  @S9S_MB_2U_LIB.S9S_MB_2U(SCH_1):XTAL_PCH_25M_IN_R
    2  GND                B  @S9S_MB_2U_LIB.S9S_MB_2U(SCH_1):GND

Q_CAP  I76  C104   [Q_CAP_0402-27PF  ,50V ,5% ,EMPA]
    1  XTAL_PCH_25M_OUT      A  @S9S_MB_2U_LIB.S9S_MB_2U(SCH_1):XTAL_PCH_25M_OUT
    2  GND                B  @S9S_MB_2U_LIB.S9S_MB_2U(SCH_1):GND

Q_CAP  I19  C108   [Q_CAP_C0603-10UF,6.3V,20%,X6S,A]
    1  P3V3_AUX_CLK_GEN_VDD_CK440      A  @S9S_MB_2U_LIB.S9S_MB_2U(SCH_1):P3V3_AUX_CLK_GEN_VDD_CK440
    2  GND                B  @S9S_MB_2U_LIB.S9S_MB_2U(SCH_1):GND

Q_CAP  I18  C109   [Q_CAP_C0402-1UF,25V,10%,X6S,CHA]
    1  P3V3_AUX_CLK_GEN_VDD_CK440      A  @S9S_MB_2U_LIB.S9S_MB_2U(SCH_1):P3V3_AUX_CLK_GEN_VDD_CK440
    2  GND                B  @S9S_MB_2U_LIB.S9S_MB_2U(SCH_1):GND

Q_CAP  I17  C110   [Q_CAP_0402-0.1UF,25V,10%,X7R,CA]
    1  P3V3_AUX_CLK_GEN_VDD_CK440      A  @S9S_MB_2U_LIB.S9S_MB_2U(SCH_1):P3V3_AUX_CLK_GEN_VDD_CK440
    2  GND                B  @S9S_MB_2U_LIB.S9S_MB_2U(SCH_1):GND

Q_CAP  I46  C111   [Q_CAP_0402-0.1UF,25V,10%,X7R,CA]
    1  P3V3_AUX_CLK_GEN_VDDXTAL_CK440      A  @S9S_MB_2U_LIB.S9S_MB_2U(SCH_1):P3V3_AUX_CLK_GEN_VDDXTAL_CK440
    2  GND                B  @S9S_MB_2U_LIB.S9S_MB_2U(SCH_1):GND

Q_CAP  I45  C112   [Q_CAP_0402-0.1UF,25V,10%,X7R,CA]
    1  P3V3_AUX_CLK_GEN_VDDXTAL_CK440      A  @S9S_MB_2U_LIB.S9S_MB_2U(SCH_1):P3V3_AUX_CLK_GEN_VDDXTAL_CK440
    2  GND                B  @S9S_MB_2U_LIB.S9S_MB_2U(SCH_1):GND

Q_CAP  I186  C113   [Q_CAP_0402-15PF,50V,5%,C0G,CH0A]
    1  XTAL_CLK_GEN1_25M_X1_R      A  @S9S_MB_2U_LIB.S9S_MB_2U(SCH_1):XTAL_CLK_GEN1_25M_X1_R
    2  GND                B  @S9S_MB_2U_LIB.S9S_MB_2U(SCH_1):GND

Q_CAP  I47  C114   [Q_CAP_0402-0.1UF,25V,10%,X7R,CA]
    1  P3V3_AUX_CLK_GEN_VDDA25M_CK440      A  @S9S_MB_2U_LIB.S9S_MB_2U(SCH_1):P3V3_AUX_CLK_GEN_VDDA25M_CK440
    2  GND                B  @S9S_MB_2U_LIB.S9S_MB_2U(SCH_1):GND

Q_CAP  I66  C115   [Q_CAP_0402-0.1UF,25V,10%,X7R,CA]
    1  P3V3_AUX_CLK_GEN_VDDMXCK_CK440      A  @S9S_MB_2U_LIB.S9S_MB_2U(SCH_1):P3V3_AUX_CLK_GEN_VDDMXCK_CK440
    2  GND                B  @S9S_MB_2U_LIB.S9S_MB_2U(SCH_1):GND

Q_CAP  I65  C116   [Q_CAP_0402-0.1UF,25V,10%,X7R,CA]
    1  P3V3_AUX_CLK_GEN_VDDMXCK_CK440      A  @S9S_MB_2U_LIB.S9S_MB_2U(SCH_1):P3V3_AUX_CLK_GEN_VDDMXCK_CK440
    2  GND                B  @S9S_MB_2U_LIB.S9S_MB_2U(SCH_1):GND

Q_CAP  I64  C117   [Q_CAP_0402-0.1UF,25V,10%,X7R,CA]
    1  P3V3_AUX_CLK_GEN_VDDMXCK_CK440      A  @S9S_MB_2U_LIB.S9S_MB_2U(SCH_1):P3V3_AUX_CLK_GEN_VDDMXCK_CK440
    2  GND                B  @S9S_MB_2U_LIB.S9S_MB_2U(SCH_1):GND

Q_CAP  I183  C118   [Q_CAP_0402-15PF,50V,5%,C0G,CH0A]
    1  XTAL_CLK_GEN1_25M_X2      A  @S9S_MB_2U_LIB.S9S_MB_2U(SCH_1):XTAL_CLK_GEN1_25M_X2
    2  GND                B  @S9S_MB_2U_LIB.S9S_MB_2U(SCH_1):GND

Q_CAP  I67  C119   [Q_CAP_0402-0.1UF,25V,10%,X7R,CA]
    1  P3V3_AUX_CLK_GEN_VDDMXCK_CK440      A  @S9S_MB_2U_LIB.S9S_MB_2U(SCH_1):P3V3_AUX_CLK_GEN_VDDMXCK_CK440
    2  GND                B  @S9S_MB_2U_LIB.S9S_MB_2U(SCH_1):GND

Q_CAP  I68  C120   [Q_CAP_0402-0.1UF,25V,10%,X7R,CA]
    1  P3V3_AUX_CLK_GEN_VDDPT_CK440      A  @S9S_MB_2U_LIB.S9S_MB_2U(SCH_1):P3V3_AUX_CLK_GEN_VDDPT_CK440
    2  GND                B  @S9S_MB_2U_LIB.S9S_MB_2U(SCH_1):GND

Q_CAPP  I50  C127   [Q_CAPP_RDLLF-270UF,16V,20%,OSCA]
    1  P12V_FRONT_CPU0      A  @S9S_MB_2U_LIB.S9S_MB_2U(SCH_1):P12V_FRONT_CPU0
    2  GND                B  @S9S_MB_2U_LIB.S9S_MB_2U(SCH_1):GND

Q_CAP  I52  C128   [Q_CAP_0402-0.1UF,25V,10%,X7R,CA]
    1  P12V_FRONT_CPU0      A  @S9S_MB_2U_LIB.S9S_MB_2U(SCH_1):P12V_FRONT_CPU0
    2  GND                B  @S9S_MB_2U_LIB.S9S_MB_2U(SCH_1):GND

Q_CAPP  I54  C129   [Q_CAPP_SMLF-100UF,16V,20%,POSCA]
    1  P3V3               A  @S9S_MB_2U_LIB.S9S_MB_2U(SCH_1):P3V3
    2  GND                B  @S9S_MB_2U_LIB.S9S_MB_2U(SCH_1):GND

Q_CAP  I56  C130   [Q_CAP_0402-0.1UF,25V,10%,X7R,CA]
    1  P3V3               A  @S9S_MB_2U_LIB.S9S_MB_2U(SCH_1):P3V3
    2  GND                B  @S9S_MB_2U_LIB.S9S_MB_2U(SCH_1):GND

Q_CAP  I103  C131   [Q_CAP_C0402-1UF,25V,10%,X6S,CHA]
    1  P3V3_AUX           A  @S9S_MB_2U_LIB.S9S_MB_2U(SCH_1):P3V3_AUX
    2  GND                B  @S9S_MB_2U_LIB.S9S_MB_2U(SCH_1):GND

Q_CAP  I106  C132   [Q_CAP_0402-0.1UF,25V,10%,X7R,CA]
    1  P3V3_AUX           A  @S9S_MB_2U_LIB.S9S_MB_2U(SCH_1):P3V3_AUX
    2  GND                B  @S9S_MB_2U_LIB.S9S_MB_2U(SCH_1):GND

Q_CAPP  I18  C133   [Q_CAPP_SMLF-100UF,16V,20%,POSCA]
    1  P12V_FRONT_CPU      A  @S9S_MB_2U_LIB.S9S_MB_2U(SCH_1):P12V_FRONT_CPU
    2  GND                B  @S9S_MB_2U_LIB.S9S_MB_2U(SCH_1):GND

Q_CAP  I20  C134   [Q_CAP_0402-0.1UF,25V,10%,X7R,CA]
    1  P12V_FRONT_CPU      A  @S9S_MB_2U_LIB.S9S_MB_2U(SCH_1):P12V_FRONT_CPU
    2  GND                B  @S9S_MB_2U_LIB.S9S_MB_2U(SCH_1):GND

Q_CAPP  I21  C135   [Q_CAPP_SMLF-100UF,16V,20%,POSCA]
    1  P3V3               A  @S9S_MB_2U_LIB.S9S_MB_2U(SCH_1):P3V3
    2  GND                B  @S9S_MB_2U_LIB.S9S_MB_2U(SCH_1):GND

Q_CAP  I23  C136   [Q_CAP_0402-0.1UF,25V,10%,X7R,CA]
    1  P3V3               A  @S9S_MB_2U_LIB.S9S_MB_2U(SCH_1):P3V3
    2  GND                B  @S9S_MB_2U_LIB.S9S_MB_2U(SCH_1):GND

Q_CAP  I24  C137   [Q_CAP_C0402-1UF,25V,10%,X6S,CHA]
    1  P3V3_AUX           A  @S9S_MB_2U_LIB.S9S_MB_2U(SCH_1):P3V3_AUX
    2  GND                B  @S9S_MB_2U_LIB.S9S_MB_2U(SCH_1):GND

Q_CAP  I26  C138   [Q_CAP_0402-0.1UF,25V,10%,X7R,CA]
    1  P3V3_AUX           A  @S9S_MB_2U_LIB.S9S_MB_2U(SCH_1):P3V3_AUX
    2  GND                B  @S9S_MB_2U_LIB.S9S_MB_2U(SCH_1):GND

Q_CAP_DIFFBUS  I35  C139   [Q_CAP_DIFFBUS_C0201-DIFF BUS_0A]
    2  DMI_CPU0_PCH_TX_DN<7>      2  @S9S_MB_2U_LIB.S9S_MB_2U(SCH_1):DMI_CPU0_PCH_TX_DN<7>
    1  DMI_CPU0_PCH_TX_C_DN<7>      1  @S9S_MB_2U_LIB.S9S_MB_2U(SCH_1):DMI_CPU0_PCH_TX_C_DN<7>

Q_CAP_DIFFBUS  I36  C140   [Q_CAP_DIFFBUS_C0201-DIFF BUS_0A]
    2  DMI_CPU0_PCH_TX_DP<7>      2  @S9S_MB_2U_LIB.S9S_MB_2U(SCH_1):DMI_CPU0_PCH_TX_DP<7>
    1  DMI_CPU0_PCH_TX_C_DP<7>      1  @S9S_MB_2U_LIB.S9S_MB_2U(SCH_1):DMI_CPU0_PCH_TX_C_DP<7>

Q_CAP_DIFFBUS  I34  C141   [Q_CAP_DIFFBUS_C0201-DIFF BUS_0A]
    2  DMI_CPU0_PCH_TX_DN<6>      2  @S9S_MB_2U_LIB.S9S_MB_2U(SCH_1):DMI_CPU0_PCH_TX_DN<6>
    1  DMI_CPU0_PCH_TX_C_DN<6>      1  @S9S_MB_2U_LIB.S9S_MB_2U(SCH_1):DMI_CPU0_PCH_TX_C_DN<6>

Q_CAP_DIFFBUS  I33  C142   [Q_CAP_DIFFBUS_C0201-DIFF BUS_0A]
    2  DMI_CPU0_PCH_TX_DP<6>      2  @S9S_MB_2U_LIB.S9S_MB_2U(SCH_1):DMI_CPU0_PCH_TX_DP<6>
    1  DMI_CPU0_PCH_TX_C_DP<6>      1  @S9S_MB_2U_LIB.S9S_MB_2U(SCH_1):DMI_CPU0_PCH_TX_C_DP<6>

Q_CAP_DIFFBUS  I32  C143   [Q_CAP_DIFFBUS_C0201-DIFF BUS_0A]
    2  DMI_CPU0_PCH_TX_DN<5>      2  @S9S_MB_2U_LIB.S9S_MB_2U(SCH_1):DMI_CPU0_PCH_TX_DN<5>
    1  DMI_CPU0_PCH_TX_C_DN<5>      1  @S9S_MB_2U_LIB.S9S_MB_2U(SCH_1):DMI_CPU0_PCH_TX_C_DN<5>

Q_CAP_DIFFBUS  I31  C144   [Q_CAP_DIFFBUS_C0201-DIFF BUS_0A]
    2  DMI_CPU0_PCH_TX_DP<5>      2  @S9S_MB_2U_LIB.S9S_MB_2U(SCH_1):DMI_CPU0_PCH_TX_DP<5>
    1  DMI_CPU0_PCH_TX_C_DP<5>      1  @S9S_MB_2U_LIB.S9S_MB_2U(SCH_1):DMI_CPU0_PCH_TX_C_DP<5>

Q_CAP_DIFFBUS  I30  C145   [Q_CAP_DIFFBUS_C0201-DIFF BUS_0A]
    2  DMI_CPU0_PCH_TX_DN<4>      2  @S9S_MB_2U_LIB.S9S_MB_2U(SCH_1):DMI_CPU0_PCH_TX_DN<4>
    1  DMI_CPU0_PCH_TX_C_DN<4>      1  @S9S_MB_2U_LIB.S9S_MB_2U(SCH_1):DMI_CPU0_PCH_TX_C_DN<4>

Q_CAP_DIFFBUS  I29  C146   [Q_CAP_DIFFBUS_C0201-DIFF BUS_0A]
    2  DMI_CPU0_PCH_TX_DP<4>      2  @S9S_MB_2U_LIB.S9S_MB_2U(SCH_1):DMI_CPU0_PCH_TX_DP<4>
    1  DMI_CPU0_PCH_TX_C_DP<4>      1  @S9S_MB_2U_LIB.S9S_MB_2U(SCH_1):DMI_CPU0_PCH_TX_C_DP<4>

Q_CAP_DIFFBUS  I28  C147   [Q_CAP_DIFFBUS_C0201-DIFF BUS_0A]
    2  DMI_CPU0_PCH_TX_DN<3>      2  @S9S_MB_2U_LIB.S9S_MB_2U(SCH_1):DMI_CPU0_PCH_TX_DN<3>
    1  DMI_CPU0_PCH_TX_C_DN<3>      1  @S9S_MB_2U_LIB.S9S_MB_2U(SCH_1):DMI_CPU0_PCH_TX_C_DN<3>

Q_CAP_DIFFBUS  I27  C148   [Q_CAP_DIFFBUS_C0201-DIFF BUS_0A]
    2  DMI_CPU0_PCH_TX_DP<3>      2  @S9S_MB_2U_LIB.S9S_MB_2U(SCH_1):DMI_CPU0_PCH_TX_DP<3>
    1  DMI_CPU0_PCH_TX_C_DP<3>      1  @S9S_MB_2U_LIB.S9S_MB_2U(SCH_1):DMI_CPU0_PCH_TX_C_DP<3>

Q_CAP_DIFFBUS  I25  C149   [Q_CAP_DIFFBUS_C0201-DIFF BUS_0A]
    2  DMI_CPU0_PCH_TX_DN<2>      2  @S9S_MB_2U_LIB.S9S_MB_2U(SCH_1):DMI_CPU0_PCH_TX_DN<2>
    1  DMI_CPU0_PCH_TX_C_DN<2>      1  @S9S_MB_2U_LIB.S9S_MB_2U(SCH_1):DMI_CPU0_PCH_TX_C_DN<2>

Q_CAP_DIFFBUS  I26  C150   [Q_CAP_DIFFBUS_C0201-DIFF BUS_0A]
    2  DMI_CPU0_PCH_TX_DP<2>      2  @S9S_MB_2U_LIB.S9S_MB_2U(SCH_1):DMI_CPU0_PCH_TX_DP<2>
    1  DMI_CPU0_PCH_TX_C_DP<2>      1  @S9S_MB_2U_LIB.S9S_MB_2U(SCH_1):DMI_CPU0_PCH_TX_C_DP<2>

Q_CAP_DIFFBUS  I24  C151   [Q_CAP_DIFFBUS_C0201-DIFF BUS_0A]
    2  DMI_CPU0_PCH_TX_DN<1>      2  @S9S_MB_2U_LIB.S9S_MB_2U(SCH_1):DMI_CPU0_PCH_TX_DN<1>
    1  DMI_CPU0_PCH_TX_C_DN<1>      1  @S9S_MB_2U_LIB.S9S_MB_2U(SCH_1):DMI_CPU0_PCH_TX_C_DN<1>

Q_CAP_DIFFBUS  I23  C152   [Q_CAP_DIFFBUS_C0201-DIFF BUS_0A]
    2  DMI_CPU0_PCH_TX_DP<1>      2  @S9S_MB_2U_LIB.S9S_MB_2U(SCH_1):DMI_CPU0_PCH_TX_DP<1>
    1  DMI_CPU0_PCH_TX_C_DP<1>      1  @S9S_MB_2U_LIB.S9S_MB_2U(SCH_1):DMI_CPU0_PCH_TX_C_DP<1>

Q_CAP_DIFFBUS  I21  C153   [Q_CAP_DIFFBUS_C0201-DIFF BUS_0A]
    2  DMI_CPU0_PCH_TX_DN<0>      2  @S9S_MB_2U_LIB.S9S_MB_2U(SCH_1):DMI_CPU0_PCH_TX_DN<0>
    1  DMI_CPU0_PCH_TX_C_DN<0>      1  @S9S_MB_2U_LIB.S9S_MB_2U(SCH_1):DMI_CPU0_PCH_TX_C_DN<0>

Q_CAP_DIFFBUS  I22  C154   [Q_CAP_DIFFBUS_C0201-DIFF BUS_0A]
    2  DMI_CPU0_PCH_TX_DP<0>      2  @S9S_MB_2U_LIB.S9S_MB_2U(SCH_1):DMI_CPU0_PCH_TX_DP<0>
    1  DMI_CPU0_PCH_TX_C_DP<0>      1  @S9S_MB_2U_LIB.S9S_MB_2U(SCH_1):DMI_CPU0_PCH_TX_C_DP<0>

Q_CAP_DIFFBUS  I113  C155   [Q_CAP_DIFFBUS_C0201-DIFF BUS_0A]
    2  DMI_CPU0_PCH_RX_DN<7>      2  @S9S_MB_2U_LIB.S9S_MB_2U(SCH_1):DMI_CPU0_PCH_RX_DN<7>
    1  DMI_CPU0_PCH_RX_C_DN<7>      1  @S9S_MB_2U_LIB.S9S_MB_2U(SCH_1):DMI_CPU0_PCH_RX_C_DN<7>

Q_CAP_DIFFBUS  I114  C156   [Q_CAP_DIFFBUS_C0201-DIFF BUS_0A]
    2  DMI_CPU0_PCH_RX_DP<7>      2  @S9S_MB_2U_LIB.S9S_MB_2U(SCH_1):DMI_CPU0_PCH_RX_DP<7>
    1  DMI_CPU0_PCH_RX_C_DP<7>      1  @S9S_MB_2U_LIB.S9S_MB_2U(SCH_1):DMI_CPU0_PCH_RX_C_DP<7>

Q_CAP_DIFFBUS  I115  C157   [Q_CAP_DIFFBUS_C0201-DIFF BUS_0A]
    2  DMI_CPU0_PCH_RX_DN<6>      2  @S9S_MB_2U_LIB.S9S_MB_2U(SCH_1):DMI_CPU0_PCH_RX_DN<6>
    1  DMI_CPU0_PCH_RX_C_DN<6>      1  @S9S_MB_2U_LIB.S9S_MB_2U(SCH_1):DMI_CPU0_PCH_RX_C_DN<6>

Q_CAP_DIFFBUS  I116  C158   [Q_CAP_DIFFBUS_C0201-DIFF BUS_0A]
    2  DMI_CPU0_PCH_RX_DP<6>      2  @S9S_MB_2U_LIB.S9S_MB_2U(SCH_1):DMI_CPU0_PCH_RX_DP<6>
    1  DMI_CPU0_PCH_RX_C_DP<6>      1  @S9S_MB_2U_LIB.S9S_MB_2U(SCH_1):DMI_CPU0_PCH_RX_C_DP<6>

Q_CAP_DIFFBUS  I117  C159   [Q_CAP_DIFFBUS_C0201-DIFF BUS_0A]
    2  DMI_CPU0_PCH_RX_DN<5>      2  @S9S_MB_2U_LIB.S9S_MB_2U(SCH_1):DMI_CPU0_PCH_RX_DN<5>
    1  DMI_CPU0_PCH_RX_C_DN<5>      1  @S9S_MB_2U_LIB.S9S_MB_2U(SCH_1):DMI_CPU0_PCH_RX_C_DN<5>

Q_CAP_DIFFBUS  I118  C160   [Q_CAP_DIFFBUS_C0201-DIFF BUS_0A]
    2  DMI_CPU0_PCH_RX_DP<5>      2  @S9S_MB_2U_LIB.S9S_MB_2U(SCH_1):DMI_CPU0_PCH_RX_DP<5>
    1  DMI_CPU0_PCH_RX_C_DP<5>      1  @S9S_MB_2U_LIB.S9S_MB_2U(SCH_1):DMI_CPU0_PCH_RX_C_DP<5>

Q_CAP_DIFFBUS  I119  C161   [Q_CAP_DIFFBUS_C0201-DIFF BUS_0A]
    2  DMI_CPU0_PCH_RX_DN<4>      2  @S9S_MB_2U_LIB.S9S_MB_2U(SCH_1):DMI_CPU0_PCH_RX_DN<4>
    1  DMI_CPU0_PCH_RX_C_DN<4>      1  @S9S_MB_2U_LIB.S9S_MB_2U(SCH_1):DMI_CPU0_PCH_RX_C_DN<4>

Q_CAP_DIFFBUS  I120  C162   [Q_CAP_DIFFBUS_C0201-DIFF BUS_0A]
    2  DMI_CPU0_PCH_RX_DP<4>      2  @S9S_MB_2U_LIB.S9S_MB_2U(SCH_1):DMI_CPU0_PCH_RX_DP<4>
    1  DMI_CPU0_PCH_RX_C_DP<4>      1  @S9S_MB_2U_LIB.S9S_MB_2U(SCH_1):DMI_CPU0_PCH_RX_C_DP<4>

Q_CAP_DIFFBUS  I121  C163   [Q_CAP_DIFFBUS_C0201-DIFF BUS_0A]
    2  DMI_CPU0_PCH_RX_DN<3>      2  @S9S_MB_2U_LIB.S9S_MB_2U(SCH_1):DMI_CPU0_PCH_RX_DN<3>
    1  DMI_CPU0_PCH_RX_C_DN<3>      1  @S9S_MB_2U_LIB.S9S_MB_2U(SCH_1):DMI_CPU0_PCH_RX_C_DN<3>

Q_CAP_DIFFBUS  I122  C164   [Q_CAP_DIFFBUS_C0201-DIFF BUS_0A]
    2  DMI_CPU0_PCH_RX_DP<3>      2  @S9S_MB_2U_LIB.S9S_MB_2U(SCH_1):DMI_CPU0_PCH_RX_DP<3>
    1  DMI_CPU0_PCH_RX_C_DP<3>      1  @S9S_MB_2U_LIB.S9S_MB_2U(SCH_1):DMI_CPU0_PCH_RX_C_DP<3>

Q_CAP_DIFFBUS  I123  C165   [Q_CAP_DIFFBUS_C0201-DIFF BUS_0A]
    2  DMI_CPU0_PCH_RX_DN<2>      2  @S9S_MB_2U_LIB.S9S_MB_2U(SCH_1):DMI_CPU0_PCH_RX_DN<2>
    1  DMI_CPU0_PCH_RX_C_DN<2>      1  @S9S_MB_2U_LIB.S9S_MB_2U(SCH_1):DMI_CPU0_PCH_RX_C_DN<2>

Q_CAP_DIFFBUS  I124  C166   [Q_CAP_DIFFBUS_C0201-DIFF BUS_0A]
    2  DMI_CPU0_PCH_RX_DP<2>      2  @S9S_MB_2U_LIB.S9S_MB_2U(SCH_1):DMI_CPU0_PCH_RX_DP<2>
    1  DMI_CPU0_PCH_RX_C_DP<2>      1  @S9S_MB_2U_LIB.S9S_MB_2U(SCH_1):DMI_CPU0_PCH_RX_C_DP<2>

Q_CAP_DIFFBUS  I126  C167   [Q_CAP_DIFFBUS_C0201-DIFF BUS_0A]
    2  DMI_CPU0_PCH_RX_DN<1>      2  @S9S_MB_2U_LIB.S9S_MB_2U(SCH_1):DMI_CPU0_PCH_RX_DN<1>
    1  DMI_CPU0_PCH_RX_C_DN<1>      1  @S9S_MB_2U_LIB.S9S_MB_2U(SCH_1):DMI_CPU0_PCH_RX_C_DN<1>

Q_CAP_DIFFBUS  I125  C168   [Q_CAP_DIFFBUS_C0201-DIFF BUS_0A]
    2  DMI_CPU0_PCH_RX_DP<1>      2  @S9S_MB_2U_LIB.S9S_MB_2U(SCH_1):DMI_CPU0_PCH_RX_DP<1>
    1  DMI_CPU0_PCH_RX_C_DP<1>      1  @S9S_MB_2U_LIB.S9S_MB_2U(SCH_1):DMI_CPU0_PCH_RX_C_DP<1>

Q_CAP_DIFFBUS  I127  C169   [Q_CAP_DIFFBUS_C0201-DIFF BUS_0A]
    2  DMI_CPU0_PCH_RX_DN<0>      2  @S9S_MB_2U_LIB.S9S_MB_2U(SCH_1):DMI_CPU0_PCH_RX_DN<0>
    1  DMI_CPU0_PCH_RX_C_DN<0>      1  @S9S_MB_2U_LIB.S9S_MB_2U(SCH_1):DMI_CPU0_PCH_RX_C_DN<0>

Q_CAP_DIFFBUS  I128  C170   [Q_CAP_DIFFBUS_C0201-DIFF BUS_0A]
    2  DMI_CPU0_PCH_RX_DP<0>      2  @S9S_MB_2U_LIB.S9S_MB_2U(SCH_1):DMI_CPU0_PCH_RX_DP<0>
    1  DMI_CPU0_PCH_RX_C_DP<0>      1  @S9S_MB_2U_LIB.S9S_MB_2U(SCH_1):DMI_CPU0_PCH_RX_C_DP<0>

Q_CAP  I2   C171   [Q_CAP_0402-0.1UF,25V,10%,X7R,CA]
    1  P3V3_AUX_CLK_GEN_VDD_CK440      A  @S9S_MB_2U_LIB.S9S_MB_2U(SCH_1):P3V3_AUX_CLK_GEN_VDD_CK440
    2  GND                B  @S9S_MB_2U_LIB.S9S_MB_2U(SCH_1):GND

Q_CAP  I6   C172   [Q_CAP_C0603-10UF,6.3V,20%,X6S,A]
    1  P3V3_AUX_CLK_GEN_VDDA100M_CK440      A  @S9S_MB_2U_LIB.S9S_MB_2U(SCH_1):P3V3_AUX_CLK_GEN_VDDA100M_CK440
    2  GND                B  @S9S_MB_2U_LIB.S9S_MB_2U(SCH_1):GND

Q_CAP  I4   C173   [Q_CAP_0402-0.1UF,25V,10%,X7R,CA]
    1  P3V3_AUX_CLK_GEN_VDDA100M_CK440      A  @S9S_MB_2U_LIB.S9S_MB_2U(SCH_1):P3V3_AUX_CLK_GEN_VDDA100M_CK440
    2  GND                B  @S9S_MB_2U_LIB.S9S_MB_2U(SCH_1):GND

Q_CAP  I151  C174   [Q_CAP_0402-0.1UF,25V,10%,X7R,CA]
    1  P3V3_AUX           A  @S9S_MB_2U_LIB.S9S_MB_2U(SCH_1):P3V3_AUX
    2  GND                B  @S9S_MB_2U_LIB.S9S_MB_2U(SCH_1):GND

Q_CAP  I38  C179   [Q_CAP_C0402-100NF,50V,10%,X7R,A]
    1  P3V3_E1S_0_DVDT      A  @S9S_MB_2U_LIB.S9S_MB_2U(SCH_1):P3V3_E1S_0_DVDT
    2  GND                B  @S9S_MB_2U_LIB.S9S_MB_2U(SCH_1):GND

Q_CAP  I77  C180   [Q_CAP_0402-0.1UF,25V,10%,X7R,CA]
    1  P12V_FRONT_CPU      A  @S9S_MB_2U_LIB.S9S_MB_2U(SCH_1):P12V_FRONT_CPU
    2  GND                B  @S9S_MB_2U_LIB.S9S_MB_2U(SCH_1):GND

Q_CAP  I45  C184   [Q_CAP_C0805-10UF,25V,10%,X6S,CA]
    1  P3V3_E1S_0         A  @S9S_MB_2U_LIB.S9S_MB_2U(SCH_1):P3V3_E1S_0
    2  GND                B  @S9S_MB_2U_LIB.S9S_MB_2U(SCH_1):GND

Q_CAP  I44  C188   [Q_CAP_0402-0.1UF,25V,10%,X7R,CA]
    1  P3V3_AUX           A  @S9S_MB_2U_LIB.S9S_MB_2U(SCH_1):P3V3_AUX
    2  GND                B  @S9S_MB_2U_LIB.S9S_MB_2U(SCH_1):GND

Q_CAP  I171  C204   [Q_CAP_0402-0.1UF,25V,10%,X7R,CA]
    1  P3V3_DB2000_VDD      A  @S9S_MB_2U_LIB.S9S_MB_2U(SCH_1):P3V3_DB2000_VDD
    2  GND                B  @S9S_MB_2U_LIB.S9S_MB_2U(SCH_1):GND

Q_CAP  I172  C205   [Q_CAP_0402-0.1UF,25V,10%,X7R,CA]
    1  P3V3_DB2000_VDD      A  @S9S_MB_2U_LIB.S9S_MB_2U(SCH_1):P3V3_DB2000_VDD
    2  GND                B  @S9S_MB_2U_LIB.S9S_MB_2U(SCH_1):GND

Q_CAP  I173  C206   [Q_CAP_0402-0.1UF,25V,10%,X7R,CA]
    1  P3V3_DB2000_VDD      A  @S9S_MB_2U_LIB.S9S_MB_2U(SCH_1):P3V3_DB2000_VDD
    2  GND                B  @S9S_MB_2U_LIB.S9S_MB_2U(SCH_1):GND

Q_CAP  I174  C207   [Q_CAP_0402-0.1UF,25V,10%,X7R,CA]
    1  P3V3_DB2000_VDD      A  @S9S_MB_2U_LIB.S9S_MB_2U(SCH_1):P3V3_DB2000_VDD
    2  GND                B  @S9S_MB_2U_LIB.S9S_MB_2U(SCH_1):GND

Q_CAP  I167  C208   [Q_CAP_C0603-10UF,6.3V,20%,X6S,A]
    1  P3V3_DB2000_VDDR      A  @S9S_MB_2U_LIB.S9S_MB_2U(SCH_1):P3V3_DB2000_VDDR
    2  GND                B  @S9S_MB_2U_LIB.S9S_MB_2U(SCH_1):GND

Q_CAP  I164  C209   [Q_CAP_C0603-10UF,6.3V,20%,X6S,A]
    1  P3V3_DB2000_VDDA      A  @S9S_MB_2U_LIB.S9S_MB_2U(SCH_1):P3V3_DB2000_VDDA
    2  GND                B  @S9S_MB_2U_LIB.S9S_MB_2U(SCH_1):GND

Q_CAP  I168  C210   [Q_CAP_0402-0.1UF,25V,10%,X7R,CA]
    1  P3V3_DB2000_VDDR      A  @S9S_MB_2U_LIB.S9S_MB_2U(SCH_1):P3V3_DB2000_VDDR
    2  GND                B  @S9S_MB_2U_LIB.S9S_MB_2U(SCH_1):GND

Q_CAP  I165  C211   [Q_CAP_0402-0.1UF,25V,10%,X7R,CA]
    1  P3V3_DB2000_VDDA      A  @S9S_MB_2U_LIB.S9S_MB_2U(SCH_1):P3V3_DB2000_VDDA
    2  GND                B  @S9S_MB_2U_LIB.S9S_MB_2U(SCH_1):GND

Q_CAP  I159  C212   [Q_CAP_0805-47UF,4V,20%,X6S,CH6A]
    1  PVCCIN_CPU0        A  @S9S_MB_2U_LIB.S9S_MB_2U(SCH_1):PVCCIN_CPU0
    2  GND                B  @S9S_MB_2U_LIB.S9S_MB_2U(SCH_1):GND

Q_CAP  I149  C213   [Q_CAP_0805-47UF,4V,20%,X6S,CH6A]
    1  PVCCIN_CPU0        A  @S9S_MB_2U_LIB.S9S_MB_2U(SCH_1):PVCCIN_CPU0
    2  GND                B  @S9S_MB_2U_LIB.S9S_MB_2U(SCH_1):GND

Q_CAP  I151  C214   [Q_CAP_0805-47UF,4V,20%,X6S,CH6A]
    1  PVCCIN_CPU0        A  @S9S_MB_2U_LIB.S9S_MB_2U(SCH_1):PVCCIN_CPU0
    2  GND                B  @S9S_MB_2U_LIB.S9S_MB_2U(SCH_1):GND

Q_CAP  I152  C215   [Q_CAP_0805-47UF,4V,20%,X6S,CH6A]
    1  PVCCIN_CPU0        A  @S9S_MB_2U_LIB.S9S_MB_2U(SCH_1):PVCCIN_CPU0
    2  GND                B  @S9S_MB_2U_LIB.S9S_MB_2U(SCH_1):GND

Q_CAP  I153  C216   [Q_CAP_0805-47UF,4V,20%,X6S,CH6A]
    1  PVCCIN_CPU0        A  @S9S_MB_2U_LIB.S9S_MB_2U(SCH_1):PVCCIN_CPU0
    2  GND                B  @S9S_MB_2U_LIB.S9S_MB_2U(SCH_1):GND

Q_CAP  I154  C217   [Q_CAP_0805-47UF,4V,20%,X6S,CH6A]
    1  PVCCIN_CPU0        A  @S9S_MB_2U_LIB.S9S_MB_2U(SCH_1):PVCCIN_CPU0
    2  GND                B  @S9S_MB_2U_LIB.S9S_MB_2U(SCH_1):GND

Q_CAP  I155  C218   [Q_CAP_0805-47UF,4V,20%,X6S,CH6A]
    1  PVCCIN_CPU0        A  @S9S_MB_2U_LIB.S9S_MB_2U(SCH_1):PVCCIN_CPU0
    2  GND                B  @S9S_MB_2U_LIB.S9S_MB_2U(SCH_1):GND

Q_CAP  I156  C219   [Q_CAP_0805-47UF,4V,20%,X6S,CH6A]
    1  PVCCIN_CPU0        A  @S9S_MB_2U_LIB.S9S_MB_2U(SCH_1):PVCCIN_CPU0
    2  GND                B  @S9S_MB_2U_LIB.S9S_MB_2U(SCH_1):GND

Q_CAP  I158  C220   [Q_CAP_0805-47UF,4V,20%,X6S,CH6A]
    1  PVCCIN_CPU0        A  @S9S_MB_2U_LIB.S9S_MB_2U(SCH_1):PVCCIN_CPU0
    2  GND                B  @S9S_MB_2U_LIB.S9S_MB_2U(SCH_1):GND

Q_CAP  I27  C221   [Q_CAP_C0402-22UF,4V,20%,X6S,CHA]
    1  PVCCIN_CPU1        A  @S9S_MB_2U_LIB.S9S_MB_2U(SCH_1):PVCCIN_CPU1
    2  GND                B  @S9S_MB_2U_LIB.S9S_MB_2U(SCH_1):GND

Q_CAP  I25  C222   [Q_CAP_C0402-22UF,4V,20%,X6S,CHA]
    1  PVCCIN_CPU1        A  @S9S_MB_2U_LIB.S9S_MB_2U(SCH_1):PVCCIN_CPU1
    2  GND                B  @S9S_MB_2U_LIB.S9S_MB_2U(SCH_1):GND

Q_CAP  I23  C223   [Q_CAP_C0402-22UF,4V,20%,X6S,CHA]
    1  PVCCIN_CPU1        A  @S9S_MB_2U_LIB.S9S_MB_2U(SCH_1):PVCCIN_CPU1
    2  GND                B  @S9S_MB_2U_LIB.S9S_MB_2U(SCH_1):GND

Q_CAP  I15  C224   [Q_CAP_C0402-22UF,4V,20%,X6S,CHA]
    1  PVCCIN_CPU1        A  @S9S_MB_2U_LIB.S9S_MB_2U(SCH_1):PVCCIN_CPU1
    2  GND                B  @S9S_MB_2U_LIB.S9S_MB_2U(SCH_1):GND

Q_CAP  I13  C225   [Q_CAP_0805-47UF,4V,20%,X6S,CH6A]
    1  PVCCIN_CPU1        A  @S9S_MB_2U_LIB.S9S_MB_2U(SCH_1):PVCCIN_CPU1
    2  GND                B  @S9S_MB_2U_LIB.S9S_MB_2U(SCH_1):GND

Q_CAP  I31  C226   [Q_CAP_C0402-22UF,4V,20%,X6S,CHA]
    1  PVCCIN_CPU1        A  @S9S_MB_2U_LIB.S9S_MB_2U(SCH_1):PVCCIN_CPU1
    2  GND                B  @S9S_MB_2U_LIB.S9S_MB_2U(SCH_1):GND

Q_CAP  I30  C227   [Q_CAP_C0402-22UF,4V,20%,X6S,CHA]
    1  PVCCIN_CPU1        A  @S9S_MB_2U_LIB.S9S_MB_2U(SCH_1):PVCCIN_CPU1
    2  GND                B  @S9S_MB_2U_LIB.S9S_MB_2U(SCH_1):GND

Q_CAP  I28  C228   [Q_CAP_C0402-22UF,4V,20%,X6S,CHA]
    1  PVCCIN_CPU1        A  @S9S_MB_2U_LIB.S9S_MB_2U(SCH_1):PVCCIN_CPU1
    2  GND                B  @S9S_MB_2U_LIB.S9S_MB_2U(SCH_1):GND

Q_CAP  I21  C229   [Q_CAP_C0402-22UF,4V,20%,X6S,CHA]
    1  PVCCIN_CPU1        A  @S9S_MB_2U_LIB.S9S_MB_2U(SCH_1):PVCCIN_CPU1
    2  GND                B  @S9S_MB_2U_LIB.S9S_MB_2U(SCH_1):GND

Q_CAP  I18  C230   [Q_CAP_0805-47UF,4V,20%,X6S,CH6A]
    1  PVCCIN_CPU1        A  @S9S_MB_2U_LIB.S9S_MB_2U(SCH_1):PVCCIN_CPU1
    2  GND                B  @S9S_MB_2U_LIB.S9S_MB_2U(SCH_1):GND

Q_CAP  I33  C231   [Q_CAP_C0402-22UF,4V,20%,X6S,CHA]
    1  PVCCIN_CPU1        A  @S9S_MB_2U_LIB.S9S_MB_2U(SCH_1):PVCCIN_CPU1
    2  GND                B  @S9S_MB_2U_LIB.S9S_MB_2U(SCH_1):GND

Q_CAP  I32  C232   [Q_CAP_C0402-22UF,4V,20%,X6S,CHA]
    1  PVCCIN_CPU1        A  @S9S_MB_2U_LIB.S9S_MB_2U(SCH_1):PVCCIN_CPU1
    2  GND                B  @S9S_MB_2U_LIB.S9S_MB_2U(SCH_1):GND

Q_CAP  I29  C233   [Q_CAP_C0402-22UF,4V,20%,X6S,CHA]
    1  PVCCIN_CPU1        A  @S9S_MB_2U_LIB.S9S_MB_2U(SCH_1):PVCCIN_CPU1
    2  GND                B  @S9S_MB_2U_LIB.S9S_MB_2U(SCH_1):GND

Q_CAP  I22  C234   [Q_CAP_C0402-22UF,4V,20%,X6S,CHA]
    1  PVCCIN_CPU1        A  @S9S_MB_2U_LIB.S9S_MB_2U(SCH_1):PVCCIN_CPU1
    2  GND                B  @S9S_MB_2U_LIB.S9S_MB_2U(SCH_1):GND

Q_CAP  I20  C235   [Q_CAP_0805-47UF,4V,20%,X6S,CH6A]
    1  PVCCIN_CPU1        A  @S9S_MB_2U_LIB.S9S_MB_2U(SCH_1):PVCCIN_CPU1
    2  GND                B  @S9S_MB_2U_LIB.S9S_MB_2U(SCH_1):GND

Q_CAP  I52  C236   [Q_CAP_C0402-22UF,4V,20%,X6S,CHA]
    1  PVCCIN_CPU1        A  @S9S_MB_2U_LIB.S9S_MB_2U(SCH_1):PVCCIN_CPU1
    2  GND                B  @S9S_MB_2U_LIB.S9S_MB_2U(SCH_1):GND

Q_CAP  I51  C237   [Q_CAP_C0402-22UF,4V,20%,X6S,CHA]
    1  PVCCIN_CPU1        A  @S9S_MB_2U_LIB.S9S_MB_2U(SCH_1):PVCCIN_CPU1
    2  GND                B  @S9S_MB_2U_LIB.S9S_MB_2U(SCH_1):GND

Q_CAP  I49  C238   [Q_CAP_C0402-22UF,4V,20%,X6S,CHA]
    1  PVCCIN_CPU1        A  @S9S_MB_2U_LIB.S9S_MB_2U(SCH_1):PVCCIN_CPU1
    2  GND                B  @S9S_MB_2U_LIB.S9S_MB_2U(SCH_1):GND

Q_CAP  I37  C239   [Q_CAP_C0402-22UF,4V,20%,X6S,CHA]
    1  PVCCIN_CPU1        A  @S9S_MB_2U_LIB.S9S_MB_2U(SCH_1):PVCCIN_CPU1
    2  GND                B  @S9S_MB_2U_LIB.S9S_MB_2U(SCH_1):GND

Q_CAP  I35  C240   [Q_CAP_0805-47UF,4V,20%,X6S,CH6A]
    1  PVCCIN_CPU1        A  @S9S_MB_2U_LIB.S9S_MB_2U(SCH_1):PVCCIN_CPU1
    2  GND                B  @S9S_MB_2U_LIB.S9S_MB_2U(SCH_1):GND

Q_CAP  I54  C241   [Q_CAP_C0402-22UF,4V,20%,X6S,CHA]
    1  PVCCIN_CPU1        A  @S9S_MB_2U_LIB.S9S_MB_2U(SCH_1):PVCCIN_CPU1
    2  GND                B  @S9S_MB_2U_LIB.S9S_MB_2U(SCH_1):GND

Q_CAP  I53  C242   [Q_CAP_C0402-22UF,4V,20%,X6S,CHA]
    1  PVCCIN_CPU1        A  @S9S_MB_2U_LIB.S9S_MB_2U(SCH_1):PVCCIN_CPU1
    2  GND                B  @S9S_MB_2U_LIB.S9S_MB_2U(SCH_1):GND

Q_CAP  I50  C243   [Q_CAP_C0402-22UF,4V,20%,X6S,CHA]
    1  PVCCIN_CPU1        A  @S9S_MB_2U_LIB.S9S_MB_2U(SCH_1):PVCCIN_CPU1
    2  GND                B  @S9S_MB_2U_LIB.S9S_MB_2U(SCH_1):GND

Q_CAP  I38  C244   [Q_CAP_C0402-22UF,4V,20%,X6S,CHA]
    1  PVCCIN_CPU1        A  @S9S_MB_2U_LIB.S9S_MB_2U(SCH_1):PVCCIN_CPU1
    2  GND                B  @S9S_MB_2U_LIB.S9S_MB_2U(SCH_1):GND

Q_CAP  I36  C245   [Q_CAP_0805-47UF,4V,20%,X6S,CH6A]
    1  PVCCIN_CPU1        A  @S9S_MB_2U_LIB.S9S_MB_2U(SCH_1):PVCCIN_CPU1
    2  GND                B  @S9S_MB_2U_LIB.S9S_MB_2U(SCH_1):GND

Q_CAP  I59  C246   [Q_CAP_C0402-22UF,4V,20%,X6S,CHA]
    1  PVCCIN_CPU1        A  @S9S_MB_2U_LIB.S9S_MB_2U(SCH_1):PVCCIN_CPU1
    2  GND                B  @S9S_MB_2U_LIB.S9S_MB_2U(SCH_1):GND

Q_CAP  I58  C247   [Q_CAP_C0402-22UF,4V,20%,X6S,CHA]
    1  PVCCIN_CPU1        A  @S9S_MB_2U_LIB.S9S_MB_2U(SCH_1):PVCCIN_CPU1
    2  GND                B  @S9S_MB_2U_LIB.S9S_MB_2U(SCH_1):GND

Q_CAP  I55  C248   [Q_CAP_C0402-22UF,4V,20%,X6S,CHA]
    1  PVCCIN_CPU1        A  @S9S_MB_2U_LIB.S9S_MB_2U(SCH_1):PVCCIN_CPU1
    2  GND                B  @S9S_MB_2U_LIB.S9S_MB_2U(SCH_1):GND

Q_CAP  I46  C249   [Q_CAP_C0402-22UF,4V,20%,X6S,CHA]
    1  PVCCIN_CPU1        A  @S9S_MB_2U_LIB.S9S_MB_2U(SCH_1):PVCCIN_CPU1
    2  GND                B  @S9S_MB_2U_LIB.S9S_MB_2U(SCH_1):GND

Q_CAP  I41  C250   [Q_CAP_0805-47UF,4V,20%,X6S,CH6A]
    1  PVCCIN_CPU1        A  @S9S_MB_2U_LIB.S9S_MB_2U(SCH_1):PVCCIN_CPU1
    2  GND                B  @S9S_MB_2U_LIB.S9S_MB_2U(SCH_1):GND

Q_CAP  I61  C251   [Q_CAP_C0402-22UF,4V,20%,X6S,CHA]
    1  PVCCIN_CPU1        A  @S9S_MB_2U_LIB.S9S_MB_2U(SCH_1):PVCCIN_CPU1
    2  GND                B  @S9S_MB_2U_LIB.S9S_MB_2U(SCH_1):GND

Q_CAP  I60  C252   [Q_CAP_C0402-22UF,4V,20%,X6S,CHA]
    1  PVCCIN_CPU1        A  @S9S_MB_2U_LIB.S9S_MB_2U(SCH_1):PVCCIN_CPU1
    2  GND                B  @S9S_MB_2U_LIB.S9S_MB_2U(SCH_1):GND

Q_CAP  I56  C253   [Q_CAP_C0402-22UF,4V,20%,X6S,CHA]
    1  PVCCIN_CPU1        A  @S9S_MB_2U_LIB.S9S_MB_2U(SCH_1):PVCCIN_CPU1
    2  GND                B  @S9S_MB_2U_LIB.S9S_MB_2U(SCH_1):GND

Q_CAP  I47  C254   [Q_CAP_C0402-22UF,4V,20%,X6S,CHA]
    1  PVCCIN_CPU1        A  @S9S_MB_2U_LIB.S9S_MB_2U(SCH_1):PVCCIN_CPU1
    2  GND                B  @S9S_MB_2U_LIB.S9S_MB_2U(SCH_1):GND

Q_CAP  I44  C255   [Q_CAP_0805-47UF,4V,20%,X6S,CH6A]
    1  PVCCIN_CPU1        A  @S9S_MB_2U_LIB.S9S_MB_2U(SCH_1):PVCCIN_CPU1
    2  GND                B  @S9S_MB_2U_LIB.S9S_MB_2U(SCH_1):GND

Q_CAP  I63  C256   [Q_CAP_C0402-22UF,4V,20%,X6S,CHA]
    1  PVCCIN_CPU1        A  @S9S_MB_2U_LIB.S9S_MB_2U(SCH_1):PVCCIN_CPU1
    2  GND                B  @S9S_MB_2U_LIB.S9S_MB_2U(SCH_1):GND

Q_CAP  I62  C257   [Q_CAP_C0402-22UF,4V,20%,X6S,CHA]
    1  PVCCIN_CPU1        A  @S9S_MB_2U_LIB.S9S_MB_2U(SCH_1):PVCCIN_CPU1
    2  GND                B  @S9S_MB_2U_LIB.S9S_MB_2U(SCH_1):GND

Q_CAP  I57  C258   [Q_CAP_C0402-22UF,4V,20%,X6S,CHA]
    1  PVCCIN_CPU1        A  @S9S_MB_2U_LIB.S9S_MB_2U(SCH_1):PVCCIN_CPU1
    2  GND                B  @S9S_MB_2U_LIB.S9S_MB_2U(SCH_1):GND

Q_CAP  I48  C259   [Q_CAP_C0402-22UF,4V,20%,X6S,CHA]
    1  PVCCIN_CPU1        A  @S9S_MB_2U_LIB.S9S_MB_2U(SCH_1):PVCCIN_CPU1
    2  GND                B  @S9S_MB_2U_LIB.S9S_MB_2U(SCH_1):GND

Q_CAP  I45  C260   [Q_CAP_0805-47UF,4V,20%,X6S,CH6A]
    1  PVCCIN_CPU1        A  @S9S_MB_2U_LIB.S9S_MB_2U(SCH_1):PVCCIN_CPU1
    2  GND                B  @S9S_MB_2U_LIB.S9S_MB_2U(SCH_1):GND

Q_CAP  I89  C261   [Q_CAP_C0402-22UF,4V,20%,X6S,CHA]
    1  PVCCIN_CPU1        A  @S9S_MB_2U_LIB.S9S_MB_2U(SCH_1):PVCCIN_CPU1
    2  GND                B  @S9S_MB_2U_LIB.S9S_MB_2U(SCH_1):GND

Q_CAP  I88  C262   [Q_CAP_C0402-22UF,4V,20%,X6S,CHA]
    1  PVCCIN_CPU1        A  @S9S_MB_2U_LIB.S9S_MB_2U(SCH_1):PVCCIN_CPU1
    2  GND                B  @S9S_MB_2U_LIB.S9S_MB_2U(SCH_1):GND

Q_CAP  I84  C263   [Q_CAP_C0402-22UF,4V,20%,X6S,CHA]
    1  PVCCIN_CPU1        A  @S9S_MB_2U_LIB.S9S_MB_2U(SCH_1):PVCCIN_CPU1
    2  GND                B  @S9S_MB_2U_LIB.S9S_MB_2U(SCH_1):GND

Q_CAP  I76  C264   [Q_CAP_C0402-22UF,4V,20%,X6S,CHA]
    1  PVCCIN_CPU1        A  @S9S_MB_2U_LIB.S9S_MB_2U(SCH_1):PVCCIN_CPU1
    2  GND                B  @S9S_MB_2U_LIB.S9S_MB_2U(SCH_1):GND

Q_CAP  I72  C265   [Q_CAP_0805-47UF,4V,20%,X6S,CH6A]
    1  PVCCIN_CPU1        A  @S9S_MB_2U_LIB.S9S_MB_2U(SCH_1):PVCCIN_CPU1
    2  GND                B  @S9S_MB_2U_LIB.S9S_MB_2U(SCH_1):GND

Q_CAP  I92  C266   [Q_CAP_C0402-22UF,4V,20%,X6S,CHA]
    1  PVCCIN_CPU1        A  @S9S_MB_2U_LIB.S9S_MB_2U(SCH_1):PVCCIN_CPU1
    2  GND                B  @S9S_MB_2U_LIB.S9S_MB_2U(SCH_1):GND

Q_CAP  I90  C267   [Q_CAP_C0402-22UF,4V,20%,X6S,CHA]
    1  PVCCIN_CPU1        A  @S9S_MB_2U_LIB.S9S_MB_2U(SCH_1):PVCCIN_CPU1
    2  GND                B  @S9S_MB_2U_LIB.S9S_MB_2U(SCH_1):GND

Q_CAP  I86  C268   [Q_CAP_C0402-22UF,4V,20%,X6S,CHA]
    1  PVCCIN_CPU1        A  @S9S_MB_2U_LIB.S9S_MB_2U(SCH_1):PVCCIN_CPU1
    2  GND                B  @S9S_MB_2U_LIB.S9S_MB_2U(SCH_1):GND

Q_CAP  I78  C269   [Q_CAP_C0402-22UF,4V,20%,X6S,CHA]
    1  PVCCIN_CPU1        A  @S9S_MB_2U_LIB.S9S_MB_2U(SCH_1):PVCCIN_CPU1
    2  GND                B  @S9S_MB_2U_LIB.S9S_MB_2U(SCH_1):GND

Q_CAP  I75  C270   [Q_CAP_0805-47UF,4V,20%,X6S,CH6A]
    1  PVCCIN_CPU1        A  @S9S_MB_2U_LIB.S9S_MB_2U(SCH_1):PVCCIN_CPU1
    2  GND                B  @S9S_MB_2U_LIB.S9S_MB_2U(SCH_1):GND

Q_CAP  I98  C271   [Q_CAP_C0402-22UF,4V,20%,X6S,CHA]
    1  PVCCIN_CPU1        A  @S9S_MB_2U_LIB.S9S_MB_2U(SCH_1):PVCCIN_CPU1
    2  GND                B  @S9S_MB_2U_LIB.S9S_MB_2U(SCH_1):GND

Q_CAP  I96  C272   [Q_CAP_C0402-22UF,4V,20%,X6S,CHA]
    1  PVCCIN_CPU1        A  @S9S_MB_2U_LIB.S9S_MB_2U(SCH_1):PVCCIN_CPU1
    2  GND                B  @S9S_MB_2U_LIB.S9S_MB_2U(SCH_1):GND

Q_CAP  I93  C273   [Q_CAP_C0402-22UF,4V,20%,X6S,CHA]
    1  PVCCIN_CPU1        A  @S9S_MB_2U_LIB.S9S_MB_2U(SCH_1):PVCCIN_CPU1
    2  GND                B  @S9S_MB_2U_LIB.S9S_MB_2U(SCH_1):GND

Q_CAP  I81  C274   [Q_CAP_C0402-22UF,4V,20%,X6S,CHA]
    1  PVCCIN_CPU1        A  @S9S_MB_2U_LIB.S9S_MB_2U(SCH_1):PVCCIN_CPU1
    2  GND                B  @S9S_MB_2U_LIB.S9S_MB_2U(SCH_1):GND

Q_CAP  I100  C275   [Q_CAP_C0402-22UF,4V,20%,X6S,CHA]
    1  PVCCIN_CPU1        A  @S9S_MB_2U_LIB.S9S_MB_2U(SCH_1):PVCCIN_CPU1
    2  GND                B  @S9S_MB_2U_LIB.S9S_MB_2U(SCH_1):GND

Q_CAP  I99  C276   [Q_CAP_C0402-22UF,4V,20%,X6S,CHA]
    1  PVCCIN_CPU1        A  @S9S_MB_2U_LIB.S9S_MB_2U(SCH_1):PVCCIN_CPU1
    2  GND                B  @S9S_MB_2U_LIB.S9S_MB_2U(SCH_1):GND

Q_CAP  I95  C277   [Q_CAP_C0402-22UF,4V,20%,X6S,CHA]
    1  PVCCIN_CPU1        A  @S9S_MB_2U_LIB.S9S_MB_2U(SCH_1):PVCCIN_CPU1
    2  GND                B  @S9S_MB_2U_LIB.S9S_MB_2U(SCH_1):GND

Q_CAP  I83  C278   [Q_CAP_C0402-22UF,4V,20%,X6S,CHA]
    1  PVCCIN_CPU1        A  @S9S_MB_2U_LIB.S9S_MB_2U(SCH_1):PVCCIN_CPU1
    2  GND                B  @S9S_MB_2U_LIB.S9S_MB_2U(SCH_1):GND

Q_CAP  I112  C279   [Q_CAP_C0402-22UF,4V,20%,X6S,CHA]
    1  PVCCIN_CPU1        A  @S9S_MB_2U_LIB.S9S_MB_2U(SCH_1):PVCCIN_CPU1
    2  GND                B  @S9S_MB_2U_LIB.S9S_MB_2U(SCH_1):GND

Q_CAP  I111  C280   [Q_CAP_C0402-22UF,4V,20%,X6S,CHA]
    1  PVCCIN_CPU1        A  @S9S_MB_2U_LIB.S9S_MB_2U(SCH_1):PVCCIN_CPU1
    2  GND                B  @S9S_MB_2U_LIB.S9S_MB_2U(SCH_1):GND

Q_CAP  I109  C281   [Q_CAP_C0402-22UF,4V,20%,X6S,CHA]
    1  PVCCIN_CPU1        A  @S9S_MB_2U_LIB.S9S_MB_2U(SCH_1):PVCCIN_CPU1
    2  GND                B  @S9S_MB_2U_LIB.S9S_MB_2U(SCH_1):GND

Q_CAP  I103  C282   [Q_CAP_C0402-22UF,4V,20%,X6S,CHA]
    1  PVCCIN_CPU1        A  @S9S_MB_2U_LIB.S9S_MB_2U(SCH_1):PVCCIN_CPU1
    2  GND                B  @S9S_MB_2U_LIB.S9S_MB_2U(SCH_1):GND

Q_CAP  I114  C283   [Q_CAP_C0402-22UF,4V,20%,X6S,CHA]
    1  PVCCIN_CPU1        A  @S9S_MB_2U_LIB.S9S_MB_2U(SCH_1):PVCCIN_CPU1
    2  GND                B  @S9S_MB_2U_LIB.S9S_MB_2U(SCH_1):GND

Q_CAP  I113  C284   [Q_CAP_C0402-22UF,4V,20%,X6S,CHA]
    1  PVCCIN_CPU1        A  @S9S_MB_2U_LIB.S9S_MB_2U(SCH_1):PVCCIN_CPU1
    2  GND                B  @S9S_MB_2U_LIB.S9S_MB_2U(SCH_1):GND

Q_CAP  I110  C285   [Q_CAP_C0402-22UF,4V,20%,X6S,CHA]
    1  PVCCIN_CPU1        A  @S9S_MB_2U_LIB.S9S_MB_2U(SCH_1):PVCCIN_CPU1
    2  GND                B  @S9S_MB_2U_LIB.S9S_MB_2U(SCH_1):GND

Q_CAP  I104  C286   [Q_CAP_C0402-22UF,4V,20%,X6S,CHA]
    1  PVCCIN_CPU1        A  @S9S_MB_2U_LIB.S9S_MB_2U(SCH_1):PVCCIN_CPU1
    2  GND                B  @S9S_MB_2U_LIB.S9S_MB_2U(SCH_1):GND

Q_CAP  I120  C287   [Q_CAP_C0402-22UF,4V,20%,X6S,CHA]
    1  PVCCIN_CPU1        A  @S9S_MB_2U_LIB.S9S_MB_2U(SCH_1):PVCCIN_CPU1
    2  GND                B  @S9S_MB_2U_LIB.S9S_MB_2U(SCH_1):GND

Q_CAP  I118  C288   [Q_CAP_C0402-22UF,4V,20%,X6S,CHA]
    1  PVCCIN_CPU1        A  @S9S_MB_2U_LIB.S9S_MB_2U(SCH_1):PVCCIN_CPU1
    2  GND                B  @S9S_MB_2U_LIB.S9S_MB_2U(SCH_1):GND

Q_CAP  I115  C289   [Q_CAP_C0402-22UF,4V,20%,X6S,CHA]
    1  PVCCIN_CPU1        A  @S9S_MB_2U_LIB.S9S_MB_2U(SCH_1):PVCCIN_CPU1
    2  GND                B  @S9S_MB_2U_LIB.S9S_MB_2U(SCH_1):GND

Q_CAP  I106  C290   [Q_CAP_C0402-22UF,4V,20%,X6S,CHA]
    1  PVCCIN_CPU1        A  @S9S_MB_2U_LIB.S9S_MB_2U(SCH_1):PVCCIN_CPU1
    2  GND                B  @S9S_MB_2U_LIB.S9S_MB_2U(SCH_1):GND

Q_CAP  I121  C291   [Q_CAP_C0402-22UF,4V,20%,X6S,CHA]
    1  PVCCIN_CPU1        A  @S9S_MB_2U_LIB.S9S_MB_2U(SCH_1):PVCCIN_CPU1
    2  GND                B  @S9S_MB_2U_LIB.S9S_MB_2U(SCH_1):GND

Q_CAP  I119  C292   [Q_CAP_C0402-22UF,4V,20%,X6S,CHA]
    1  PVCCIN_CPU1        A  @S9S_MB_2U_LIB.S9S_MB_2U(SCH_1):PVCCIN_CPU1
    2  GND                B  @S9S_MB_2U_LIB.S9S_MB_2U(SCH_1):GND

Q_CAP  I116  C293   [Q_CAP_C0402-22UF,4V,20%,X6S,CHA]
    1  PVCCIN_CPU1        A  @S9S_MB_2U_LIB.S9S_MB_2U(SCH_1):PVCCIN_CPU1
    2  GND                B  @S9S_MB_2U_LIB.S9S_MB_2U(SCH_1):GND

Q_CAP  I107  C294   [Q_CAP_C0402-22UF,4V,20%,X6S,CHA]
    1  PVCCIN_CPU1        A  @S9S_MB_2U_LIB.S9S_MB_2U(SCH_1):PVCCIN_CPU1
    2  GND                B  @S9S_MB_2U_LIB.S9S_MB_2U(SCH_1):GND

Q_CAP  I123  C295   [Q_CAP_C0402-22UF,4V,20%,X6S,CHA]
    1  PVCCIN_CPU1        A  @S9S_MB_2U_LIB.S9S_MB_2U(SCH_1):PVCCIN_CPU1
    2  GND                B  @S9S_MB_2U_LIB.S9S_MB_2U(SCH_1):GND

Q_CAP  I122  C296   [Q_CAP_C0402-22UF,4V,20%,X6S,CHA]
    1  PVCCIN_CPU1        A  @S9S_MB_2U_LIB.S9S_MB_2U(SCH_1):PVCCIN_CPU1
    2  GND                B  @S9S_MB_2U_LIB.S9S_MB_2U(SCH_1):GND

Q_CAP  I117  C297   [Q_CAP_C0402-22UF,4V,20%,X6S,CHA]
    1  PVCCIN_CPU1        A  @S9S_MB_2U_LIB.S9S_MB_2U(SCH_1):PVCCIN_CPU1
    2  GND                B  @S9S_MB_2U_LIB.S9S_MB_2U(SCH_1):GND

Q_CAP  I108  C298   [Q_CAP_C0402-22UF,4V,20%,X6S,CHA]
    1  PVCCIN_CPU1        A  @S9S_MB_2U_LIB.S9S_MB_2U(SCH_1):PVCCIN_CPU1
    2  GND                B  @S9S_MB_2U_LIB.S9S_MB_2U(SCH_1):GND

Q_CAP  I132  C299   [Q_CAP_C0402-22UF,4V,20%,X6S,CHA]
    1  PVCCIN_CPU1        A  @S9S_MB_2U_LIB.S9S_MB_2U(SCH_1):PVCCIN_CPU1
    2  GND                B  @S9S_MB_2U_LIB.S9S_MB_2U(SCH_1):GND

Q_CAP  I131  C300   [Q_CAP_C0402-22UF,4V,20%,X6S,CHA]
    1  PVCCIN_CPU1        A  @S9S_MB_2U_LIB.S9S_MB_2U(SCH_1):PVCCIN_CPU1
    2  GND                B  @S9S_MB_2U_LIB.S9S_MB_2U(SCH_1):GND

Q_CAP  I129  C301   [Q_CAP_C0402-22UF,4V,20%,X6S,CHA]
    1  PVCCIN_CPU1        A  @S9S_MB_2U_LIB.S9S_MB_2U(SCH_1):PVCCIN_CPU1
    2  GND                B  @S9S_MB_2U_LIB.S9S_MB_2U(SCH_1):GND

Q_CAP  I125  C302   [Q_CAP_C0402-22UF,4V,20%,X6S,CHA]
    1  PVCCIN_CPU1        A  @S9S_MB_2U_LIB.S9S_MB_2U(SCH_1):PVCCIN_CPU1
    2  GND                B  @S9S_MB_2U_LIB.S9S_MB_2U(SCH_1):GND

Q_CAP  I134  C303   [Q_CAP_C0402-22UF,4V,20%,X6S,CHA]
    1  PVCCIN_CPU1        A  @S9S_MB_2U_LIB.S9S_MB_2U(SCH_1):PVCCIN_CPU1
    2  GND                B  @S9S_MB_2U_LIB.S9S_MB_2U(SCH_1):GND

Q_CAP  I133  C304   [Q_CAP_C0402-22UF,4V,20%,X6S,CHA]
    1  PVCCIN_CPU1        A  @S9S_MB_2U_LIB.S9S_MB_2U(SCH_1):PVCCIN_CPU1
    2  GND                B  @S9S_MB_2U_LIB.S9S_MB_2U(SCH_1):GND

Q_CAP  I130  C305   [Q_CAP_C0402-22UF,4V,20%,X6S,CHA]
    1  PVCCIN_CPU1        A  @S9S_MB_2U_LIB.S9S_MB_2U(SCH_1):PVCCIN_CPU1
    2  GND                B  @S9S_MB_2U_LIB.S9S_MB_2U(SCH_1):GND

Q_CAP  I126  C306   [Q_CAP_C0402-22UF,4V,20%,X6S,CHA]
    1  PVCCIN_CPU1        A  @S9S_MB_2U_LIB.S9S_MB_2U(SCH_1):PVCCIN_CPU1
    2  GND                B  @S9S_MB_2U_LIB.S9S_MB_2U(SCH_1):GND

Q_CAP  I140  C307   [Q_CAP_C0402-22UF,4V,20%,X6S,CHA]
    1  PVCCIN_CPU1        A  @S9S_MB_2U_LIB.S9S_MB_2U(SCH_1):PVCCIN_CPU1
    2  GND                B  @S9S_MB_2U_LIB.S9S_MB_2U(SCH_1):GND

Q_CAP  I138  C308   [Q_CAP_C0402-22UF,4V,20%,X6S,CHA]
    1  PVCCIN_CPU1        A  @S9S_MB_2U_LIB.S9S_MB_2U(SCH_1):PVCCIN_CPU1
    2  GND                B  @S9S_MB_2U_LIB.S9S_MB_2U(SCH_1):GND

Q_CAP  I136  C309   [Q_CAP_C0402-22UF,4V,20%,X6S,CHA]
    1  PVCCIN_CPU1        A  @S9S_MB_2U_LIB.S9S_MB_2U(SCH_1):PVCCIN_CPU1
    2  GND                B  @S9S_MB_2U_LIB.S9S_MB_2U(SCH_1):GND

Q_CAP  I148  C310   [Q_CAP_C0402-22UF,4V,20%,X6S,CHA]
    1  PVNN_MAIN_CPU1      A  @S9S_MB_2U_LIB.S9S_MB_2U(SCH_1):PVNN_MAIN_CPU1
    2  GND                B  @S9S_MB_2U_LIB.S9S_MB_2U(SCH_1):GND

Q_CAP  I35  C311   [Q_CAP_C0805-100UF,4V,20%,X6S,CA]
    1  PVCCIN_CPU1        A  @S9S_MB_2U_LIB.S9S_MB_2U(SCH_1):PVCCIN_CPU1
    2  GND                B  @S9S_MB_2U_LIB.S9S_MB_2U(SCH_1):GND

Q_CAP  I32  C312   [Q_CAP_C0805-100UF,4V,20%,X6S,CA]
    1  PVCCIN_CPU1        A  @S9S_MB_2U_LIB.S9S_MB_2U(SCH_1):PVCCIN_CPU1
    2  GND                B  @S9S_MB_2U_LIB.S9S_MB_2U(SCH_1):GND

Q_CAP  I128  C313   [Q_CAP_C0805-100UF,4V,20%,X6S,CA]
    1  PVCCIN_CPU1        A  @S9S_MB_2U_LIB.S9S_MB_2U(SCH_1):PVCCIN_CPU1
    2  GND                B  @S9S_MB_2U_LIB.S9S_MB_2U(SCH_1):GND

Q_CAP  I40  C314   [Q_CAP_C0805-100UF,4V,20%,X6S,CA]
    1  PVCCIN_CPU1        A  @S9S_MB_2U_LIB.S9S_MB_2U(SCH_1):PVCCIN_CPU1
    2  GND                B  @S9S_MB_2U_LIB.S9S_MB_2U(SCH_1):GND

Q_CAP  I37  C315   [Q_CAP_C0805-100UF,4V,20%,X6S,CA]
    1  PVCCIN_CPU1        A  @S9S_MB_2U_LIB.S9S_MB_2U(SCH_1):PVCCIN_CPU1
    2  GND                B  @S9S_MB_2U_LIB.S9S_MB_2U(SCH_1):GND

Q_CAP  I129  C316   [Q_CAP_C0805-100UF,4V,20%,X6S,CA]
    1  PVCCIN_CPU1        A  @S9S_MB_2U_LIB.S9S_MB_2U(SCH_1):PVCCIN_CPU1
    2  GND                B  @S9S_MB_2U_LIB.S9S_MB_2U(SCH_1):GND

Q_CAP  I41  C317   [Q_CAP_C0805-100UF,4V,20%,X6S,CA]
    1  PVCCIN_CPU1        A  @S9S_MB_2U_LIB.S9S_MB_2U(SCH_1):PVCCIN_CPU1
    2  GND                B  @S9S_MB_2U_LIB.S9S_MB_2U(SCH_1):GND

Q_CAP  I39  C318   [Q_CAP_C0805-100UF,4V,20%,X6S,CA]
    1  PVCCIN_CPU1        A  @S9S_MB_2U_LIB.S9S_MB_2U(SCH_1):PVCCIN_CPU1
    2  GND                B  @S9S_MB_2U_LIB.S9S_MB_2U(SCH_1):GND

Q_CAP  I361  C319   [Q_CAP_C0805-22UF,16V,20%,X6S,CA]
    1  P12V_OCP_SFF       A  @S9S_MB_2U_LIB.S9S_MB_2U(SCH_1):P12V_OCP_SFF
    2  GND                B  @S9S_MB_2U_LIB.S9S_MB_2U(SCH_1):GND

Q_CAP  I59  C320   [Q_CAP_C0805-100UF,4V,20%,X6S,CA]
    1  PVCCIN_CPU1        A  @S9S_MB_2U_LIB.S9S_MB_2U(SCH_1):PVCCIN_CPU1
    2  GND                B  @S9S_MB_2U_LIB.S9S_MB_2U(SCH_1):GND

Q_CAP  I56  C321   [Q_CAP_C0805-100UF,4V,20%,X6S,CA]
    1  PVCCIN_CPU1        A  @S9S_MB_2U_LIB.S9S_MB_2U(SCH_1):PVCCIN_CPU1
    2  GND                B  @S9S_MB_2U_LIB.S9S_MB_2U(SCH_1):GND

Q_CAP  I115  C322   [Q_CAP_C0805-100UF,4V,20%,X6S,CA]
    1  PVCCIN_CPU1        A  @S9S_MB_2U_LIB.S9S_MB_2U(SCH_1):PVCCIN_CPU1
    2  GND                B  @S9S_MB_2U_LIB.S9S_MB_2U(SCH_1):GND

Q_CAP  I60  C323   [Q_CAP_C0805-100UF,4V,20%,X6S,CA]
    1  PVCCIN_CPU1        A  @S9S_MB_2U_LIB.S9S_MB_2U(SCH_1):PVCCIN_CPU1
    2  GND                B  @S9S_MB_2U_LIB.S9S_MB_2U(SCH_1):GND

Q_CAP  I58  C324   [Q_CAP_C0805-100UF,4V,20%,X6S,CA]
    1  PVCCIN_CPU1        A  @S9S_MB_2U_LIB.S9S_MB_2U(SCH_1):PVCCIN_CPU1
    2  GND                B  @S9S_MB_2U_LIB.S9S_MB_2U(SCH_1):GND

Q_CAP  I114  C325   [Q_CAP_C0805-100UF,4V,20%,X6S,CA]
    1  PVCCIN_CPU1        A  @S9S_MB_2U_LIB.S9S_MB_2U(SCH_1):PVCCIN_CPU1
    2  GND                B  @S9S_MB_2U_LIB.S9S_MB_2U(SCH_1):GND

Q_CAP  I67  C326   [Q_CAP_C0805-100UF,4V,20%,X6S,CA]
    1  PVCCIN_CPU1        A  @S9S_MB_2U_LIB.S9S_MB_2U(SCH_1):PVCCIN_CPU1
    2  GND                B  @S9S_MB_2U_LIB.S9S_MB_2U(SCH_1):GND

Q_CAP  I62  C327   [Q_CAP_C0805-100UF,4V,20%,X6S,CA]
    1  PVCCIN_CPU1        A  @S9S_MB_2U_LIB.S9S_MB_2U(SCH_1):PVCCIN_CPU1
    2  GND                B  @S9S_MB_2U_LIB.S9S_MB_2U(SCH_1):GND

Q_CAP  I112  C328   [Q_CAP_C0805-100UF,4V,20%,X6S,CA]
    1  PVCCIN_CPU1        A  @S9S_MB_2U_LIB.S9S_MB_2U(SCH_1):PVCCIN_CPU1
    2  GND                B  @S9S_MB_2U_LIB.S9S_MB_2U(SCH_1):GND

Q_CAP  I68  C329   [Q_CAP_C0805-100UF,4V,20%,X6S,CA]
    1  PVCCIN_CPU1        A  @S9S_MB_2U_LIB.S9S_MB_2U(SCH_1):PVCCIN_CPU1
    2  GND                B  @S9S_MB_2U_LIB.S9S_MB_2U(SCH_1):GND

Q_CAP  I65  C330   [Q_CAP_C0805-100UF,4V,20%,X6S,CA]
    1  PVCCIN_CPU1        A  @S9S_MB_2U_LIB.S9S_MB_2U(SCH_1):PVCCIN_CPU1
    2  GND                B  @S9S_MB_2U_LIB.S9S_MB_2U(SCH_1):GND

Q_CAP  I360  C331   [Q_CAP_C0805-22UF,16V,20%,X6S,CA]
    1  P12V_OCP_SFF       A  @S9S_MB_2U_LIB.S9S_MB_2U(SCH_1):P12V_OCP_SFF
    2  GND                B  @S9S_MB_2U_LIB.S9S_MB_2U(SCH_1):GND

Q_CAP  I69  C332   [Q_CAP_C0805-100UF,4V,20%,X6S,CA]
    1  PVCCIN_CPU1        A  @S9S_MB_2U_LIB.S9S_MB_2U(SCH_1):PVCCIN_CPU1
    2  GND                B  @S9S_MB_2U_LIB.S9S_MB_2U(SCH_1):GND

Q_CAP  I66  C333   [Q_CAP_C0805-100UF,4V,20%,X6S,CA]
    1  PVCCIN_CPU1        A  @S9S_MB_2U_LIB.S9S_MB_2U(SCH_1):PVCCIN_CPU1
    2  GND                B  @S9S_MB_2U_LIB.S9S_MB_2U(SCH_1):GND

Q_CAP  I80  C335   [Q_CAP_C0805-100UF,4V,20%,X6S,CA]
    1  PVCCIN_CPU1        A  @S9S_MB_2U_LIB.S9S_MB_2U(SCH_1):PVCCIN_CPU1
    2  GND                B  @S9S_MB_2U_LIB.S9S_MB_2U(SCH_1):GND

Q_CAP  I76  C336   [Q_CAP_C0805-100UF,4V,20%,X6S,CA]
    1  PVCCIN_CPU1        A  @S9S_MB_2U_LIB.S9S_MB_2U(SCH_1):PVCCIN_CPU1
    2  GND                B  @S9S_MB_2U_LIB.S9S_MB_2U(SCH_1):GND

Q_CAP  I121  C337   [Q_CAP_C0603-47UF,2.5V,20%,X6S,A]
    1  PVCCIN_CPU1        A  @S9S_MB_2U_LIB.S9S_MB_2U(SCH_1):PVCCIN_CPU1
    2  GND                B  @S9S_MB_2U_LIB.S9S_MB_2U(SCH_1):GND

Q_CAP  I82  C338   [Q_CAP_C0805-100UF,4V,20%,X6S,CA]
    1  PVCCIN_CPU1        A  @S9S_MB_2U_LIB.S9S_MB_2U(SCH_1):PVCCIN_CPU1
    2  GND                B  @S9S_MB_2U_LIB.S9S_MB_2U(SCH_1):GND

Q_CAP  I79  C339   [Q_CAP_C0805-100UF,4V,20%,X6S,CA]
    1  PVCCIN_CPU1        A  @S9S_MB_2U_LIB.S9S_MB_2U(SCH_1):PVCCIN_CPU1
    2  GND                B  @S9S_MB_2U_LIB.S9S_MB_2U(SCH_1):GND

Q_CAP  I120  C340   [Q_CAP_C0603-47UF,2.5V,20%,X6S,A]
    1  PVCCIN_CPU1        A  @S9S_MB_2U_LIB.S9S_MB_2U(SCH_1):PVCCIN_CPU1
    2  GND                B  @S9S_MB_2U_LIB.S9S_MB_2U(SCH_1):GND

Q_CAP  I125  C341   [Q_CAP_C0805-100UF,4V,20%,X6S,CA]
    1  PVCCIN_CPU1        A  @S9S_MB_2U_LIB.S9S_MB_2U(SCH_1):PVCCIN_CPU1
    2  GND                B  @S9S_MB_2U_LIB.S9S_MB_2U(SCH_1):GND

Q_CAP  I109  C342   [Q_CAP_C0805-100UF,4V,20%,X6S,CA]
    1  PVCCIN_CPU1        A  @S9S_MB_2U_LIB.S9S_MB_2U(SCH_1):PVCCIN_CPU1
    2  GND                B  @S9S_MB_2U_LIB.S9S_MB_2U(SCH_1):GND

Q_CAP  I124  C343   [Q_CAP_C0805-100UF,4V,20%,X6S,CA]
    1  PVCCIN_CPU1        A  @S9S_MB_2U_LIB.S9S_MB_2U(SCH_1):PVCCIN_CPU1
    2  GND                B  @S9S_MB_2U_LIB.S9S_MB_2U(SCH_1):GND

Q_CAP  I110  C344   [Q_CAP_C0805-100UF,4V,20%,X6S,CA]
    1  PVCCIN_CPU1        A  @S9S_MB_2U_LIB.S9S_MB_2U(SCH_1):PVCCIN_CPU1
    2  GND                B  @S9S_MB_2U_LIB.S9S_MB_2U(SCH_1):GND

Q_CAP  I123  C345   [Q_CAP_C0805-100UF,4V,20%,X6S,CA]
    1  PVCCIN_CPU1        A  @S9S_MB_2U_LIB.S9S_MB_2U(SCH_1):PVCCIN_CPU1
    2  GND                B  @S9S_MB_2U_LIB.S9S_MB_2U(SCH_1):GND

Q_CAP  I111  C346   [Q_CAP_C0805-100UF,4V,20%,X6S,CA]
    1  PVCCIN_CPU1        A  @S9S_MB_2U_LIB.S9S_MB_2U(SCH_1):PVCCIN_CPU1
    2  GND                B  @S9S_MB_2U_LIB.S9S_MB_2U(SCH_1):GND

Q_CAP  I122  C347   [Q_CAP_C0805-100UF,4V,20%,X6S,CA]
    1  PVCCIN_CPU1        A  @S9S_MB_2U_LIB.S9S_MB_2U(SCH_1):PVCCIN_CPU1
    2  GND                B  @S9S_MB_2U_LIB.S9S_MB_2U(SCH_1):GND

Q_CAP  I119  C348   [Q_CAP_C0805-100UF,4V,20%,X6S,CA]
    1  PVCCIN_CPU1        A  @S9S_MB_2U_LIB.S9S_MB_2U(SCH_1):PVCCIN_CPU1
    2  GND                B  @S9S_MB_2U_LIB.S9S_MB_2U(SCH_1):GND

Q_CAP  I124  C349   [Q_CAP_C0805-100UF,4V,20%,X6S,CA]
    1  PVCCIN_CPU1        A  @S9S_MB_2U_LIB.S9S_MB_2U(SCH_1):PVCCIN_CPU1
    2  GND                B  @S9S_MB_2U_LIB.S9S_MB_2U(SCH_1):GND

Q_CAP  I118  C350   [Q_CAP_C0805-100UF,4V,20%,X6S,CA]
    1  PVCCIN_CPU1        A  @S9S_MB_2U_LIB.S9S_MB_2U(SCH_1):PVCCIN_CPU1
    2  GND                B  @S9S_MB_2U_LIB.S9S_MB_2U(SCH_1):GND

Q_CAP  I126  C351   [Q_CAP_C0805-100UF,4V,20%,X6S,CA]
    1  PVCCIN_CPU1        A  @S9S_MB_2U_LIB.S9S_MB_2U(SCH_1):PVCCIN_CPU1
    2  GND                B  @S9S_MB_2U_LIB.S9S_MB_2U(SCH_1):GND

Q_CAP  I117  C352   [Q_CAP_C0805-100UF,4V,20%,X6S,CA]
    1  PVCCIN_CPU1        A  @S9S_MB_2U_LIB.S9S_MB_2U(SCH_1):PVCCIN_CPU1
    2  GND                B  @S9S_MB_2U_LIB.S9S_MB_2U(SCH_1):GND

Q_CAP  I125  C353   [Q_CAP_C0805-100UF,4V,20%,X6S,CA]
    1  PVCCIN_CPU1        A  @S9S_MB_2U_LIB.S9S_MB_2U(SCH_1):PVCCIN_CPU1
    2  GND                B  @S9S_MB_2U_LIB.S9S_MB_2U(SCH_1):GND

Q_CAP  I116  C354   [Q_CAP_C0805-100UF,4V,20%,X6S,CA]
    1  PVCCIN_CPU1        A  @S9S_MB_2U_LIB.S9S_MB_2U(SCH_1):PVCCIN_CPU1
    2  GND                B  @S9S_MB_2U_LIB.S9S_MB_2U(SCH_1):GND

Q_CAP  I22  C355   [Q_CAP_C0805-100UF,4V,20%,X6S,CA]
    1  PVCCIN_CPU0        A  @S9S_MB_2U_LIB.S9S_MB_2U(SCH_1):PVCCIN_CPU0
    2  GND                B  @S9S_MB_2U_LIB.S9S_MB_2U(SCH_1):GND

Q_CAP  I20  C356   [Q_CAP_C0805-100UF,4V,20%,X6S,CA]
    1  PVCCIN_CPU0        A  @S9S_MB_2U_LIB.S9S_MB_2U(SCH_1):PVCCIN_CPU0
    2  GND                B  @S9S_MB_2U_LIB.S9S_MB_2U(SCH_1):GND

Q_CAP  I237  C357   [Q_CAP_C0805-100UF,4V,20%,X6S,CA]
    1  PVCCIN_CPU0        A  @S9S_MB_2U_LIB.S9S_MB_2U(SCH_1):PVCCIN_CPU0
    2  GND                B  @S9S_MB_2U_LIB.S9S_MB_2U(SCH_1):GND

Q_CAP  I26  C358   [Q_CAP_C0805-100UF,4V,20%,X6S,CA]
    1  PVCCIN_CPU0        A  @S9S_MB_2U_LIB.S9S_MB_2U(SCH_1):PVCCIN_CPU0
    2  GND                B  @S9S_MB_2U_LIB.S9S_MB_2U(SCH_1):GND

Q_CAP  I25  C359   [Q_CAP_C0805-100UF,4V,20%,X6S,CA]
    1  PVCCIN_CPU0        A  @S9S_MB_2U_LIB.S9S_MB_2U(SCH_1):PVCCIN_CPU0
    2  GND                B  @S9S_MB_2U_LIB.S9S_MB_2U(SCH_1):GND

Q_CAP  I234  C360   [Q_CAP_C0805-100UF,4V,20%,X6S,CA]
    1  PVCCIN_CPU0        A  @S9S_MB_2U_LIB.S9S_MB_2U(SCH_1):PVCCIN_CPU0
    2  GND                B  @S9S_MB_2U_LIB.S9S_MB_2U(SCH_1):GND

Q_CAP  I28  C361   [Q_CAP_C0805-100UF,4V,20%,X6S,CA]
    1  PVCCIN_CPU0        A  @S9S_MB_2U_LIB.S9S_MB_2U(SCH_1):PVCCIN_CPU0
    2  GND                B  @S9S_MB_2U_LIB.S9S_MB_2U(SCH_1):GND

Q_CAP  I27  C362   [Q_CAP_C0805-100UF,4V,20%,X6S,CA]
    1  PVCCIN_CPU0        A  @S9S_MB_2U_LIB.S9S_MB_2U(SCH_1):PVCCIN_CPU0
    2  GND                B  @S9S_MB_2U_LIB.S9S_MB_2U(SCH_1):GND

Q_CAP  I232  C363   [Q_CAP_C0805-100UF,4V,20%,X6S,CA]
    1  PVCCIN_CPU0        A  @S9S_MB_2U_LIB.S9S_MB_2U(SCH_1):PVCCIN_CPU0
    2  GND                B  @S9S_MB_2U_LIB.S9S_MB_2U(SCH_1):GND

Q_CAP  I43  C364   [Q_CAP_C0805-100UF,4V,20%,X6S,CA]
    1  PVCCIN_CPU0        A  @S9S_MB_2U_LIB.S9S_MB_2U(SCH_1):PVCCIN_CPU0
    2  GND                B  @S9S_MB_2U_LIB.S9S_MB_2U(SCH_1):GND

Q_CAP  I42  C365   [Q_CAP_C0805-100UF,4V,20%,X6S,CA]
    1  PVCCIN_CPU0        A  @S9S_MB_2U_LIB.S9S_MB_2U(SCH_1):PVCCIN_CPU0
    2  GND                B  @S9S_MB_2U_LIB.S9S_MB_2U(SCH_1):GND

Q_CAP  I70  C366   [Q_CAP_C0805-100UF,4V,20%,X6S,CA]
    1  PVCCIN_CPU0        A  @S9S_MB_2U_LIB.S9S_MB_2U(SCH_1):PVCCIN_CPU0
    2  GND                B  @S9S_MB_2U_LIB.S9S_MB_2U(SCH_1):GND

Q_CAP  I45  C367   [Q_CAP_C0805-100UF,4V,20%,X6S,CA]
    1  PVCCIN_CPU0        A  @S9S_MB_2U_LIB.S9S_MB_2U(SCH_1):PVCCIN_CPU0
    2  GND                B  @S9S_MB_2U_LIB.S9S_MB_2U(SCH_1):GND

Q_CAP  I44  C368   [Q_CAP_C0805-100UF,4V,20%,X6S,CA]
    1  PVCCIN_CPU0        A  @S9S_MB_2U_LIB.S9S_MB_2U(SCH_1):PVCCIN_CPU0
    2  GND                B  @S9S_MB_2U_LIB.S9S_MB_2U(SCH_1):GND

Q_CAP  I82  C369   [Q_CAP_C0805-100UF,4V,20%,X6S,CA]
    1  PVCCIN_CPU0        A  @S9S_MB_2U_LIB.S9S_MB_2U(SCH_1):PVCCIN_CPU0
    2  GND                B  @S9S_MB_2U_LIB.S9S_MB_2U(SCH_1):GND

Q_CAP  I50  C370   [Q_CAP_C0805-100UF,4V,20%,X6S,CA]
    1  PVCCIN_CPU0        A  @S9S_MB_2U_LIB.S9S_MB_2U(SCH_1):PVCCIN_CPU0
    2  GND                B  @S9S_MB_2U_LIB.S9S_MB_2U(SCH_1):GND

Q_CAP  I49  C371   [Q_CAP_C0805-100UF,4V,20%,X6S,CA]
    1  PVCCIN_CPU0        A  @S9S_MB_2U_LIB.S9S_MB_2U(SCH_1):PVCCIN_CPU0
    2  GND                B  @S9S_MB_2U_LIB.S9S_MB_2U(SCH_1):GND

Q_CAP  I83  C372   [Q_CAP_C0805-100UF,4V,20%,X6S,CA]
    1  PVCCIN_CPU0        A  @S9S_MB_2U_LIB.S9S_MB_2U(SCH_1):PVCCIN_CPU0
    2  GND                B  @S9S_MB_2U_LIB.S9S_MB_2U(SCH_1):GND

Q_CAP  I52  C373   [Q_CAP_C0805-100UF,4V,20%,X6S,CA]
    1  PVCCIN_CPU0        A  @S9S_MB_2U_LIB.S9S_MB_2U(SCH_1):PVCCIN_CPU0
    2  GND                B  @S9S_MB_2U_LIB.S9S_MB_2U(SCH_1):GND

Q_CAP  I88  C374   [Q_CAP_C0805-100UF,4V,20%,X6S,CA]
    1  PVCCIN_CPU0        A  @S9S_MB_2U_LIB.S9S_MB_2U(SCH_1):PVCCIN_CPU0
    2  GND                B  @S9S_MB_2U_LIB.S9S_MB_2U(SCH_1):GND

Q_CAP  I54  C376   [Q_CAP_C0805-100UF,4V,20%,X6S,CA]
    1  PVCCIN_CPU0        A  @S9S_MB_2U_LIB.S9S_MB_2U(SCH_1):PVCCIN_CPU0
    2  GND                B  @S9S_MB_2U_LIB.S9S_MB_2U(SCH_1):GND

Q_CAP  I90  C377   [Q_CAP_C0805-100UF,4V,20%,X6S,CA]
    1  PVCCIN_CPU0        A  @S9S_MB_2U_LIB.S9S_MB_2U(SCH_1):PVCCIN_CPU0
    2  GND                B  @S9S_MB_2U_LIB.S9S_MB_2U(SCH_1):GND

Q_CAP  I77  C379   [Q_CAP_C0805-100UF,4V,20%,X6S,CA]
    1  PVCCIN_CPU0        A  @S9S_MB_2U_LIB.S9S_MB_2U(SCH_1):PVCCIN_CPU0
    2  GND                B  @S9S_MB_2U_LIB.S9S_MB_2U(SCH_1):GND

Q_CAP  I95  C380   [Q_CAP_C0805-100UF,4V,20%,X6S,CA]
    1  PVCCIN_CPU0        A  @S9S_MB_2U_LIB.S9S_MB_2U(SCH_1):PVCCIN_CPU0
    2  GND                B  @S9S_MB_2U_LIB.S9S_MB_2U(SCH_1):GND

Q_CAP  I189  C381   [Q_CAP_C0603-47UF,2.5V,20%,X6S,A]
    1  PVCCIN_CPU0        A  @S9S_MB_2U_LIB.S9S_MB_2U(SCH_1):PVCCIN_CPU0
    2  GND                B  @S9S_MB_2U_LIB.S9S_MB_2U(SCH_1):GND

Q_CAP  I80  C382   [Q_CAP_C0805-100UF,4V,20%,X6S,CA]
    1  PVCCIN_CPU0        A  @S9S_MB_2U_LIB.S9S_MB_2U(SCH_1):PVCCIN_CPU0
    2  GND                B  @S9S_MB_2U_LIB.S9S_MB_2U(SCH_1):GND

Q_CAP  I97  C383   [Q_CAP_C0805-100UF,4V,20%,X6S,CA]
    1  PVCCIN_CPU0        A  @S9S_MB_2U_LIB.S9S_MB_2U(SCH_1):PVCCIN_CPU0
    2  GND                B  @S9S_MB_2U_LIB.S9S_MB_2U(SCH_1):GND

Q_CAP  I187  C384   [Q_CAP_C0603-47UF,2.5V,20%,X6S,A]
    1  PVCCIN_CPU0        A  @S9S_MB_2U_LIB.S9S_MB_2U(SCH_1):PVCCIN_CPU0
    2  GND                B  @S9S_MB_2U_LIB.S9S_MB_2U(SCH_1):GND

Q_CAP  I113  C385   [Q_CAP_C0805-100UF,4V,20%,X6S,CA]
    1  PVCCIN_CPU0        A  @S9S_MB_2U_LIB.S9S_MB_2U(SCH_1):PVCCIN_CPU0
    2  GND                B  @S9S_MB_2U_LIB.S9S_MB_2U(SCH_1):GND

Q_CAP  I41  C386   [Q_CAP_C0805-100UF,4V,20%,X6S,CA]
    1  PVCCIN_CPU0        A  @S9S_MB_2U_LIB.S9S_MB_2U(SCH_1):PVCCIN_CPU0
    2  GND                B  @S9S_MB_2U_LIB.S9S_MB_2U(SCH_1):GND

Q_CAP  I112  C387   [Q_CAP_C0805-100UF,4V,20%,X6S,CA]
    1  PVCCIN_CPU0        A  @S9S_MB_2U_LIB.S9S_MB_2U(SCH_1):PVCCIN_CPU0
    2  GND                B  @S9S_MB_2U_LIB.S9S_MB_2U(SCH_1):GND

Q_CAP  I46  C388   [Q_CAP_C0805-100UF,4V,20%,X6S,CA]
    1  PVCCIN_CPU0        A  @S9S_MB_2U_LIB.S9S_MB_2U(SCH_1):PVCCIN_CPU0
    2  GND                B  @S9S_MB_2U_LIB.S9S_MB_2U(SCH_1):GND

Q_CAP  I217  C389   [Q_CAP_C0805-100UF,4V,20%,X6S,CA]
    1  PVCCIN_CPU0        A  @S9S_MB_2U_LIB.S9S_MB_2U(SCH_1):PVCCIN_CPU0
    2  GND                B  @S9S_MB_2U_LIB.S9S_MB_2U(SCH_1):GND

Q_CAP  I47  C390   [Q_CAP_C0805-100UF,4V,20%,X6S,CA]
    1  PVCCIN_CPU0        A  @S9S_MB_2U_LIB.S9S_MB_2U(SCH_1):PVCCIN_CPU0
    2  GND                B  @S9S_MB_2U_LIB.S9S_MB_2U(SCH_1):GND

Q_CAP  I216  C391   [Q_CAP_C0805-100UF,4V,20%,X6S,CA]
    1  PVCCIN_CPU0        A  @S9S_MB_2U_LIB.S9S_MB_2U(SCH_1):PVCCIN_CPU0
    2  GND                B  @S9S_MB_2U_LIB.S9S_MB_2U(SCH_1):GND

Q_CAP  I62  C392   [Q_CAP_C0805-100UF,4V,20%,X6S,CA]
    1  PVCCIN_CPU0        A  @S9S_MB_2U_LIB.S9S_MB_2U(SCH_1):PVCCIN_CPU0
    2  GND                B  @S9S_MB_2U_LIB.S9S_MB_2U(SCH_1):GND

Q_CAP  I215  C393   [Q_CAP_C0805-100UF,4V,20%,X6S,CA]
    1  PVCCIN_CPU0        A  @S9S_MB_2U_LIB.S9S_MB_2U(SCH_1):PVCCIN_CPU0
    2  GND                B  @S9S_MB_2U_LIB.S9S_MB_2U(SCH_1):GND

Q_CAP  I63  C394   [Q_CAP_C0805-100UF,4V,20%,X6S,CA]
    1  PVCCIN_CPU0        A  @S9S_MB_2U_LIB.S9S_MB_2U(SCH_1):PVCCIN_CPU0
    2  GND                B  @S9S_MB_2U_LIB.S9S_MB_2U(SCH_1):GND

Q_CAP  I108  C395   [Q_CAP_C0805-100UF,4V,20%,X6S,CA]
    1  PVNN_MAIN_CPU0      A  @S9S_MB_2U_LIB.S9S_MB_2U(SCH_1):PVNN_MAIN_CPU0
    2  GND                B  @S9S_MB_2U_LIB.S9S_MB_2U(SCH_1):GND

Q_CAP  I68  C396   [Q_CAP_C0805-100UF,4V,20%,X6S,CA]
    1  PVCCIN_CPU0        A  @S9S_MB_2U_LIB.S9S_MB_2U(SCH_1):PVCCIN_CPU0
    2  GND                B  @S9S_MB_2U_LIB.S9S_MB_2U(SCH_1):GND

Q_CAP  I236  C397   [Q_CAP_C0805-100UF,4V,20%,X6S,CA]
    1  PVCCIN_CPU0        A  @S9S_MB_2U_LIB.S9S_MB_2U(SCH_1):PVCCIN_CPU0
    2  GND                B  @S9S_MB_2U_LIB.S9S_MB_2U(SCH_1):GND

Q_CAP  I69  C398   [Q_CAP_C0805-100UF,4V,20%,X6S,CA]
    1  PVCCIN_CPU0        A  @S9S_MB_2U_LIB.S9S_MB_2U(SCH_1):PVCCIN_CPU0
    2  GND                B  @S9S_MB_2U_LIB.S9S_MB_2U(SCH_1):GND

Q_CAP  I102  C399   [Q_CAP_C0402-22UF,4V,20%,X6S,CHA]
    1  PVCCD_HV_CPU0      A  @S9S_MB_2U_LIB.S9S_MB_2U(SCH_1):PVCCD_HV_CPU0
    2  GND                B  @S9S_MB_2U_LIB.S9S_MB_2U(SCH_1):GND

Q_CAP  I134  C400   [Q_CAP_C0402-22UF,4V,20%,X6S,CHA]
    1  PVCCFA_EHV_FIVRA_CPU0      A  @S9S_MB_2U_LIB.S9S_MB_2U(SCH_1):PVCCFA_EHV_FIVRA_CPU0
    2  GND                B  @S9S_MB_2U_LIB.S9S_MB_2U(SCH_1):GND

Q_CAP  I105  C401   [Q_CAP_C0402-22UF,4V,20%,X6S,CHA]
    1  PVCCD_HV_CPU0      A  @S9S_MB_2U_LIB.S9S_MB_2U(SCH_1):PVCCD_HV_CPU0
    2  GND                B  @S9S_MB_2U_LIB.S9S_MB_2U(SCH_1):GND

Q_CAP  I133  C402   [Q_CAP_C0402-22UF,4V,20%,X6S,CHA]
    1  PVCCFA_EHV_FIVRA_CPU0      A  @S9S_MB_2U_LIB.S9S_MB_2U(SCH_1):PVCCFA_EHV_FIVRA_CPU0
    2  GND                B  @S9S_MB_2U_LIB.S9S_MB_2U(SCH_1):GND

Q_CAP  I104  C403   [Q_CAP_C0402-22UF,4V,20%,X6S,CHA]
    1  PVCCD_HV_CPU0      A  @S9S_MB_2U_LIB.S9S_MB_2U(SCH_1):PVCCD_HV_CPU0
    2  GND                B  @S9S_MB_2U_LIB.S9S_MB_2U(SCH_1):GND

Q_CAP  I132  C404   [Q_CAP_C0402-22UF,4V,20%,X6S,CHA]
    1  PVCCFA_EHV_FIVRA_CPU0      A  @S9S_MB_2U_LIB.S9S_MB_2U(SCH_1):PVCCFA_EHV_FIVRA_CPU0
    2  GND                B  @S9S_MB_2U_LIB.S9S_MB_2U(SCH_1):GND

Q_CAP  I103  C405   [Q_CAP_C0402-22UF,4V,20%,X6S,CHA]
    1  PVCCD_HV_CPU0      A  @S9S_MB_2U_LIB.S9S_MB_2U(SCH_1):PVCCD_HV_CPU0
    2  GND                B  @S9S_MB_2U_LIB.S9S_MB_2U(SCH_1):GND

Q_CAP  I131  C406   [Q_CAP_C0402-22UF,4V,20%,X6S,CHA]
    1  PVCCFA_EHV_FIVRA_CPU0      A  @S9S_MB_2U_LIB.S9S_MB_2U(SCH_1):PVCCFA_EHV_FIVRA_CPU0
    2  GND                B  @S9S_MB_2U_LIB.S9S_MB_2U(SCH_1):GND

Q_CAP  I135  C407   [Q_CAP_C0402-22UF,4V,20%,X6S,CHA]
    1  PVCCFA_EHV_FIVRA_CPU0      A  @S9S_MB_2U_LIB.S9S_MB_2U(SCH_1):PVCCFA_EHV_FIVRA_CPU0
    2  GND                B  @S9S_MB_2U_LIB.S9S_MB_2U(SCH_1):GND

Q_CAP  I115  C408   [Q_CAP_C0402-22UF,4V,20%,X6S,CHA]
    1  PVCCINFAON_CPU0      A  @S9S_MB_2U_LIB.S9S_MB_2U(SCH_1):PVCCINFAON_CPU0
    2  GND                B  @S9S_MB_2U_LIB.S9S_MB_2U(SCH_1):GND

Q_CAP  I136  C409   [Q_CAP_C0402-22UF,4V,20%,X6S,CHA]
    1  PVCCFA_EHV_FIVRA_CPU0      A  @S9S_MB_2U_LIB.S9S_MB_2U(SCH_1):PVCCFA_EHV_FIVRA_CPU0
    2  GND                B  @S9S_MB_2U_LIB.S9S_MB_2U(SCH_1):GND

Q_CAP  I114  C410   [Q_CAP_C0402-22UF,4V,20%,X6S,CHA]
    1  PVCCINFAON_CPU0      A  @S9S_MB_2U_LIB.S9S_MB_2U(SCH_1):PVCCINFAON_CPU0
    2  GND                B  @S9S_MB_2U_LIB.S9S_MB_2U(SCH_1):GND

Q_CAP  I137  C411   [Q_CAP_C0402-22UF,4V,20%,X6S,CHA]
    1  PVCCFA_EHV_FIVRA_CPU0      A  @S9S_MB_2U_LIB.S9S_MB_2U(SCH_1):PVCCFA_EHV_FIVRA_CPU0
    2  GND                B  @S9S_MB_2U_LIB.S9S_MB_2U(SCH_1):GND

Q_CAP  I113  C412   [Q_CAP_C0402-22UF,4V,20%,X6S,CHA]
    1  PVCCINFAON_CPU0      A  @S9S_MB_2U_LIB.S9S_MB_2U(SCH_1):PVCCINFAON_CPU0
    2  GND                B  @S9S_MB_2U_LIB.S9S_MB_2U(SCH_1):GND

Q_CAP  I138  C413   [Q_CAP_C0402-22UF,4V,20%,X6S,CHA]
    1  PVCCFA_EHV_FIVRA_CPU0      A  @S9S_MB_2U_LIB.S9S_MB_2U(SCH_1):PVCCFA_EHV_FIVRA_CPU0
    2  GND                B  @S9S_MB_2U_LIB.S9S_MB_2U(SCH_1):GND

Q_CAP  I112  C414   [Q_CAP_C0402-22UF,4V,20%,X6S,CHA]
    1  PVCCINFAON_CPU0      A  @S9S_MB_2U_LIB.S9S_MB_2U(SCH_1):PVCCINFAON_CPU0
    2  GND                B  @S9S_MB_2U_LIB.S9S_MB_2U(SCH_1):GND

Q_CAP  I139  C415   [Q_CAP_C0402-22UF,4V,20%,X6S,CHA]
    1  PVCCFA_EHV_FIVRA_CPU0      A  @S9S_MB_2U_LIB.S9S_MB_2U(SCH_1):PVCCFA_EHV_FIVRA_CPU0
    2  GND                B  @S9S_MB_2U_LIB.S9S_MB_2U(SCH_1):GND

Q_CAP  I111  C416   [Q_CAP_C0402-22UF,4V,20%,X6S,CHA]
    1  PVCCINFAON_CPU0      A  @S9S_MB_2U_LIB.S9S_MB_2U(SCH_1):PVCCINFAON_CPU0
    2  GND                B  @S9S_MB_2U_LIB.S9S_MB_2U(SCH_1):GND

Q_CAP  I140  C417   [Q_CAP_C0402-22UF,4V,20%,X6S,CHA]
    1  PVCCFA_EHV_FIVRA_CPU0      A  @S9S_MB_2U_LIB.S9S_MB_2U(SCH_1):PVCCFA_EHV_FIVRA_CPU0
    2  GND                B  @S9S_MB_2U_LIB.S9S_MB_2U(SCH_1):GND

Q_CAP  I141  C418   [Q_CAP_C0402-22UF,4V,20%,X6S,CHA]
    1  PVCCFA_EHV_FIVRA_CPU0      A  @S9S_MB_2U_LIB.S9S_MB_2U(SCH_1):PVCCFA_EHV_FIVRA_CPU0
    2  GND                B  @S9S_MB_2U_LIB.S9S_MB_2U(SCH_1):GND

Q_CAP  I142  C419   [Q_CAP_C0402-22UF,4V,20%,X6S,CHA]
    1  PVCCFA_EHV_CPU0      A  @S9S_MB_2U_LIB.S9S_MB_2U(SCH_1):PVCCFA_EHV_CPU0
    2  GND                B  @S9S_MB_2U_LIB.S9S_MB_2U(SCH_1):GND

Q_CAP  I146  C420   [Q_CAP_C0402-22UF,4V,20%,X6S,CHA]
    1  PVCCFA_EHV_CPU0      A  @S9S_MB_2U_LIB.S9S_MB_2U(SCH_1):PVCCFA_EHV_CPU0
    2  GND                B  @S9S_MB_2U_LIB.S9S_MB_2U(SCH_1):GND

Q_CAP  I145  C421   [Q_CAP_C0402-22UF,4V,20%,X6S,CHA]
    1  PVCCFA_EHV_CPU0      A  @S9S_MB_2U_LIB.S9S_MB_2U(SCH_1):PVCCFA_EHV_CPU0
    2  GND                B  @S9S_MB_2U_LIB.S9S_MB_2U(SCH_1):GND

Q_CAP  I143  C422   [Q_CAP_C0402-22UF,4V,20%,X6S,CHA]
    1  PVCCFA_EHV_CPU0      A  @S9S_MB_2U_LIB.S9S_MB_2U(SCH_1):PVCCFA_EHV_CPU0
    2  GND                B  @S9S_MB_2U_LIB.S9S_MB_2U(SCH_1):GND

Q_CAP  I11  C423   [Q_CAP_C0402-22UF,4V,20%,X6S,CHA]
    1  PVCCD_HV_CPU1      A  @S9S_MB_2U_LIB.S9S_MB_2U(SCH_1):PVCCD_HV_CPU1
    2  GND                B  @S9S_MB_2U_LIB.S9S_MB_2U(SCH_1):GND

Q_CAP  I1   C424   [Q_CAP_C0402-22UF,4V,20%,X6S,CHA]
    1  PVCCFA_EHV_FIVRA_CPU1      A  @S9S_MB_2U_LIB.S9S_MB_2U(SCH_1):PVCCFA_EHV_FIVRA_CPU1
    2  GND                B  @S9S_MB_2U_LIB.S9S_MB_2U(SCH_1):GND

Q_CAP  I17  C425   [Q_CAP_C0402-22UF,4V,20%,X6S,CHA]
    1  PVCCD_HV_CPU1      A  @S9S_MB_2U_LIB.S9S_MB_2U(SCH_1):PVCCD_HV_CPU1
    2  GND                B  @S9S_MB_2U_LIB.S9S_MB_2U(SCH_1):GND

Q_CAP  I3   C426   [Q_CAP_C0402-22UF,4V,20%,X6S,CHA]
    1  PVCCFA_EHV_FIVRA_CPU1      A  @S9S_MB_2U_LIB.S9S_MB_2U(SCH_1):PVCCFA_EHV_FIVRA_CPU1
    2  GND                B  @S9S_MB_2U_LIB.S9S_MB_2U(SCH_1):GND

Q_CAP  I19  C427   [Q_CAP_C0402-22UF,4V,20%,X6S,CHA]
    1  PVCCD_HV_CPU1      A  @S9S_MB_2U_LIB.S9S_MB_2U(SCH_1):PVCCD_HV_CPU1
    2  GND                B  @S9S_MB_2U_LIB.S9S_MB_2U(SCH_1):GND

Q_CAP  I4   C428   [Q_CAP_C0402-22UF,4V,20%,X6S,CHA]
    1  PVCCFA_EHV_FIVRA_CPU1      A  @S9S_MB_2U_LIB.S9S_MB_2U(SCH_1):PVCCFA_EHV_FIVRA_CPU1
    2  GND                B  @S9S_MB_2U_LIB.S9S_MB_2U(SCH_1):GND

Q_CAP  I34  C429   [Q_CAP_C0402-22UF,4V,20%,X6S,CHA]
    1  PVCCD_HV_CPU1      A  @S9S_MB_2U_LIB.S9S_MB_2U(SCH_1):PVCCD_HV_CPU1
    2  GND                B  @S9S_MB_2U_LIB.S9S_MB_2U(SCH_1):GND

Q_CAP  I5   C430   [Q_CAP_C0402-22UF,4V,20%,X6S,CHA]
    1  PVCCFA_EHV_FIVRA_CPU1      A  @S9S_MB_2U_LIB.S9S_MB_2U(SCH_1):PVCCFA_EHV_FIVRA_CPU1
    2  GND                B  @S9S_MB_2U_LIB.S9S_MB_2U(SCH_1):GND

Q_CAP  I7   C431   [Q_CAP_C0402-22UF,4V,20%,X6S,CHA]
    1  PVCCFA_EHV_FIVRA_CPU1      A  @S9S_MB_2U_LIB.S9S_MB_2U(SCH_1):PVCCFA_EHV_FIVRA_CPU1
    2  GND                B  @S9S_MB_2U_LIB.S9S_MB_2U(SCH_1):GND

Q_CAP  I39  C432   [Q_CAP_C0402-22UF,4V,20%,X6S,CHA]
    1  PVCCINFAON_CPU1      A  @S9S_MB_2U_LIB.S9S_MB_2U(SCH_1):PVCCINFAON_CPU1
    2  GND                B  @S9S_MB_2U_LIB.S9S_MB_2U(SCH_1):GND

Q_CAP  I8   C433   [Q_CAP_C0402-22UF,4V,20%,X6S,CHA]
    1  PVCCFA_EHV_FIVRA_CPU1      A  @S9S_MB_2U_LIB.S9S_MB_2U(SCH_1):PVCCFA_EHV_FIVRA_CPU1
    2  GND                B  @S9S_MB_2U_LIB.S9S_MB_2U(SCH_1):GND

Q_CAP  I42  C434   [Q_CAP_C0402-22UF,4V,20%,X6S,CHA]
    1  PVCCINFAON_CPU1      A  @S9S_MB_2U_LIB.S9S_MB_2U(SCH_1):PVCCINFAON_CPU1
    2  GND                B  @S9S_MB_2U_LIB.S9S_MB_2U(SCH_1):GND

Q_CAP  I9   C435   [Q_CAP_C0402-22UF,4V,20%,X6S,CHA]
    1  PVCCFA_EHV_FIVRA_CPU1      A  @S9S_MB_2U_LIB.S9S_MB_2U(SCH_1):PVCCFA_EHV_FIVRA_CPU1
    2  GND                B  @S9S_MB_2U_LIB.S9S_MB_2U(SCH_1):GND

Q_CAP  I43  C436   [Q_CAP_C0402-22UF,4V,20%,X6S,CHA]
    1  PVCCINFAON_CPU1      A  @S9S_MB_2U_LIB.S9S_MB_2U(SCH_1):PVCCINFAON_CPU1
    2  GND                B  @S9S_MB_2U_LIB.S9S_MB_2U(SCH_1):GND

Q_CAP  I10  C437   [Q_CAP_C0402-22UF,4V,20%,X6S,CHA]
    1  PVCCFA_EHV_FIVRA_CPU1      A  @S9S_MB_2U_LIB.S9S_MB_2U(SCH_1):PVCCFA_EHV_FIVRA_CPU1
    2  GND                B  @S9S_MB_2U_LIB.S9S_MB_2U(SCH_1):GND

Q_CAP  I71  C438   [Q_CAP_C0402-22UF,4V,20%,X6S,CHA]
    1  PVCCINFAON_CPU1      A  @S9S_MB_2U_LIB.S9S_MB_2U(SCH_1):PVCCINFAON_CPU1
    2  GND                B  @S9S_MB_2U_LIB.S9S_MB_2U(SCH_1):GND

Q_CAP  I65  C439   [Q_CAP_C0402-22UF,4V,20%,X6S,CHA]
    1  PVCCFA_EHV_FIVRA_CPU1      A  @S9S_MB_2U_LIB.S9S_MB_2U(SCH_1):PVCCFA_EHV_FIVRA_CPU1
    2  GND                B  @S9S_MB_2U_LIB.S9S_MB_2U(SCH_1):GND

Q_CAP  I73  C440   [Q_CAP_C0402-22UF,4V,20%,X6S,CHA]
    1  PVCCINFAON_CPU1      A  @S9S_MB_2U_LIB.S9S_MB_2U(SCH_1):PVCCINFAON_CPU1
    2  GND                B  @S9S_MB_2U_LIB.S9S_MB_2U(SCH_1):GND

Q_CAP  I66  C441   [Q_CAP_C0402-22UF,4V,20%,X6S,CHA]
    1  PVCCFA_EHV_FIVRA_CPU1      A  @S9S_MB_2U_LIB.S9S_MB_2U(SCH_1):PVCCFA_EHV_FIVRA_CPU1
    2  GND                B  @S9S_MB_2U_LIB.S9S_MB_2U(SCH_1):GND

Q_CAP  I69  C442   [Q_CAP_C0402-22UF,4V,20%,X6S,CHA]
    1  PVCCFA_EHV_FIVRA_CPU1      A  @S9S_MB_2U_LIB.S9S_MB_2U(SCH_1):PVCCFA_EHV_FIVRA_CPU1
    2  GND                B  @S9S_MB_2U_LIB.S9S_MB_2U(SCH_1):GND

Q_CAP  I79  C443   [Q_CAP_C0402-22UF,4V,20%,X6S,CHA]
    1  PVCCFA_EHV_CPU1      A  @S9S_MB_2U_LIB.S9S_MB_2U(SCH_1):PVCCFA_EHV_CPU1
    2  GND                B  @S9S_MB_2U_LIB.S9S_MB_2U(SCH_1):GND

Q_CAP  I101  C444   [Q_CAP_C0402-22UF,4V,20%,X6S,CHA]
    1  PVCCFA_EHV_CPU1      A  @S9S_MB_2U_LIB.S9S_MB_2U(SCH_1):PVCCFA_EHV_CPU1
    2  GND                B  @S9S_MB_2U_LIB.S9S_MB_2U(SCH_1):GND

Q_CAP  I102  C445   [Q_CAP_C0402-22UF,4V,20%,X6S,CHA]
    1  PVCCFA_EHV_CPU1      A  @S9S_MB_2U_LIB.S9S_MB_2U(SCH_1):PVCCFA_EHV_CPU1
    2  GND                B  @S9S_MB_2U_LIB.S9S_MB_2U(SCH_1):GND

Q_CAP  I105  C446   [Q_CAP_C0402-22UF,4V,20%,X6S,CHA]
    1  PVCCFA_EHV_CPU1      A  @S9S_MB_2U_LIB.S9S_MB_2U(SCH_1):PVCCFA_EHV_CPU1
    2  GND                B  @S9S_MB_2U_LIB.S9S_MB_2U(SCH_1):GND

Q_CAP  I24  C447   [Q_CAP_C0805-100UF,4V,20%,X6S,CA]
    1  PVCCD_HV_CPU1      A  @S9S_MB_2U_LIB.S9S_MB_2U(SCH_1):PVCCD_HV_CPU1
    2  GND                B  @S9S_MB_2U_LIB.S9S_MB_2U(SCH_1):GND

Q_CAP  I23  C448   [Q_CAP_C0805-100UF,4V,20%,X6S,CA]
    1  PVCCFA_EHV_CPU1      A  @S9S_MB_2U_LIB.S9S_MB_2U(SCH_1):PVCCFA_EHV_CPU1
    2  GND                B  @S9S_MB_2U_LIB.S9S_MB_2U(SCH_1):GND

Q_CAP  I3   C449   [Q_CAP_C0805-100UF,4V,20%,X6S,CA]
    1  PVCCFA_EHV_FIVRA_CPU1      A  @S9S_MB_2U_LIB.S9S_MB_2U(SCH_1):PVCCFA_EHV_FIVRA_CPU1
    2  GND                B  @S9S_MB_2U_LIB.S9S_MB_2U(SCH_1):GND

Q_CAP  I1   C450   [Q_CAP_C0805-100UF,4V,20%,X6S,CA]
    1  PVCCFA_EHV_FIVRA_CPU1      A  @S9S_MB_2U_LIB.S9S_MB_2U(SCH_1):PVCCFA_EHV_FIVRA_CPU1
    2  GND                B  @S9S_MB_2U_LIB.S9S_MB_2U(SCH_1):GND

Q_CAP  I29  C451   [Q_CAP_C0805-100UF,4V,20%,X6S,CA]
    1  PVCCD_HV_CPU1      A  @S9S_MB_2U_LIB.S9S_MB_2U(SCH_1):PVCCD_HV_CPU1
    2  GND                B  @S9S_MB_2U_LIB.S9S_MB_2U(SCH_1):GND

Q_CAP  I27  C452   [Q_CAP_C0805-100UF,4V,20%,X6S,CA]
    1  PVCCFA_EHV_CPU1      A  @S9S_MB_2U_LIB.S9S_MB_2U(SCH_1):PVCCFA_EHV_CPU1
    2  GND                B  @S9S_MB_2U_LIB.S9S_MB_2U(SCH_1):GND

Q_CAP  I5   C453   [Q_CAP_C0805-100UF,4V,20%,X6S,CA]
    1  PVCCFA_EHV_FIVRA_CPU1      A  @S9S_MB_2U_LIB.S9S_MB_2U(SCH_1):PVCCFA_EHV_FIVRA_CPU1
    2  GND                B  @S9S_MB_2U_LIB.S9S_MB_2U(SCH_1):GND

Q_CAP  I3   C454   [Q_CAP_C0805-100UF,4V,20%,X6S,CA]
    1  PVCCFA_EHV_FIVRA_CPU1      A  @S9S_MB_2U_LIB.S9S_MB_2U(SCH_1):PVCCFA_EHV_FIVRA_CPU1
    2  GND                B  @S9S_MB_2U_LIB.S9S_MB_2U(SCH_1):GND

Q_CAP  I129  C455   [Q_CAP_C0805-100UF,4V,20%,X6S,CA]
    1  PVCCD_HV_CPU1      A  @S9S_MB_2U_LIB.S9S_MB_2U(SCH_1):PVCCD_HV_CPU1
    2  GND                B  @S9S_MB_2U_LIB.S9S_MB_2U(SCH_1):GND

Q_CAP  I136  C456   [Q_CAP_C0805-100UF,4V,20%,X6S,CA]
    1  PVCCFA_EHV_CPU1      A  @S9S_MB_2U_LIB.S9S_MB_2U(SCH_1):PVCCFA_EHV_CPU1
    2  GND                B  @S9S_MB_2U_LIB.S9S_MB_2U(SCH_1):GND

Q_CAP  I7   C457   [Q_CAP_C0805-100UF,4V,20%,X6S,CA]
    1  PVCCFA_EHV_FIVRA_CPU1      A  @S9S_MB_2U_LIB.S9S_MB_2U(SCH_1):PVCCFA_EHV_FIVRA_CPU1
    2  GND                B  @S9S_MB_2U_LIB.S9S_MB_2U(SCH_1):GND

Q_CAP  I4   C458   [Q_CAP_C0805-100UF,4V,20%,X6S,CA]
    1  PVCCFA_EHV_FIVRA_CPU1      A  @S9S_MB_2U_LIB.S9S_MB_2U(SCH_1):PVCCFA_EHV_FIVRA_CPU1
    2  GND                B  @S9S_MB_2U_LIB.S9S_MB_2U(SCH_1):GND

Q_CAP  I128  C459   [Q_CAP_C0805-100UF,4V,20%,X6S,CA]
    1  PVCCD_HV_CPU1      A  @S9S_MB_2U_LIB.S9S_MB_2U(SCH_1):PVCCD_HV_CPU1
    2  GND                B  @S9S_MB_2U_LIB.S9S_MB_2U(SCH_1):GND

Q_CAP  I135  C460   [Q_CAP_C0805-100UF,4V,20%,X6S,CA]
    1  PVCCFA_EHV_CPU1      A  @S9S_MB_2U_LIB.S9S_MB_2U(SCH_1):PVCCFA_EHV_CPU1
    2  GND                B  @S9S_MB_2U_LIB.S9S_MB_2U(SCH_1):GND

Q_CAP  I9   C461   [Q_CAP_C0805-100UF,4V,20%,X6S,CA]
    1  PVCCFA_EHV_FIVRA_CPU1      A  @S9S_MB_2U_LIB.S9S_MB_2U(SCH_1):PVCCFA_EHV_FIVRA_CPU1
    2  GND                B  @S9S_MB_2U_LIB.S9S_MB_2U(SCH_1):GND

Q_CAP  I5   C462   [Q_CAP_C0805-100UF,4V,20%,X6S,CA]
    1  PVCCFA_EHV_FIVRA_CPU1      A  @S9S_MB_2U_LIB.S9S_MB_2U(SCH_1):PVCCFA_EHV_FIVRA_CPU1
    2  GND                B  @S9S_MB_2U_LIB.S9S_MB_2U(SCH_1):GND

Q_CAP  I127  C463   [Q_CAP_C0805-100UF,4V,20%,X6S,CA]
    1  PVCCD_HV_CPU1      A  @S9S_MB_2U_LIB.S9S_MB_2U(SCH_1):PVCCD_HV_CPU1
    2  GND                B  @S9S_MB_2U_LIB.S9S_MB_2U(SCH_1):GND

Q_CAP  I134  C464   [Q_CAP_C0805-100UF,4V,20%,X6S,CA]
    1  PVCCFA_EHV_CPU1      A  @S9S_MB_2U_LIB.S9S_MB_2U(SCH_1):PVCCFA_EHV_CPU1
    2  GND                B  @S9S_MB_2U_LIB.S9S_MB_2U(SCH_1):GND

Q_CAP  I11  C465   [Q_CAP_C0603-47UF,2.5V,20%,X6S,A]
    1  PVCCFA_EHV_FIVRA_CPU1      A  @S9S_MB_2U_LIB.S9S_MB_2U(SCH_1):PVCCFA_EHV_FIVRA_CPU1
    2  GND                B  @S9S_MB_2U_LIB.S9S_MB_2U(SCH_1):GND

Q_CAP  I6   C466   [Q_CAP_C0805-100UF,4V,20%,X6S,CA]
    1  PVCCFA_EHV_FIVRA_CPU1      A  @S9S_MB_2U_LIB.S9S_MB_2U(SCH_1):PVCCFA_EHV_FIVRA_CPU1
    2  GND                B  @S9S_MB_2U_LIB.S9S_MB_2U(SCH_1):GND

Q_CAP  I126  C467   [Q_CAP_C0805-100UF,4V,20%,X6S,CA]
    1  PVCCD_HV_CPU1      A  @S9S_MB_2U_LIB.S9S_MB_2U(SCH_1):PVCCD_HV_CPU1
    2  GND                B  @S9S_MB_2U_LIB.S9S_MB_2U(SCH_1):GND

Q_CAP  I133  C468   [Q_CAP_C0805-100UF,4V,20%,X6S,CA]
    1  PVCCFA_EHV_CPU1      A  @S9S_MB_2U_LIB.S9S_MB_2U(SCH_1):PVCCFA_EHV_CPU1
    2  GND                B  @S9S_MB_2U_LIB.S9S_MB_2U(SCH_1):GND

Q_CAP  I7   C470   [Q_CAP_C0805-100UF,4V,20%,X6S,CA]
    1  PVCCFA_EHV_FIVRA_CPU1      A  @S9S_MB_2U_LIB.S9S_MB_2U(SCH_1):PVCCFA_EHV_FIVRA_CPU1
    2  GND                B  @S9S_MB_2U_LIB.S9S_MB_2U(SCH_1):GND

Q_CAP  I52  C471   [Q_CAP_C0603-47UF,2.5V,20%,X6S,A]
    1  PVCCD_HV_CPU1      A  @S9S_MB_2U_LIB.S9S_MB_2U(SCH_1):PVCCD_HV_CPU1
    2  GND                B  @S9S_MB_2U_LIB.S9S_MB_2U(SCH_1):GND

Q_CAP  I132  C472   [Q_CAP_C0603-47UF,2.5V,20%,X6S,A]
    1  PVCCFA_EHV_CPU1      A  @S9S_MB_2U_LIB.S9S_MB_2U(SCH_1):PVCCFA_EHV_CPU1
    2  GND                B  @S9S_MB_2U_LIB.S9S_MB_2U(SCH_1):GND

Q_CAP  I8   C473   [Q_CAP_C0805-100UF,4V,20%,X6S,CA]
    1  PVCCFA_EHV_FIVRA_CPU1      A  @S9S_MB_2U_LIB.S9S_MB_2U(SCH_1):PVCCFA_EHV_FIVRA_CPU1
    2  GND                B  @S9S_MB_2U_LIB.S9S_MB_2U(SCH_1):GND

Q_CAP  I54  C474   [Q_CAP_C0603-47UF,2.5V,20%,X6S,A]
    1  PVCCD_HV_CPU1      A  @S9S_MB_2U_LIB.S9S_MB_2U(SCH_1):PVCCD_HV_CPU1
    2  GND                B  @S9S_MB_2U_LIB.S9S_MB_2U(SCH_1):GND

Q_CAP  I131  C475   [Q_CAP_C0603-47UF,2.5V,20%,X6S,A]
    1  PVCCFA_EHV_CPU1      A  @S9S_MB_2U_LIB.S9S_MB_2U(SCH_1):PVCCFA_EHV_CPU1
    2  GND                B  @S9S_MB_2U_LIB.S9S_MB_2U(SCH_1):GND

Q_CAP  I9   C476   [Q_CAP_C0805-100UF,4V,20%,X6S,CA]
    1  PVCCFA_EHV_FIVRA_CPU1      A  @S9S_MB_2U_LIB.S9S_MB_2U(SCH_1):PVCCFA_EHV_FIVRA_CPU1
    2  GND                B  @S9S_MB_2U_LIB.S9S_MB_2U(SCH_1):GND

Q_CAP  I10  C477   [Q_CAP_C0805-100UF,4V,20%,X6S,CA]
    1  PVCCFA_EHV_FIVRA_CPU1      A  @S9S_MB_2U_LIB.S9S_MB_2U(SCH_1):PVCCFA_EHV_FIVRA_CPU1
    2  GND                B  @S9S_MB_2U_LIB.S9S_MB_2U(SCH_1):GND

Q_CAP  I70  C478   [Q_CAP_C0805-100UF,4V,20%,X6S,CA]
    1  PVCCINFAON_CPU1      A  @S9S_MB_2U_LIB.S9S_MB_2U(SCH_1):PVCCINFAON_CPU1
    2  GND                B  @S9S_MB_2U_LIB.S9S_MB_2U(SCH_1):GND

Q_CAP  I11  C479   [Q_CAP_C0805-100UF,4V,20%,X6S,CA]
    1  PVCCFA_EHV_FIVRA_CPU1      A  @S9S_MB_2U_LIB.S9S_MB_2U(SCH_1):PVCCFA_EHV_FIVRA_CPU1
    2  GND                B  @S9S_MB_2U_LIB.S9S_MB_2U(SCH_1):GND

Q_CAP  I119  C480   [Q_CAP_C0603-47UF,2.5V,20%,X6S,A]
    1  PVCCIN_CPU1        A  @S9S_MB_2U_LIB.S9S_MB_2U(SCH_1):PVCCIN_CPU1
    2  GND                B  @S9S_MB_2U_LIB.S9S_MB_2U(SCH_1):GND

Q_CAP  I77  C481   [Q_CAP_C0805-100UF,4V,20%,X6S,CA]
    1  PVCCINFAON_CPU1      A  @S9S_MB_2U_LIB.S9S_MB_2U(SCH_1):PVCCINFAON_CPU1
    2  GND                B  @S9S_MB_2U_LIB.S9S_MB_2U(SCH_1):GND

Q_CAP  I74  C482   [Q_CAP_C0805-100UF,4V,20%,X6S,CA]
    1  PVCCFA_EHV_FIVRA_CPU1      A  @S9S_MB_2U_LIB.S9S_MB_2U(SCH_1):PVCCFA_EHV_FIVRA_CPU1
    2  GND                B  @S9S_MB_2U_LIB.S9S_MB_2U(SCH_1):GND

Q_CAP  I118  C483   [Q_CAP_C0603-47UF,2.5V,20%,X6S,A]
    1  PVCCIN_CPU1        A  @S9S_MB_2U_LIB.S9S_MB_2U(SCH_1):PVCCIN_CPU1
    2  GND                B  @S9S_MB_2U_LIB.S9S_MB_2U(SCH_1):GND

Q_CAP  I78  C484   [Q_CAP_C0805-100UF,4V,20%,X6S,CA]
    1  PVCCINFAON_CPU1      A  @S9S_MB_2U_LIB.S9S_MB_2U(SCH_1):PVCCINFAON_CPU1
    2  GND                B  @S9S_MB_2U_LIB.S9S_MB_2U(SCH_1):GND

Q_CAP  I76  C485   [Q_CAP_C0805-100UF,4V,20%,X6S,CA]
    1  PVCCFA_EHV_FIVRA_CPU1      A  @S9S_MB_2U_LIB.S9S_MB_2U(SCH_1):PVCCFA_EHV_FIVRA_CPU1
    2  GND                B  @S9S_MB_2U_LIB.S9S_MB_2U(SCH_1):GND

Q_CAP  I79  C486   [Q_CAP_C0805-100UF,4V,20%,X6S,CA]
    1  PVCCINFAON_CPU1      A  @S9S_MB_2U_LIB.S9S_MB_2U(SCH_1):PVCCINFAON_CPU1
    2  GND                B  @S9S_MB_2U_LIB.S9S_MB_2U(SCH_1):GND

Q_CAP  I80  C487   [Q_CAP_C0805-100UF,4V,20%,X6S,CA]
    1  PVCCINFAON_CPU1      A  @S9S_MB_2U_LIB.S9S_MB_2U(SCH_1):PVCCINFAON_CPU1
    2  GND                B  @S9S_MB_2U_LIB.S9S_MB_2U(SCH_1):GND

Q_CAP  I134  C488   [Q_CAP_C0603-47UF,2.5V,20%,X6S,A]
    1  PVCCINFAON_CPU1      A  @S9S_MB_2U_LIB.S9S_MB_2U(SCH_1):PVCCINFAON_CPU1
    2  GND                B  @S9S_MB_2U_LIB.S9S_MB_2U(SCH_1):GND

Q_CAP  I133  C489   [Q_CAP_C0603-47UF,2.5V,20%,X6S,A]
    1  PVCCINFAON_CPU1      A  @S9S_MB_2U_LIB.S9S_MB_2U(SCH_1):PVCCINFAON_CPU1
    2  GND                B  @S9S_MB_2U_LIB.S9S_MB_2U(SCH_1):GND

Q_CAP  I132  C490   [Q_CAP_C0402-22UF,4V,20%,X6S,CHA]
    1  PVCCINFAON_CPU1      A  @S9S_MB_2U_LIB.S9S_MB_2U(SCH_1):PVCCINFAON_CPU1
    2  GND                B  @S9S_MB_2U_LIB.S9S_MB_2U(SCH_1):GND

Q_CAP  I10  C491   [Q_CAP_C0805-100UF,4V,20%,X6S,CA]
    1  PVCCD_HV_CPU0      A  @S9S_MB_2U_LIB.S9S_MB_2U(SCH_1):PVCCD_HV_CPU0
    2  GND                B  @S9S_MB_2U_LIB.S9S_MB_2U(SCH_1):GND

Q_CAP  I66  C492   [Q_CAP_C0805-100UF,4V,20%,X6S,CA]
    1  PVCCFA_EHV_CPU0      A  @S9S_MB_2U_LIB.S9S_MB_2U(SCH_1):PVCCFA_EHV_CPU0
    2  GND                B  @S9S_MB_2U_LIB.S9S_MB_2U(SCH_1):GND

Q_CAP  I1   C493   [Q_CAP_C0805-100UF,4V,20%,X6S,CA]
    1  PVCCFA_EHV_FIVRA_CPU0      A  @S9S_MB_2U_LIB.S9S_MB_2U(SCH_1):PVCCFA_EHV_FIVRA_CPU0
    2  GND                B  @S9S_MB_2U_LIB.S9S_MB_2U(SCH_1):GND

Q_CAP  I1   C494   [Q_CAP_C0805-100UF,4V,20%,X6S,CA]
    1  PVCCFA_EHV_FIVRA_CPU0      A  @S9S_MB_2U_LIB.S9S_MB_2U(SCH_1):PVCCFA_EHV_FIVRA_CPU0
    2  GND                B  @S9S_MB_2U_LIB.S9S_MB_2U(SCH_1):GND

Q_CAP  I14  C495   [Q_CAP_C0805-100UF,4V,20%,X6S,CA]
    1  PVCCD_HV_CPU0      A  @S9S_MB_2U_LIB.S9S_MB_2U(SCH_1):PVCCD_HV_CPU0
    2  GND                B  @S9S_MB_2U_LIB.S9S_MB_2U(SCH_1):GND

Q_CAP  I67  C496   [Q_CAP_C0805-100UF,4V,20%,X6S,CA]
    1  PVCCFA_EHV_CPU0      A  @S9S_MB_2U_LIB.S9S_MB_2U(SCH_1):PVCCFA_EHV_CPU0
    2  GND                B  @S9S_MB_2U_LIB.S9S_MB_2U(SCH_1):GND

Q_CAP  I2   C497   [Q_CAP_C0805-100UF,4V,20%,X6S,CA]
    1  PVCCFA_EHV_FIVRA_CPU0      A  @S9S_MB_2U_LIB.S9S_MB_2U(SCH_1):PVCCFA_EHV_FIVRA_CPU0
    2  GND                B  @S9S_MB_2U_LIB.S9S_MB_2U(SCH_1):GND

Q_CAP  I6   C498   [Q_CAP_C0805-100UF,4V,20%,X6S,CA]
    1  PVCCFA_EHV_FIVRA_CPU0      A  @S9S_MB_2U_LIB.S9S_MB_2U(SCH_1):PVCCFA_EHV_FIVRA_CPU0
    2  GND                B  @S9S_MB_2U_LIB.S9S_MB_2U(SCH_1):GND

Q_CAP  I107  C499   [Q_CAP_C0805-100UF,4V,20%,X6S,CA]
    1  PVCCD_HV_CPU0      A  @S9S_MB_2U_LIB.S9S_MB_2U(SCH_1):PVCCD_HV_CPU0
    2  GND                B  @S9S_MB_2U_LIB.S9S_MB_2U(SCH_1):GND

Q_CAP  I55  C500   [Q_CAP_C0805-100UF,4V,20%,X6S,CA]
    1  PVCCFA_EHV_CPU0      A  @S9S_MB_2U_LIB.S9S_MB_2U(SCH_1):PVCCFA_EHV_CPU0
    2  GND                B  @S9S_MB_2U_LIB.S9S_MB_2U(SCH_1):GND

Q_CAP  I3   C501   [Q_CAP_C0805-100UF,4V,20%,X6S,CA]
    1  PVCCFA_EHV_FIVRA_CPU0      A  @S9S_MB_2U_LIB.S9S_MB_2U(SCH_1):PVCCFA_EHV_FIVRA_CPU0
    2  GND                B  @S9S_MB_2U_LIB.S9S_MB_2U(SCH_1):GND

Q_CAP  I7   C502   [Q_CAP_C0805-100UF,4V,20%,X6S,CA]
    1  PVCCFA_EHV_FIVRA_CPU0      A  @S9S_MB_2U_LIB.S9S_MB_2U(SCH_1):PVCCFA_EHV_FIVRA_CPU0
    2  GND                B  @S9S_MB_2U_LIB.S9S_MB_2U(SCH_1):GND

Q_CAP  I110  C503   [Q_CAP_C0805-100UF,4V,20%,X6S,CA]
    1  PVCCD_HV_CPU0      A  @S9S_MB_2U_LIB.S9S_MB_2U(SCH_1):PVCCD_HV_CPU0
    2  GND                B  @S9S_MB_2U_LIB.S9S_MB_2U(SCH_1):GND

Q_CAP  I56  C504   [Q_CAP_C0805-100UF,4V,20%,X6S,CA]
    1  PVCCFA_EHV_CPU0      A  @S9S_MB_2U_LIB.S9S_MB_2U(SCH_1):PVCCFA_EHV_CPU0
    2  GND                B  @S9S_MB_2U_LIB.S9S_MB_2U(SCH_1):GND

Q_CAP  I4   C505   [Q_CAP_C0805-100UF,4V,20%,X6S,CA]
    1  PVCCFA_EHV_FIVRA_CPU0      A  @S9S_MB_2U_LIB.S9S_MB_2U(SCH_1):PVCCFA_EHV_FIVRA_CPU0
    2  GND                B  @S9S_MB_2U_LIB.S9S_MB_2U(SCH_1):GND

Q_CAP  I12  C506   [Q_CAP_C0805-100UF,4V,20%,X6S,CA]
    1  PVCCFA_EHV_FIVRA_CPU0      A  @S9S_MB_2U_LIB.S9S_MB_2U(SCH_1):PVCCFA_EHV_FIVRA_CPU0
    2  GND                B  @S9S_MB_2U_LIB.S9S_MB_2U(SCH_1):GND

Q_CAP  I109  C507   [Q_CAP_C0805-100UF,4V,20%,X6S,CA]
    1  PVCCD_HV_CPU0      A  @S9S_MB_2U_LIB.S9S_MB_2U(SCH_1):PVCCD_HV_CPU0
    2  GND                B  @S9S_MB_2U_LIB.S9S_MB_2U(SCH_1):GND

Q_CAP  I77  C508   [Q_CAP_C0805-100UF,4V,20%,X6S,CA]
    1  PVCCFA_EHV_CPU0      A  @S9S_MB_2U_LIB.S9S_MB_2U(SCH_1):PVCCFA_EHV_CPU0
    2  GND                B  @S9S_MB_2U_LIB.S9S_MB_2U(SCH_1):GND

Q_CAP  I105  C509   [Q_CAP_C0603-47UF,2.5V,20%,X6S,A]
    1  PVCCFA_EHV_FIVRA_CPU0      A  @S9S_MB_2U_LIB.S9S_MB_2U(SCH_1):PVCCFA_EHV_FIVRA_CPU0
    2  GND                B  @S9S_MB_2U_LIB.S9S_MB_2U(SCH_1):GND

Q_CAP  I13  C510   [Q_CAP_C0805-100UF,4V,20%,X6S,CA]
    1  PVCCFA_EHV_FIVRA_CPU0      A  @S9S_MB_2U_LIB.S9S_MB_2U(SCH_1):PVCCFA_EHV_FIVRA_CPU0
    2  GND                B  @S9S_MB_2U_LIB.S9S_MB_2U(SCH_1):GND

Q_CAP  I108  C511   [Q_CAP_C0805-100UF,4V,20%,X6S,CA]
    1  PVCCD_HV_CPU0      A  @S9S_MB_2U_LIB.S9S_MB_2U(SCH_1):PVCCD_HV_CPU0
    2  GND                B  @S9S_MB_2U_LIB.S9S_MB_2U(SCH_1):GND

Q_CAP  I78  C512   [Q_CAP_C0805-100UF,4V,20%,X6S,CA]
    1  PVCCFA_EHV_CPU0      A  @S9S_MB_2U_LIB.S9S_MB_2U(SCH_1):PVCCFA_EHV_CPU0
    2  GND                B  @S9S_MB_2U_LIB.S9S_MB_2U(SCH_1):GND

Q_CAP  I5   C513   [Q_CAP_C0805-22UF,16V,20%,X6S,CA]
    1  PGPPA_AUX          A  @S9S_MB_2U_LIB.S9S_MB_2U(SCH_1):PGPPA_AUX
    2  GND                B  @S9S_MB_2U_LIB.S9S_MB_2U(SCH_1):GND

Q_CAP  I18  C514   [Q_CAP_C0805-100UF,4V,20%,X6S,CA]
    1  PVCCFA_EHV_FIVRA_CPU0      A  @S9S_MB_2U_LIB.S9S_MB_2U(SCH_1):PVCCFA_EHV_FIVRA_CPU0
    2  GND                B  @S9S_MB_2U_LIB.S9S_MB_2U(SCH_1):GND

Q_CAP  I126  C515   [Q_CAP_C0603-47UF,2.5V,20%,X6S,A]
    1  PVCCD_HV_CPU0      A  @S9S_MB_2U_LIB.S9S_MB_2U(SCH_1):PVCCD_HV_CPU0
    2  GND                B  @S9S_MB_2U_LIB.S9S_MB_2U(SCH_1):GND

Q_CAP  I79  C516   [Q_CAP_C0603-47UF,2.5V,20%,X6S,A]
    1  PVCCFA_EHV_CPU0      A  @S9S_MB_2U_LIB.S9S_MB_2U(SCH_1):PVCCFA_EHV_CPU0
    2  GND                B  @S9S_MB_2U_LIB.S9S_MB_2U(SCH_1):GND

Q_CAP  I19  C517   [Q_CAP_C0805-100UF,4V,20%,X6S,CA]
    1  PVCCFA_EHV_FIVRA_CPU0      A  @S9S_MB_2U_LIB.S9S_MB_2U(SCH_1):PVCCFA_EHV_FIVRA_CPU0
    2  GND                B  @S9S_MB_2U_LIB.S9S_MB_2U(SCH_1):GND

Q_CAP  I130  C518   [Q_CAP_C0603-47UF,2.5V,20%,X6S,A]
    1  PVCCD_HV_CPU0      A  @S9S_MB_2U_LIB.S9S_MB_2U(SCH_1):PVCCD_HV_CPU0
    2  GND                B  @S9S_MB_2U_LIB.S9S_MB_2U(SCH_1):GND

Q_CAP  I81  C519   [Q_CAP_C0603-47UF,2.5V,20%,X6S,A]
    1  PVCCFA_EHV_CPU0      A  @S9S_MB_2U_LIB.S9S_MB_2U(SCH_1):PVCCFA_EHV_CPU0
    2  GND                B  @S9S_MB_2U_LIB.S9S_MB_2U(SCH_1):GND

Q_CAP  I20  C520   [Q_CAP_C0805-100UF,4V,20%,X6S,CA]
    1  PVCCFA_EHV_FIVRA_CPU0      A  @S9S_MB_2U_LIB.S9S_MB_2U(SCH_1):PVCCFA_EHV_FIVRA_CPU0
    2  GND                B  @S9S_MB_2U_LIB.S9S_MB_2U(SCH_1):GND

Q_CAP  I27  C521   [Q_CAP_C0805-100UF,4V,20%,X6S,CA]
    1  PVCCFA_EHV_FIVRA_CPU0      A  @S9S_MB_2U_LIB.S9S_MB_2U(SCH_1):PVCCFA_EHV_FIVRA_CPU0
    2  GND                B  @S9S_MB_2U_LIB.S9S_MB_2U(SCH_1):GND

Q_CAP  I33  C522   [Q_CAP_C0805-100UF,4V,20%,X6S,CA]
    1  PVCCINFAON_CPU0      A  @S9S_MB_2U_LIB.S9S_MB_2U(SCH_1):PVCCINFAON_CPU0
    2  GND                B  @S9S_MB_2U_LIB.S9S_MB_2U(SCH_1):GND

Q_CAP  I28  C523   [Q_CAP_C0805-100UF,4V,20%,X6S,CA]
    1  PVCCFA_EHV_FIVRA_CPU0      A  @S9S_MB_2U_LIB.S9S_MB_2U(SCH_1):PVCCFA_EHV_FIVRA_CPU0
    2  GND                B  @S9S_MB_2U_LIB.S9S_MB_2U(SCH_1):GND

Q_CAP  I186  C524   [Q_CAP_C0603-47UF,2.5V,20%,X6S,A]
    1  PVCCIN_CPU0        A  @S9S_MB_2U_LIB.S9S_MB_2U(SCH_1):PVCCIN_CPU0
    2  GND                B  @S9S_MB_2U_LIB.S9S_MB_2U(SCH_1):GND

Q_CAP  I114  C525   [Q_CAP_C0805-100UF,4V,20%,X6S,CA]
    1  PVCCINFAON_CPU0      A  @S9S_MB_2U_LIB.S9S_MB_2U(SCH_1):PVCCINFAON_CPU0
    2  GND                B  @S9S_MB_2U_LIB.S9S_MB_2U(SCH_1):GND

Q_CAP  I29  C526   [Q_CAP_C0805-100UF,4V,20%,X6S,CA]
    1  PVCCFA_EHV_FIVRA_CPU0      A  @S9S_MB_2U_LIB.S9S_MB_2U(SCH_1):PVCCFA_EHV_FIVRA_CPU0
    2  GND                B  @S9S_MB_2U_LIB.S9S_MB_2U(SCH_1):GND

Q_CAP  I185  C527   [Q_CAP_C0603-47UF,2.5V,20%,X6S,A]
    1  PVCCIN_CPU0        A  @S9S_MB_2U_LIB.S9S_MB_2U(SCH_1):PVCCIN_CPU0
    2  GND                B  @S9S_MB_2U_LIB.S9S_MB_2U(SCH_1):GND

Q_CAP  I118  C528   [Q_CAP_C0805-100UF,4V,20%,X6S,CA]
    1  PVCCINFAON_CPU0      A  @S9S_MB_2U_LIB.S9S_MB_2U(SCH_1):PVCCINFAON_CPU0
    2  GND                B  @S9S_MB_2U_LIB.S9S_MB_2U(SCH_1):GND

Q_CAP  I31  C529   [Q_CAP_C0805-100UF,4V,20%,X6S,CA]
    1  PVCCFA_EHV_FIVRA_CPU0      A  @S9S_MB_2U_LIB.S9S_MB_2U(SCH_1):PVCCFA_EHV_FIVRA_CPU0
    2  GND                B  @S9S_MB_2U_LIB.S9S_MB_2U(SCH_1):GND

Q_CAP  I117  C530   [Q_CAP_C0805-100UF,4V,20%,X6S,CA]
    1  PVCCINFAON_CPU0      A  @S9S_MB_2U_LIB.S9S_MB_2U(SCH_1):PVCCINFAON_CPU0
    2  GND                B  @S9S_MB_2U_LIB.S9S_MB_2U(SCH_1):GND

Q_CAP  I115  C531   [Q_CAP_C0805-100UF,4V,20%,X6S,CA]
    1  PVCCINFAON_CPU0      A  @S9S_MB_2U_LIB.S9S_MB_2U(SCH_1):PVCCINFAON_CPU0
    2  GND                B  @S9S_MB_2U_LIB.S9S_MB_2U(SCH_1):GND

Q_CAP  I163  C532   [Q_CAP_C0603-47UF,2.5V,20%,X6S,A]
    1  PVCCINFAON_CPU0      A  @S9S_MB_2U_LIB.S9S_MB_2U(SCH_1):PVCCINFAON_CPU0
    2  GND                B  @S9S_MB_2U_LIB.S9S_MB_2U(SCH_1):GND

Q_CAP  I164  C533   [Q_CAP_C0603-47UF,2.5V,20%,X6S,A]
    1  PVCCINFAON_CPU0      A  @S9S_MB_2U_LIB.S9S_MB_2U(SCH_1):PVCCINFAON_CPU0
    2  GND                B  @S9S_MB_2U_LIB.S9S_MB_2U(SCH_1):GND

Q_CAP  I165  C534   [Q_CAP_C0402-22UF,4V,20%,X6S,CHA]
    1  PVCCINFAON_CPU0      A  @S9S_MB_2U_LIB.S9S_MB_2U(SCH_1):PVCCINFAON_CPU0
    2  GND                B  @S9S_MB_2U_LIB.S9S_MB_2U(SCH_1):GND

Q_CAP  I4   C535   [Q_CAP_C0805-22UF,16V,20%,X6S,CA]
    1  PGPPA_AUX          A  @S9S_MB_2U_LIB.S9S_MB_2U(SCH_1):PGPPA_AUX
    2  GND                B  @S9S_MB_2U_LIB.S9S_MB_2U(SCH_1):GND

Q_CAP  I182  C536   [Q_CAP_0402-0.1UF,25V,10%,X7R,CA]
    1  P3V3_AUX           A  @S9S_MB_2U_LIB.S9S_MB_2U(SCH_1):P3V3_AUX
    2  GND                B  @S9S_MB_2U_LIB.S9S_MB_2U(SCH_1):GND

Q_CAP  I24  C537   [Q_CAP_0402-0.1UF,25V,10%,X7R,CA]
    1  P3V3_AUX           A  @S9S_MB_2U_LIB.S9S_MB_2U(SCH_1):P3V3_AUX
    2  GND                B  @S9S_MB_2U_LIB.S9S_MB_2U(SCH_1):GND

Q_CAP  I84  C538   [Q_CAP_0402-0.1UF,25V,10%,X7R,CA]
    1  P3V3_AUX           A  @S9S_MB_2U_LIB.S9S_MB_2U(SCH_1):P3V3_AUX
    2  GND                B  @S9S_MB_2U_LIB.S9S_MB_2U(SCH_1):GND

Q_CAP  I70  C539   [Q_CAP_0402-0.1UF,25V,10%,X7R,CA]
    1  P3V3_AUX           A  @S9S_MB_2U_LIB.S9S_MB_2U(SCH_1):P3V3_AUX
    2  GND                B  @S9S_MB_2U_LIB.S9S_MB_2U(SCH_1):GND

Q_CAP  I81  C540   [Q_CAP_0402-0.1UF,25V,10%,X7R,CA]
    1  P3V3_AUX           A  @S9S_MB_2U_LIB.S9S_MB_2U(SCH_1):P3V3_AUX
    2  GND                B  @S9S_MB_2U_LIB.S9S_MB_2U(SCH_1):GND

Q_CAP  I61  C541   [Q_CAP_C0402-1UF,25V,10%,X6S,CHA]
    1  P3V3_AUX           A  @S9S_MB_2U_LIB.S9S_MB_2U(SCH_1):P3V3_AUX
    2  GND                B  @S9S_MB_2U_LIB.S9S_MB_2U(SCH_1):GND

Q_CAP  I80  C542   [Q_CAP_C0402-1UF,25V,10%,X6S,CHA]
    1  P3V3_AUX           A  @S9S_MB_2U_LIB.S9S_MB_2U(SCH_1):P3V3_AUX
    2  GND                B  @S9S_MB_2U_LIB.S9S_MB_2U(SCH_1):GND

Q_CAP  I100  C543   [Q_CAP_0402-0.1UF,25V,10%,X7R,CA]
    1  P3V3_AUX           A  @S9S_MB_2U_LIB.S9S_MB_2U(SCH_1):P3V3_AUX
    2  GND                B  @S9S_MB_2U_LIB.S9S_MB_2U(SCH_1):GND

Q_CAP  I94  C544   [Q_CAP_0402-0.1UF,25V,10%,X7R,CA]
    1  P3V3_AUX           A  @S9S_MB_2U_LIB.S9S_MB_2U(SCH_1):P3V3_AUX
    2  GND                B  @S9S_MB_2U_LIB.S9S_MB_2U(SCH_1):GND

Q_CAP  I93  C545   [Q_CAP_C0402-1UF,25V,10%,X6S,CHA]
    1  P3V3_AUX           A  @S9S_MB_2U_LIB.S9S_MB_2U(SCH_1):P3V3_AUX
    2  GND                B  @S9S_MB_2U_LIB.S9S_MB_2U(SCH_1):GND

Q_CAP  I135  C546   [Q_CAP_C0402-1UF,25V,10%,X6S,CHA]
    1  P3V3_AUX           A  @S9S_MB_2U_LIB.S9S_MB_2U(SCH_1):P3V3_AUX
    2  GND                B  @S9S_MB_2U_LIB.S9S_MB_2U(SCH_1):GND

Q_CAP  I100  C547   [Q_CAP_C0402-1UF,25V,10%,X6S,CHA]
    1  P1V05_PCH_AUX      A  @S9S_MB_2U_LIB.S9S_MB_2U(SCH_1):P1V05_PCH_AUX
    2  GND                B  @S9S_MB_2U_LIB.S9S_MB_2U(SCH_1):GND

Q_CAP  I130  C548   [Q_CAP_0402-0.1UF,25V,10%,X7R,CA]
    1  JTAG_DBP_POWER_BTN_N      A  @S9S_MB_2U_LIB.S9S_MB_2U(SCH_1):JTAG_DBP_POWER_BTN_N
    2  GND                B  @S9S_MB_2U_LIB.S9S_MB_2U(SCH_1):GND

Q_CAP  I129  C549   [Q_CAP_0402-0.1UF,25V,10%,X7R,CA]
    1  JTAG_RST_DBP_RST_CO_N      A  @S9S_MB_2U_LIB.S9S_MB_2U(SCH_1):JTAG_RST_DBP_RST_CO_N
    2  GND                B  @S9S_MB_2U_LIB.S9S_MB_2U(SCH_1):GND

Q_CAP  I99  C550   [Q_CAP_C0402-1UF,25V,10%,X6S,CHA]
    1  P1V8_PCH_AUX       A  @S9S_MB_2U_LIB.S9S_MB_2U(SCH_1):P1V8_PCH_AUX
    2  GND                B  @S9S_MB_2U_LIB.S9S_MB_2U(SCH_1):GND

Q_CAP  I105  C551   [Q_CAP_C0402-1UF,25V,10%,X6S,CHA]
    1  P3V3_AUX           A  @S9S_MB_2U_LIB.S9S_MB_2U(SCH_1):P3V3_AUX
    2  GND                B  @S9S_MB_2U_LIB.S9S_MB_2U(SCH_1):GND

Q_CAP  I96  C552   [Q_CAP_0402-0.1UF,25V,10%,X7R,CA]
    2  GND                B  @S9S_MB_2U_LIB.S9S_MB_2U(SCH_1):GND
    1  FM_CPU_FBRK_DEBUG_N      A  @S9S_MB_2U_LIB.S9S_MB_2U(SCH_1):FM_CPU_FBRK_DEBUG_N

Q_CAP  I40  C553   [Q_CAP_0402-0.1UF,25V,10%,X7R,CA]
    1  P3V3_AUX           A  @S9S_MB_2U_LIB.S9S_MB_2U(SCH_1):P3V3_AUX
    2  GND                B  @S9S_MB_2U_LIB.S9S_MB_2U(SCH_1):GND

Q_CAP  I52  C554   [Q_CAP_0402-0.1UF,25V,10%,X7R,CA]
    1  P3V3_AUX           A  @S9S_MB_2U_LIB.S9S_MB_2U(SCH_1):P3V3_AUX
    2  GND                B  @S9S_MB_2U_LIB.S9S_MB_2U(SCH_1):GND

Q_CAP  I20  C559   [Q_CAP_0402-0.1UF,25V,10%,X7R,CA]
    1  PVNN_TERM_CPU0      A  @S9S_MB_2U_LIB.S9S_MB_2U(SCH_1):PVNN_TERM_CPU0
    2  GND                B  @S9S_MB_2U_LIB.S9S_MB_2U(SCH_1):GND

Q_CAP  I42  C560   [Q_CAP_0402-0.1UF,25V,10%,X7R,CA]
    1  PVNN_TERM_CPU1      A  @S9S_MB_2U_LIB.S9S_MB_2U(SCH_1):PVNN_TERM_CPU1
    2  GND                B  @S9S_MB_2U_LIB.S9S_MB_2U(SCH_1):GND

Q_CAP  I18  C561   [Q_CAP_0402-0.1UF,25V,10%,X7R,CA]
    1  P3V3_AUX           A  @S9S_MB_2U_LIB.S9S_MB_2U(SCH_1):P3V3_AUX
    2  GND                B  @S9S_MB_2U_LIB.S9S_MB_2U(SCH_1):GND

Q_CAP  I31  C562   [Q_CAP_0402-0.1UF,25V,10%,X7R,CA]
    1  P3V3_AUX           A  @S9S_MB_2U_LIB.S9S_MB_2U(SCH_1):P3V3_AUX
    2  GND                B  @S9S_MB_2U_LIB.S9S_MB_2U(SCH_1):GND

Q_CAP  I50  C563   [Q_CAP_C0805-10UF,25V,10%,X6S,CA]
    1  P3V3_AUX           A  @S9S_MB_2U_LIB.S9S_MB_2U(SCH_1):P3V3_AUX
    2  GND                B  @S9S_MB_2U_LIB.S9S_MB_2U(SCH_1):GND

Q_CAP  I9   C564   [Q_CAP_0402-0.1UF,25V,10%,X7R,CA]
    1  PU_USB_INT_P5V_EN_N      A  @S9S_MB_2U_LIB.S9S_MB_2U(SCH_1):PU_USB_INT_P5V_EN_N
    2  GND                B  @S9S_MB_2U_LIB.S9S_MB_2U(SCH_1):GND

Q_CAP  I23  C565   [Q_CAP_0402-0.1UF,25V,10%,X7R,CA]
    2  USB3_9_TX_DN_C      B  @S9S_MB_2U_LIB.S9S_MB_2U(SCH_1):USB3_9_TX_DN_C
    1  USB3_9_TX_DN       A  @S9S_MB_2U_LIB.S9S_MB_2U(SCH_1):USB3_9_TX_DN

Q_CAP  I17  C566   [Q_CAP_0402-0.1UF,25V,10%,X7R,CA]
    2  USB3_9_TX_DP_C      B  @S9S_MB_2U_LIB.S9S_MB_2U(SCH_1):USB3_9_TX_DP_C
    1  USB3_9_TX_DP       A  @S9S_MB_2U_LIB.S9S_MB_2U(SCH_1):USB3_9_TX_DP

Q_CAP  I25  C567   [Q_CAP_0402-0.1UF,25V,10%,X7R,CA]
    1  PVNN_TERM_CPU0      A  @S9S_MB_2U_LIB.S9S_MB_2U(SCH_1):PVNN_TERM_CPU0
    2  GND                B  @S9S_MB_2U_LIB.S9S_MB_2U(SCH_1):GND

Q_CAP  I35  C568   [Q_CAP_0402-0.1UF,25V,10%,X7R,CA]
    1  PVNN_TERM_CPU1      A  @S9S_MB_2U_LIB.S9S_MB_2U(SCH_1):PVNN_TERM_CPU1
    2  GND                B  @S9S_MB_2U_LIB.S9S_MB_2U(SCH_1):GND

Q_CAP  I22  C569   [Q_CAP_0402-0.1UF,25V,10%,X7R,CA]
    1  P3V3_AUX           A  @S9S_MB_2U_LIB.S9S_MB_2U(SCH_1):P3V3_AUX
    2  GND                B  @S9S_MB_2U_LIB.S9S_MB_2U(SCH_1):GND

Q_CAP  I33  C570   [Q_CAP_0402-0.1UF,25V,10%,X7R,CA]
    1  P3V3_AUX           A  @S9S_MB_2U_LIB.S9S_MB_2U(SCH_1):P3V3_AUX
    2  GND                B  @S9S_MB_2U_LIB.S9S_MB_2U(SCH_1):GND

Q_CAP  I19  C575   [Q_CAP_C0402-100NF,50V,10%,X7R,A]
    1  P3V3_E1S_3_DVDT      A  @S9S_MB_2U_LIB.S9S_MB_2U(SCH_1):P3V3_E1S_3_DVDT
    2  GND                B  @S9S_MB_2U_LIB.S9S_MB_2U(SCH_1):GND

Q_CAP  I169  C578   [Q_CAP_0402-0.1UF,25V,10%,X7R,CA]
    1  P3V3_AUX           A  @S9S_MB_2U_LIB.S9S_MB_2U(SCH_1):P3V3_AUX
    2  GND                B  @S9S_MB_2U_LIB.S9S_MB_2U(SCH_1):GND

Q_CAP  I123  C579   [Q_CAP_0402-0.1UF,25V,10%,X7R,CA]
    1  P3V3_AUX           A  @S9S_MB_2U_LIB.S9S_MB_2U(SCH_1):P3V3_AUX
    2  GND                B  @S9S_MB_2U_LIB.S9S_MB_2U(SCH_1):GND

Q_CAP  I165  C580   [Q_CAP_0402-0.1UF,25V,10%,X7R,CA]
    1  P3V3_AUX           A  @S9S_MB_2U_LIB.S9S_MB_2U(SCH_1):P3V3_AUX
    2  GND                B  @S9S_MB_2U_LIB.S9S_MB_2U(SCH_1):GND

Q_CAP  I148  C581   [Q_CAP_0402-0.1UF,25V,10%,X7R,CA]
    1  P3V3_AUX           A  @S9S_MB_2U_LIB.S9S_MB_2U(SCH_1):P3V3_AUX
    2  GND                B  @S9S_MB_2U_LIB.S9S_MB_2U(SCH_1):GND

Q_CAP  I353  C582   [Q_CAP_C0402-100NF,50V,10%,X7R,A]
    1  P3V3_OCP_DVDT_1      A  @S9S_MB_2U_LIB.S9S_MB_2U(SCH_1):P3V3_OCP_DVDT_1
    2  GND                B  @S9S_MB_2U_LIB.S9S_MB_2U(SCH_1):GND

Q_CAP  I382  C583   [Q_CAP_C0402-1UF,16V,10%,X6S,CHA]
    1  P12V_AUX           A  @S9S_MB_2U_LIB.S9S_MB_2U(SCH_1):P12V_AUX
    2  GND                B  @S9S_MB_2U_LIB.S9S_MB_2U(SCH_1):GND

Q_CAP  I381  C586   [Q_CAP_0402-0.1UF,25V,10%,X7R,CA]
    1  P12V_AUX           A  @S9S_MB_2U_LIB.S9S_MB_2U(SCH_1):P12V_AUX
    2  GND                B  @S9S_MB_2U_LIB.S9S_MB_2U(SCH_1):GND

Q_CAP  I347  C587   [Q_CAP_C0805-10UF,25V,10%,X6S,CA]
    1  P3V3_OCP_SFF       A  @S9S_MB_2U_LIB.S9S_MB_2U(SCH_1):P3V3_OCP_SFF
    2  GND                B  @S9S_MB_2U_LIB.S9S_MB_2U(SCH_1):GND

Q_CAP  I373  C588   [Q_CAP_C0402-3900PF,50V,10%,X7RA]
    1  P12V_OCP_ITIMER_1      A  @S9S_MB_2U_LIB.S9S_MB_2U(SCH_1):P12V_OCP_ITIMER_1
    2  GND                B  @S9S_MB_2U_LIB.S9S_MB_2U(SCH_1):GND

Q_CAP  I369  C589   [Q_CAP_C0402-1UF,16V,10%,X6S,CHA]
    1  P12V_OCP_SFF       A  @S9S_MB_2U_LIB.S9S_MB_2U(SCH_1):P12V_OCP_SFF
    2  GND                B  @S9S_MB_2U_LIB.S9S_MB_2U(SCH_1):GND

Q_CAP  I171  C590   [Q_CAP_C0402-22UF,4V,20%,X6S,CHA]
    1  PVNN_MAIN_CPU0      A  @S9S_MB_2U_LIB.S9S_MB_2U(SCH_1):PVNN_MAIN_CPU0
    2  GND                B  @S9S_MB_2U_LIB.S9S_MB_2U(SCH_1):GND

Q_CAP  I371  C591   [Q_CAP_0402-3300PF,50V,10%,X7R,A]
    1  P12V_OCP_DVDT_1      A  @S9S_MB_2U_LIB.S9S_MB_2U(SCH_1):P12V_OCP_DVDT_1
    2  GND                B  @S9S_MB_2U_LIB.S9S_MB_2U(SCH_1):GND

Q_CAP  I393  C592   [Q_CAP_0402-0.1UF,25V,10%,X7R,CA]
    1  P3V3_AUX           A  @S9S_MB_2U_LIB.S9S_MB_2U(SCH_1):P3V3_AUX
    2  GND                B  @S9S_MB_2U_LIB.S9S_MB_2U(SCH_1):GND

Q_CAP  I395  C593   [Q_CAP_0402-0.1UF,25V,10%,X7R,CA]
    1  P3V3_AUX           A  @S9S_MB_2U_LIB.S9S_MB_2U(SCH_1):P3V3_AUX
    2  GND                B  @S9S_MB_2U_LIB.S9S_MB_2U(SCH_1):GND

Q_CAP  I37  C605   [Q_CAP_C0402-1UF,25V,10%,X6S,CHA]
    1  PGPPA_AUX          A  @S9S_MB_2U_LIB.S9S_MB_2U(SCH_1):PGPPA_AUX
    2  GND                B  @S9S_MB_2U_LIB.S9S_MB_2U(SCH_1):GND

Q_CAP  I45  C606   [Q_CAP_C0402-1UF,25V,10%,X6S,CHA]
    1  PGPPA_AUX          A  @S9S_MB_2U_LIB.S9S_MB_2U(SCH_1):PGPPA_AUX
    2  GND                B  @S9S_MB_2U_LIB.S9S_MB_2U(SCH_1):GND

Q_CAP  I36  C607   [Q_CAP_0402-0.1UF,25V,10%,X7R,CA]
    1  PGPPA_AUX          A  @S9S_MB_2U_LIB.S9S_MB_2U(SCH_1):PGPPA_AUX
    2  GND                B  @S9S_MB_2U_LIB.S9S_MB_2U(SCH_1):GND

Q_CAP  I43  C608   [Q_CAP_0402-0.1UF,25V,10%,X7R,CA]
    1  PGPPA_AUX          A  @S9S_MB_2U_LIB.S9S_MB_2U(SCH_1):PGPPA_AUX
    2  GND                B  @S9S_MB_2U_LIB.S9S_MB_2U(SCH_1):GND

Q_CAP  I89  C609   [Q_CAP_0402-0.1UF,25V,10%,X7R,CA]
    1  RTC_EXT_CAP        A  @S9S_MB_2U_LIB.S9S_MB_2U(SCH_1):RTC_EXT_CAP
    2  GND                B  @S9S_MB_2U_LIB.S9S_MB_2U(SCH_1):GND

Q_CAP  I68  C610   [Q_CAP_C0402-1UF,25V,10%,X6S,CHA]
    1  RST_SRTCRST_N      A  @S9S_MB_2U_LIB.S9S_MB_2U(SCH_1):RST_SRTCRST_N
    2  GND                B  @S9S_MB_2U_LIB.S9S_MB_2U(SCH_1):GND

Q_CAP  I65  C611   [Q_CAP_C0402-1UF,25V,10%,X6S,CHA]
    1  P3V3_RTC_AUX       A  @S9S_MB_2U_LIB.S9S_MB_2U(SCH_1):P3V3_RTC_AUX
    2  GND                B  @S9S_MB_2U_LIB.S9S_MB_2U(SCH_1):GND

Q_CAP  I68  C613   [Q_CAP_C0402-1UF,25V,10%,EMPTY,A]
    1  RST_PLD_CPU1_DRAM_GH_N      A  @S9S_MB_2U_LIB.S9S_MB_2U(SCH_1):RST_PLD_CPU1_DRAM_GH_N
    2  GND                B  @S9S_MB_2U_LIB.S9S_MB_2U(SCH_1):GND

Q_CAP  I65  C614   [Q_CAP_C0402-1UF,25V,10%,EMPTY,A]
    1  RST_PLD_CPU1_DRAM_AB_N      A  @S9S_MB_2U_LIB.S9S_MB_2U(SCH_1):RST_PLD_CPU1_DRAM_AB_N
    2  GND                B  @S9S_MB_2U_LIB.S9S_MB_2U(SCH_1):GND

Q_CAP  I62  C615   [Q_CAP_C0402-1UF,25V,10%,EMPTY,A]
    1  RST_PLD_CPU1_DRAM_CD_N      A  @S9S_MB_2U_LIB.S9S_MB_2U(SCH_1):RST_PLD_CPU1_DRAM_CD_N
    2  GND                B  @S9S_MB_2U_LIB.S9S_MB_2U(SCH_1):GND

Q_CAP  I59  C616   [Q_CAP_C0402-1UF,25V,10%,EMPTY,A]
    1  RST_PLD_CPU1_DRAM_EF_N      A  @S9S_MB_2U_LIB.S9S_MB_2U(SCH_1):RST_PLD_CPU1_DRAM_EF_N
    2  GND                B  @S9S_MB_2U_LIB.S9S_MB_2U(SCH_1):GND

Q_CAP  I102  C621   [Q_CAP_C0402-1UF,25V,10%,EMPTY,A]
    1  RST_PLD_CPU0_DRAM_GH_N      A  @S9S_MB_2U_LIB.S9S_MB_2U(SCH_1):RST_PLD_CPU0_DRAM_GH_N
    2  GND                B  @S9S_MB_2U_LIB.S9S_MB_2U(SCH_1):GND

Q_CAP  I91  C622   [Q_CAP_C0402-1UF,25V,10%,EMPTY,A]
    1  RST_PLD_CPU0_DRAM_AB_N      A  @S9S_MB_2U_LIB.S9S_MB_2U(SCH_1):RST_PLD_CPU0_DRAM_AB_N
    2  GND                B  @S9S_MB_2U_LIB.S9S_MB_2U(SCH_1):GND

Q_CAP  I94  C623   [Q_CAP_C0402-1UF,25V,10%,EMPTY,A]
    1  RST_PLD_CPU0_DRAM_CD_N      A  @S9S_MB_2U_LIB.S9S_MB_2U(SCH_1):RST_PLD_CPU0_DRAM_CD_N
    2  GND                B  @S9S_MB_2U_LIB.S9S_MB_2U(SCH_1):GND

Q_CAP  I99  C624   [Q_CAP_C0402-1UF,25V,10%,EMPTY,A]
    1  RST_PLD_CPU0_DRAM_EF_N      A  @S9S_MB_2U_LIB.S9S_MB_2U(SCH_1):RST_PLD_CPU0_DRAM_EF_N
    2  GND                B  @S9S_MB_2U_LIB.S9S_MB_2U(SCH_1):GND

Q_CAP  I55  C629   [Q_CAP_0402-0.1UF,25V,10%,X7R,CA]
    1  P3V3_AUX           A  @S9S_MB_2U_LIB.S9S_MB_2U(SCH_1):P3V3_AUX
    2  GND                B  @S9S_MB_2U_LIB.S9S_MB_2U(SCH_1):GND

Q_CAP  I10  C630   [Q_CAP_0402-0.1UF,25V,10%,X7R,CA]
    1  P3V3_AUX           A  @S9S_MB_2U_LIB.S9S_MB_2U(SCH_1):P3V3_AUX
    2  GND                B  @S9S_MB_2U_LIB.S9S_MB_2U(SCH_1):GND

Q_CAP  I75  C631   [Q_CAP_0402-0.1UF,25V,10%,X7R,CA]
    1  P3V3_AUX           A  @S9S_MB_2U_LIB.S9S_MB_2U(SCH_1):P3V3_AUX
    2  GND                B  @S9S_MB_2U_LIB.S9S_MB_2U(SCH_1):GND

Q_CAP  I59  C632   [Q_CAP_C0805-10UF,25V,10%,X6S,CA]
    1  P12V_FRONT_CPU      A  @S9S_MB_2U_LIB.S9S_MB_2U(SCH_1):P12V_FRONT_CPU
    2  GND                B  @S9S_MB_2U_LIB.S9S_MB_2U(SCH_1):GND

Q_CAP  I61  C633   [Q_CAP_C0805-22UF,25V,20%,X5R,CA]
    1  P5V                A  @S9S_MB_2U_LIB.S9S_MB_2U(SCH_1):P5V
    2  GND                B  @S9S_MB_2U_LIB.S9S_MB_2U(SCH_1):GND

Q_CAP_SATA6G  I10  C634   [Q_CAP_SATA6G_C0402-SATA6G_0.01A]
    2  SATA_P11_TX_DP      2  @S9S_MB_2U_LIB.S9S_MB_2U(SCH_1):SATA_P11_TX_DP
    1  SATA_P11_TX_C_DP      1  @S9S_MB_2U_LIB.S9S_MB_2U(SCH_1):SATA_P11_TX_C_DP

Q_CAP_SATA6G  I11  C635   [Q_CAP_SATA6G_C0402-SATA6G_0.01A]
    2  SATA_P11_TX_DN      2  @S9S_MB_2U_LIB.S9S_MB_2U(SCH_1):SATA_P11_TX_DN
    1  SATA_P11_TX_C_DN      1  @S9S_MB_2U_LIB.S9S_MB_2U(SCH_1):SATA_P11_TX_C_DN

Q_CAP_SATA6G  I12  C636   [Q_CAP_SATA6G_C0402-SATA6G_0.01A]
    2  SATA_P11_RX_DN      2  @S9S_MB_2U_LIB.S9S_MB_2U(SCH_1):SATA_P11_RX_DN
    1  SATA_P11_RX_C_DN      1  @S9S_MB_2U_LIB.S9S_MB_2U(SCH_1):SATA_P11_RX_C_DN

Q_CAP_SATA6G  I13  C637   [Q_CAP_SATA6G_C0402-SATA6G_0.01A]
    2  SATA_P11_RX_DP      2  @S9S_MB_2U_LIB.S9S_MB_2U(SCH_1):SATA_P11_RX_DP
    1  SATA_P11_RX_C_DP      1  @S9S_MB_2U_LIB.S9S_MB_2U(SCH_1):SATA_P11_RX_C_DP

Q_CAP  I63  C638   [Q_CAP_0402-0.1UF,25V,10%,X7R,CA]
    1  P5V                A  @S9S_MB_2U_LIB.S9S_MB_2U(SCH_1):P5V
    2  GND                B  @S9S_MB_2U_LIB.S9S_MB_2U(SCH_1):GND

Q_CAP  I59  C639   [Q_CAP_0402-0.1UF,25V,10%,X7R,CA]
    1  P3V3_AUX           A  @S9S_MB_2U_LIB.S9S_MB_2U(SCH_1):P3V3_AUX
    2  GND                B  @S9S_MB_2U_LIB.S9S_MB_2U(SCH_1):GND

Q_CAP  I47  C640   [Q_CAP_0402-0.1UF,25V,10%,X7R,CA]
    1  P3V3_AUX           A  @S9S_MB_2U_LIB.S9S_MB_2U(SCH_1):P3V3_AUX
    2  GND                B  @S9S_MB_2U_LIB.S9S_MB_2U(SCH_1):GND

Q_CAP  I16  C641   [Q_CAP_0402-0.1UF,25V,10%,X7R,CA]
    1  P3V3_AUX           A  @S9S_MB_2U_LIB.S9S_MB_2U(SCH_1):P3V3_AUX
    2  GND                B  @S9S_MB_2U_LIB.S9S_MB_2U(SCH_1):GND

Q_CAP_DIFFBUS  I195  C643   [Q_CAP_DIFFBUS_C0402-DIFF BUS_0A]
    1  P3E_PCH_BMC_TX_DP      1  @S9S_MB_2U_LIB.S9S_MB_2U(SCH_1):P3E_PCH_BMC_TX_DP
    2  P3E_PCH_BMC_TX_C_DP      2  @S9S_MB_2U_LIB.S9S_MB_2U(SCH_1):P3E_PCH_BMC_TX_C_DP

Q_CAP_DIFFBUS  I194  C644   [Q_CAP_DIFFBUS_C0402-DIFF BUS_0A]
    1  P3E_PCH_BMC_TX_DN      1  @S9S_MB_2U_LIB.S9S_MB_2U(SCH_1):P3E_PCH_BMC_TX_DN
    2  P3E_PCH_BMC_TX_C_DN      2  @S9S_MB_2U_LIB.S9S_MB_2U(SCH_1):P3E_PCH_BMC_TX_C_DN

Q_CAP_DIFFBUS  I172  C678   [Q_CAP_DIFFBUS_C0201-DIFF BUS_0A]
    2  P5E_CPU1_PE4_TX_DN<15>      2  @S9S_MB_2U_LIB.S9S_MB_2U(SCH_1):P5E_CPU1_PE4_TX_DN<15>
    1  P5E_CPU1_PE4_TX_C_DN<15>      1  @S9S_MB_2U_LIB.S9S_MB_2U(SCH_1):P5E_CPU1_PE4_TX_C_DN<15>

Q_CAP_DIFFBUS  I169  C679   [Q_CAP_DIFFBUS_C0201-DIFF BUS_0A]
    2  P5E_CPU1_PE4_TX_DP<15>      2  @S9S_MB_2U_LIB.S9S_MB_2U(SCH_1):P5E_CPU1_PE4_TX_DP<15>
    1  P5E_CPU1_PE4_TX_C_DP<15>      1  @S9S_MB_2U_LIB.S9S_MB_2U(SCH_1):P5E_CPU1_PE4_TX_C_DP<15>

Q_CAP_DIFFBUS  I170  C680   [Q_CAP_DIFFBUS_C0201-DIFF BUS_0A]
    2  P5E_CPU1_PE4_TX_DN<14>      2  @S9S_MB_2U_LIB.S9S_MB_2U(SCH_1):P5E_CPU1_PE4_TX_DN<14>
    1  P5E_CPU1_PE4_TX_C_DN<14>      1  @S9S_MB_2U_LIB.S9S_MB_2U(SCH_1):P5E_CPU1_PE4_TX_C_DN<14>

Q_CAP_DIFFBUS  I171  C681   [Q_CAP_DIFFBUS_C0201-DIFF BUS_0A]
    2  P5E_CPU1_PE4_TX_DP<14>      2  @S9S_MB_2U_LIB.S9S_MB_2U(SCH_1):P5E_CPU1_PE4_TX_DP<14>
    1  P5E_CPU1_PE4_TX_C_DP<14>      1  @S9S_MB_2U_LIB.S9S_MB_2U(SCH_1):P5E_CPU1_PE4_TX_C_DP<14>

Q_CAP_DIFFBUS  I167  C682   [Q_CAP_DIFFBUS_C0201-DIFF BUS_0A]
    2  P5E_CPU1_PE4_TX_DN<13>      2  @S9S_MB_2U_LIB.S9S_MB_2U(SCH_1):P5E_CPU1_PE4_TX_DN<13>
    1  P5E_CPU1_PE4_TX_C_DN<13>      1  @S9S_MB_2U_LIB.S9S_MB_2U(SCH_1):P5E_CPU1_PE4_TX_C_DN<13>

Q_CAP_DIFFBUS  I168  C683   [Q_CAP_DIFFBUS_C0201-DIFF BUS_0A]
    2  P5E_CPU1_PE4_TX_DP<13>      2  @S9S_MB_2U_LIB.S9S_MB_2U(SCH_1):P5E_CPU1_PE4_TX_DP<13>
    1  P5E_CPU1_PE4_TX_C_DP<13>      1  @S9S_MB_2U_LIB.S9S_MB_2U(SCH_1):P5E_CPU1_PE4_TX_C_DP<13>

Q_CAP_DIFFBUS  I166  C684   [Q_CAP_DIFFBUS_C0201-DIFF BUS_0A]
    2  P5E_CPU1_PE4_TX_DN<12>      2  @S9S_MB_2U_LIB.S9S_MB_2U(SCH_1):P5E_CPU1_PE4_TX_DN<12>
    1  P5E_CPU1_PE4_TX_C_DN<12>      1  @S9S_MB_2U_LIB.S9S_MB_2U(SCH_1):P5E_CPU1_PE4_TX_C_DN<12>

Q_CAP_DIFFBUS  I165  C685   [Q_CAP_DIFFBUS_C0201-DIFF BUS_0A]
    2  P5E_CPU1_PE4_TX_DP<12>      2  @S9S_MB_2U_LIB.S9S_MB_2U(SCH_1):P5E_CPU1_PE4_TX_DP<12>
    1  P5E_CPU1_PE4_TX_C_DP<12>      1  @S9S_MB_2U_LIB.S9S_MB_2U(SCH_1):P5E_CPU1_PE4_TX_C_DP<12>

Q_CAP_DIFFBUS  I164  C686   [Q_CAP_DIFFBUS_C0201-DIFF BUS_0A]
    2  P5E_CPU1_PE4_TX_DN<11>      2  @S9S_MB_2U_LIB.S9S_MB_2U(SCH_1):P5E_CPU1_PE4_TX_DN<11>
    1  P5E_CPU1_PE4_TX_C_DN<11>      1  @S9S_MB_2U_LIB.S9S_MB_2U(SCH_1):P5E_CPU1_PE4_TX_C_DN<11>

Q_CAP_DIFFBUS  I161  C687   [Q_CAP_DIFFBUS_C0201-DIFF BUS_0A]
    2  P5E_CPU1_PE4_TX_DP<11>      2  @S9S_MB_2U_LIB.S9S_MB_2U(SCH_1):P5E_CPU1_PE4_TX_DP<11>
    1  P5E_CPU1_PE4_TX_C_DP<11>      1  @S9S_MB_2U_LIB.S9S_MB_2U(SCH_1):P5E_CPU1_PE4_TX_C_DP<11>

Q_CAP_DIFFBUS  I162  C688   [Q_CAP_DIFFBUS_C0201-DIFF BUS_0A]
    2  P5E_CPU1_PE4_TX_DN<10>      2  @S9S_MB_2U_LIB.S9S_MB_2U(SCH_1):P5E_CPU1_PE4_TX_DN<10>
    1  P5E_CPU1_PE4_TX_C_DN<10>      1  @S9S_MB_2U_LIB.S9S_MB_2U(SCH_1):P5E_CPU1_PE4_TX_C_DN<10>

Q_CAP_DIFFBUS  I163  C689   [Q_CAP_DIFFBUS_C0201-DIFF BUS_0A]
    2  P5E_CPU1_PE4_TX_DP<10>      2  @S9S_MB_2U_LIB.S9S_MB_2U(SCH_1):P5E_CPU1_PE4_TX_DP<10>
    1  P5E_CPU1_PE4_TX_C_DP<10>      1  @S9S_MB_2U_LIB.S9S_MB_2U(SCH_1):P5E_CPU1_PE4_TX_C_DP<10>

Q_CAP_DIFFBUS  I159  C690   [Q_CAP_DIFFBUS_C0201-DIFF BUS_0A]
    2  P5E_CPU1_PE4_TX_DN<9>      2  @S9S_MB_2U_LIB.S9S_MB_2U(SCH_1):P5E_CPU1_PE4_TX_DN<9>
    1  P5E_CPU1_PE4_TX_C_DN<9>      1  @S9S_MB_2U_LIB.S9S_MB_2U(SCH_1):P5E_CPU1_PE4_TX_C_DN<9>

Q_CAP_DIFFBUS  I160  C691   [Q_CAP_DIFFBUS_C0201-DIFF BUS_0A]
    2  P5E_CPU1_PE4_TX_DP<9>      2  @S9S_MB_2U_LIB.S9S_MB_2U(SCH_1):P5E_CPU1_PE4_TX_DP<9>
    1  P5E_CPU1_PE4_TX_C_DP<9>      1  @S9S_MB_2U_LIB.S9S_MB_2U(SCH_1):P5E_CPU1_PE4_TX_C_DP<9>

Q_CAP_DIFFBUS  I158  C692   [Q_CAP_DIFFBUS_C0201-DIFF BUS_0A]
    2  P5E_CPU1_PE4_TX_DN<8>      2  @S9S_MB_2U_LIB.S9S_MB_2U(SCH_1):P5E_CPU1_PE4_TX_DN<8>
    1  P5E_CPU1_PE4_TX_C_DN<8>      1  @S9S_MB_2U_LIB.S9S_MB_2U(SCH_1):P5E_CPU1_PE4_TX_C_DN<8>

Q_CAP_DIFFBUS  I157  C693   [Q_CAP_DIFFBUS_C0201-DIFF BUS_0A]
    2  P5E_CPU1_PE4_TX_DP<8>      2  @S9S_MB_2U_LIB.S9S_MB_2U(SCH_1):P5E_CPU1_PE4_TX_DP<8>
    1  P5E_CPU1_PE4_TX_C_DP<8>      1  @S9S_MB_2U_LIB.S9S_MB_2U(SCH_1):P5E_CPU1_PE4_TX_C_DP<8>

Q_CAP_DIFFBUS  I140  C694   [Q_CAP_DIFFBUS_C0201-DIFF BUS_0A]
    2  P5E_CPU1_PE4_TX_DN<7>      2  @S9S_MB_2U_LIB.S9S_MB_2U(SCH_1):P5E_CPU1_PE4_TX_DN<7>
    1  P5E_CPU1_PE4_TX_C_DN<7>      1  @S9S_MB_2U_LIB.S9S_MB_2U(SCH_1):P5E_CPU1_PE4_TX_C_DN<7>

Q_CAP_DIFFBUS  I139  C695   [Q_CAP_DIFFBUS_C0201-DIFF BUS_0A]
    2  P5E_CPU1_PE4_TX_DP<7>      2  @S9S_MB_2U_LIB.S9S_MB_2U(SCH_1):P5E_CPU1_PE4_TX_DP<7>
    1  P5E_CPU1_PE4_TX_C_DP<7>      1  @S9S_MB_2U_LIB.S9S_MB_2U(SCH_1):P5E_CPU1_PE4_TX_C_DP<7>

Q_CAP_DIFFBUS  I137  C696   [Q_CAP_DIFFBUS_C0201-DIFF BUS_0A]
    2  P5E_CPU1_PE4_TX_DN<6>      2  @S9S_MB_2U_LIB.S9S_MB_2U(SCH_1):P5E_CPU1_PE4_TX_DN<6>
    1  P5E_CPU1_PE4_TX_C_DN<6>      1  @S9S_MB_2U_LIB.S9S_MB_2U(SCH_1):P5E_CPU1_PE4_TX_C_DN<6>

Q_CAP_DIFFBUS  I138  C697   [Q_CAP_DIFFBUS_C0201-DIFF BUS_0A]
    2  P5E_CPU1_PE4_TX_DP<6>      2  @S9S_MB_2U_LIB.S9S_MB_2U(SCH_1):P5E_CPU1_PE4_TX_DP<6>
    1  P5E_CPU1_PE4_TX_C_DP<6>      1  @S9S_MB_2U_LIB.S9S_MB_2U(SCH_1):P5E_CPU1_PE4_TX_C_DP<6>

Q_CAP_DIFFBUS  I135  C698   [Q_CAP_DIFFBUS_C0201-DIFF BUS_0A]
    2  P5E_CPU1_PE4_TX_DN<5>      2  @S9S_MB_2U_LIB.S9S_MB_2U(SCH_1):P5E_CPU1_PE4_TX_DN<5>
    1  P5E_CPU1_PE4_TX_C_DN<5>      1  @S9S_MB_2U_LIB.S9S_MB_2U(SCH_1):P5E_CPU1_PE4_TX_C_DN<5>

Q_CAP_DIFFBUS  I136  C699   [Q_CAP_DIFFBUS_C0201-DIFF BUS_0A]
    2  P5E_CPU1_PE4_TX_DP<5>      2  @S9S_MB_2U_LIB.S9S_MB_2U(SCH_1):P5E_CPU1_PE4_TX_DP<5>
    1  P5E_CPU1_PE4_TX_C_DP<5>      1  @S9S_MB_2U_LIB.S9S_MB_2U(SCH_1):P5E_CPU1_PE4_TX_C_DP<5>

Q_CAP_DIFFBUS  I134  C700   [Q_CAP_DIFFBUS_C0201-DIFF BUS_0A]
    2  P5E_CPU1_PE4_TX_DN<4>      2  @S9S_MB_2U_LIB.S9S_MB_2U(SCH_1):P5E_CPU1_PE4_TX_DN<4>
    1  P5E_CPU1_PE4_TX_C_DN<4>      1  @S9S_MB_2U_LIB.S9S_MB_2U(SCH_1):P5E_CPU1_PE4_TX_C_DN<4>

Q_CAP_DIFFBUS  I131  C701   [Q_CAP_DIFFBUS_C0201-DIFF BUS_0A]
    2  P5E_CPU1_PE4_TX_DP<4>      2  @S9S_MB_2U_LIB.S9S_MB_2U(SCH_1):P5E_CPU1_PE4_TX_DP<4>
    1  P5E_CPU1_PE4_TX_C_DP<4>      1  @S9S_MB_2U_LIB.S9S_MB_2U(SCH_1):P5E_CPU1_PE4_TX_C_DP<4>

Q_CAP_DIFFBUS  I132  C702   [Q_CAP_DIFFBUS_C0201-DIFF BUS_0A]
    2  P5E_CPU1_PE4_TX_DN<3>      2  @S9S_MB_2U_LIB.S9S_MB_2U(SCH_1):P5E_CPU1_PE4_TX_DN<3>
    1  P5E_CPU1_PE4_TX_C_DN<3>      1  @S9S_MB_2U_LIB.S9S_MB_2U(SCH_1):P5E_CPU1_PE4_TX_C_DN<3>

Q_CAP_DIFFBUS  I133  C703   [Q_CAP_DIFFBUS_C0201-DIFF BUS_0A]
    2  P5E_CPU1_PE4_TX_DP<3>      2  @S9S_MB_2U_LIB.S9S_MB_2U(SCH_1):P5E_CPU1_PE4_TX_DP<3>
    1  P5E_CPU1_PE4_TX_C_DP<3>      1  @S9S_MB_2U_LIB.S9S_MB_2U(SCH_1):P5E_CPU1_PE4_TX_C_DP<3>

Q_CAP_DIFFBUS  I129  C704   [Q_CAP_DIFFBUS_C0201-DIFF BUS_0A]
    2  P5E_CPU1_PE4_TX_DN<2>      2  @S9S_MB_2U_LIB.S9S_MB_2U(SCH_1):P5E_CPU1_PE4_TX_DN<2>
    1  P5E_CPU1_PE4_TX_C_DN<2>      1  @S9S_MB_2U_LIB.S9S_MB_2U(SCH_1):P5E_CPU1_PE4_TX_C_DN<2>

Q_CAP_DIFFBUS  I130  C705   [Q_CAP_DIFFBUS_C0201-DIFF BUS_0A]
    2  P5E_CPU1_PE4_TX_DP<2>      2  @S9S_MB_2U_LIB.S9S_MB_2U(SCH_1):P5E_CPU1_PE4_TX_DP<2>
    1  P5E_CPU1_PE4_TX_C_DP<2>      1  @S9S_MB_2U_LIB.S9S_MB_2U(SCH_1):P5E_CPU1_PE4_TX_C_DP<2>

Q_CAP_DIFFBUS  I127  C706   [Q_CAP_DIFFBUS_C0201-DIFF BUS_0A]
    2  P5E_CPU1_PE4_TX_DN<1>      2  @S9S_MB_2U_LIB.S9S_MB_2U(SCH_1):P5E_CPU1_PE4_TX_DN<1>
    1  P5E_CPU1_PE4_TX_C_DN<1>      1  @S9S_MB_2U_LIB.S9S_MB_2U(SCH_1):P5E_CPU1_PE4_TX_C_DN<1>

Q_CAP_DIFFBUS  I128  C707   [Q_CAP_DIFFBUS_C0201-DIFF BUS_0A]
    2  P5E_CPU1_PE4_TX_DP<1>      2  @S9S_MB_2U_LIB.S9S_MB_2U(SCH_1):P5E_CPU1_PE4_TX_DP<1>
    1  P5E_CPU1_PE4_TX_C_DP<1>      1  @S9S_MB_2U_LIB.S9S_MB_2U(SCH_1):P5E_CPU1_PE4_TX_C_DP<1>

Q_CAP_DIFFBUS  I125  C708   [Q_CAP_DIFFBUS_C0201-DIFF BUS_0A]
    2  P5E_CPU1_PE4_TX_DN<0>      2  @S9S_MB_2U_LIB.S9S_MB_2U(SCH_1):P5E_CPU1_PE4_TX_DN<0>
    1  P5E_CPU1_PE4_TX_C_DN<0>      1  @S9S_MB_2U_LIB.S9S_MB_2U(SCH_1):P5E_CPU1_PE4_TX_C_DN<0>

Q_CAP_DIFFBUS  I126  C709   [Q_CAP_DIFFBUS_C0201-DIFF BUS_0A]
    2  P5E_CPU1_PE4_TX_DP<0>      2  @S9S_MB_2U_LIB.S9S_MB_2U(SCH_1):P5E_CPU1_PE4_TX_DP<0>
    1  P5E_CPU1_PE4_TX_C_DP<0>      1  @S9S_MB_2U_LIB.S9S_MB_2U(SCH_1):P5E_CPU1_PE4_TX_C_DP<0>

Q_CAP_DIFFBUS  I80  C710   [Q_CAP_DIFFBUS_C0201-DIFF BUS_0A]
    2  P5E_CPU1_PE1_TX_DN<15>      2  @S9S_MB_2U_LIB.S9S_MB_2U(SCH_1):P5E_CPU1_PE1_TX_DN<15>
    1  P5E_CPU1_PE1_TX_C_DN<15>      1  @S9S_MB_2U_LIB.S9S_MB_2U(SCH_1):P5E_CPU1_PE1_TX_C_DN<15>

Q_CAP_DIFFBUS  I79  C711   [Q_CAP_DIFFBUS_C0201-DIFF BUS_0A]
    2  P5E_CPU1_PE1_TX_DP<15>      2  @S9S_MB_2U_LIB.S9S_MB_2U(SCH_1):P5E_CPU1_PE1_TX_DP<15>
    1  P5E_CPU1_PE1_TX_C_DP<15>      1  @S9S_MB_2U_LIB.S9S_MB_2U(SCH_1):P5E_CPU1_PE1_TX_C_DP<15>

Q_CAP_DIFFBUS  I81  C712   [Q_CAP_DIFFBUS_C0201-DIFF BUS_0A]
    2  P5E_CPU1_PE1_TX_DN<14>      2  @S9S_MB_2U_LIB.S9S_MB_2U(SCH_1):P5E_CPU1_PE1_TX_DN<14>
    1  P5E_CPU1_PE1_TX_C_DN<14>      1  @S9S_MB_2U_LIB.S9S_MB_2U(SCH_1):P5E_CPU1_PE1_TX_C_DN<14>

Q_CAP_DIFFBUS  I77  C713   [Q_CAP_DIFFBUS_C0201-DIFF BUS_0A]
    2  P5E_CPU1_PE1_TX_DP<14>      2  @S9S_MB_2U_LIB.S9S_MB_2U(SCH_1):P5E_CPU1_PE1_TX_DP<14>
    1  P5E_CPU1_PE1_TX_C_DP<14>      1  @S9S_MB_2U_LIB.S9S_MB_2U(SCH_1):P5E_CPU1_PE1_TX_C_DP<14>

Q_CAP_DIFFBUS  I78  C714   [Q_CAP_DIFFBUS_C0201-DIFF BUS_0A]
    2  P5E_CPU1_PE1_TX_DN<13>      2  @S9S_MB_2U_LIB.S9S_MB_2U(SCH_1):P5E_CPU1_PE1_TX_DN<13>
    1  P5E_CPU1_PE1_TX_C_DN<13>      1  @S9S_MB_2U_LIB.S9S_MB_2U(SCH_1):P5E_CPU1_PE1_TX_C_DN<13>

Q_CAP_DIFFBUS  I76  C715   [Q_CAP_DIFFBUS_C0201-DIFF BUS_0A]
    2  P5E_CPU1_PE1_TX_DP<13>      2  @S9S_MB_2U_LIB.S9S_MB_2U(SCH_1):P5E_CPU1_PE1_TX_DP<13>
    1  P5E_CPU1_PE1_TX_C_DP<13>      1  @S9S_MB_2U_LIB.S9S_MB_2U(SCH_1):P5E_CPU1_PE1_TX_C_DP<13>

Q_CAP_DIFFBUS  I69  C716   [Q_CAP_DIFFBUS_C0201-DIFF BUS_0A]
    2  P5E_CPU1_PE1_TX_DN<12>      2  @S9S_MB_2U_LIB.S9S_MB_2U(SCH_1):P5E_CPU1_PE1_TX_DN<12>
    1  P5E_CPU1_PE1_TX_C_DN<12>      1  @S9S_MB_2U_LIB.S9S_MB_2U(SCH_1):P5E_CPU1_PE1_TX_C_DN<12>

Q_CAP_DIFFBUS  I70  C717   [Q_CAP_DIFFBUS_C0201-DIFF BUS_0A]
    2  P5E_CPU1_PE1_TX_DP<12>      2  @S9S_MB_2U_LIB.S9S_MB_2U(SCH_1):P5E_CPU1_PE1_TX_DP<12>
    1  P5E_CPU1_PE1_TX_C_DP<12>      1  @S9S_MB_2U_LIB.S9S_MB_2U(SCH_1):P5E_CPU1_PE1_TX_C_DP<12>

Q_CAP_DIFFBUS  I67  C718   [Q_CAP_DIFFBUS_C0201-DIFF BUS_0A]
    2  P5E_CPU1_PE1_TX_DN<11>      2  @S9S_MB_2U_LIB.S9S_MB_2U(SCH_1):P5E_CPU1_PE1_TX_DN<11>
    1  P5E_CPU1_PE1_TX_C_DN<11>      1  @S9S_MB_2U_LIB.S9S_MB_2U(SCH_1):P5E_CPU1_PE1_TX_C_DN<11>

Q_CAP_DIFFBUS  I68  C719   [Q_CAP_DIFFBUS_C0201-DIFF BUS_0A]
    2  P5E_CPU1_PE1_TX_DP<11>      2  @S9S_MB_2U_LIB.S9S_MB_2U(SCH_1):P5E_CPU1_PE1_TX_DP<11>
    1  P5E_CPU1_PE1_TX_C_DP<11>      1  @S9S_MB_2U_LIB.S9S_MB_2U(SCH_1):P5E_CPU1_PE1_TX_C_DP<11>

Q_CAP_DIFFBUS  I66  C720   [Q_CAP_DIFFBUS_C0201-DIFF BUS_0A]
    2  P5E_CPU1_PE1_TX_DN<10>      2  @S9S_MB_2U_LIB.S9S_MB_2U(SCH_1):P5E_CPU1_PE1_TX_DN<10>
    1  P5E_CPU1_PE1_TX_C_DN<10>      1  @S9S_MB_2U_LIB.S9S_MB_2U(SCH_1):P5E_CPU1_PE1_TX_C_DN<10>

Q_CAP_DIFFBUS  I64  C721   [Q_CAP_DIFFBUS_C0201-DIFF BUS_0A]
    2  P5E_CPU1_PE1_TX_DP<10>      2  @S9S_MB_2U_LIB.S9S_MB_2U(SCH_1):P5E_CPU1_PE1_TX_DP<10>
    1  P5E_CPU1_PE1_TX_C_DP<10>      1  @S9S_MB_2U_LIB.S9S_MB_2U(SCH_1):P5E_CPU1_PE1_TX_C_DP<10>

Q_CAP_DIFFBUS  I65  C722   [Q_CAP_DIFFBUS_C0201-DIFF BUS_0A]
    2  P5E_CPU1_PE1_TX_DN<9>      2  @S9S_MB_2U_LIB.S9S_MB_2U(SCH_1):P5E_CPU1_PE1_TX_DN<9>
    1  P5E_CPU1_PE1_TX_C_DN<9>      1  @S9S_MB_2U_LIB.S9S_MB_2U(SCH_1):P5E_CPU1_PE1_TX_C_DN<9>

Q_CAP_DIFFBUS  I63  C723   [Q_CAP_DIFFBUS_C0201-DIFF BUS_0A]
    2  P5E_CPU1_PE1_TX_DP<9>      2  @S9S_MB_2U_LIB.S9S_MB_2U(SCH_1):P5E_CPU1_PE1_TX_DP<9>
    1  P5E_CPU1_PE1_TX_C_DP<9>      1  @S9S_MB_2U_LIB.S9S_MB_2U(SCH_1):P5E_CPU1_PE1_TX_C_DP<9>

Q_CAP_DIFFBUS  I62  C724   [Q_CAP_DIFFBUS_C0201-DIFF BUS_0A]
    2  P5E_CPU1_PE1_TX_DN<8>      2  @S9S_MB_2U_LIB.S9S_MB_2U(SCH_1):P5E_CPU1_PE1_TX_DN<8>
    1  P5E_CPU1_PE1_TX_C_DN<8>      1  @S9S_MB_2U_LIB.S9S_MB_2U(SCH_1):P5E_CPU1_PE1_TX_C_DN<8>

Q_CAP_DIFFBUS  I61  C725   [Q_CAP_DIFFBUS_C0201-DIFF BUS_0A]
    2  P5E_CPU1_PE1_TX_DP<8>      2  @S9S_MB_2U_LIB.S9S_MB_2U(SCH_1):P5E_CPU1_PE1_TX_DP<8>
    1  P5E_CPU1_PE1_TX_C_DP<8>      1  @S9S_MB_2U_LIB.S9S_MB_2U(SCH_1):P5E_CPU1_PE1_TX_C_DP<8>

Q_CAP_DIFFBUS  I41  C726   [Q_CAP_DIFFBUS_C0201-DIFF BUS_0A]
    2  P5E_CPU1_PE1_TX_DN<7>      2  @S9S_MB_2U_LIB.S9S_MB_2U(SCH_1):P5E_CPU1_PE1_TX_DN<7>
    1  P5E_CPU1_PE1_TX_C_DN<7>      1  @S9S_MB_2U_LIB.S9S_MB_2U(SCH_1):P5E_CPU1_PE1_TX_C_DN<7>

Q_CAP_DIFFBUS  I40  C727   [Q_CAP_DIFFBUS_C0201-DIFF BUS_0A]
    2  P5E_CPU1_PE1_TX_DP<7>      2  @S9S_MB_2U_LIB.S9S_MB_2U(SCH_1):P5E_CPU1_PE1_TX_DP<7>
    1  P5E_CPU1_PE1_TX_C_DP<7>      1  @S9S_MB_2U_LIB.S9S_MB_2U(SCH_1):P5E_CPU1_PE1_TX_C_DP<7>

Q_CAP_DIFFBUS  I38  C728   [Q_CAP_DIFFBUS_C0201-DIFF BUS_0A]
    2  P5E_CPU1_PE1_TX_DN<6>      2  @S9S_MB_2U_LIB.S9S_MB_2U(SCH_1):P5E_CPU1_PE1_TX_DN<6>
    1  P5E_CPU1_PE1_TX_C_DN<6>      1  @S9S_MB_2U_LIB.S9S_MB_2U(SCH_1):P5E_CPU1_PE1_TX_C_DN<6>

Q_CAP_DIFFBUS  I39  C729   [Q_CAP_DIFFBUS_C0201-DIFF BUS_0A]
    2  P5E_CPU1_PE1_TX_DP<6>      2  @S9S_MB_2U_LIB.S9S_MB_2U(SCH_1):P5E_CPU1_PE1_TX_DP<6>
    1  P5E_CPU1_PE1_TX_C_DP<6>      1  @S9S_MB_2U_LIB.S9S_MB_2U(SCH_1):P5E_CPU1_PE1_TX_C_DP<6>

Q_CAP_DIFFBUS  I36  C730   [Q_CAP_DIFFBUS_C0201-DIFF BUS_0A]
    2  P5E_CPU1_PE1_TX_DN<5>      2  @S9S_MB_2U_LIB.S9S_MB_2U(SCH_1):P5E_CPU1_PE1_TX_DN<5>
    1  P5E_CPU1_PE1_TX_C_DN<5>      1  @S9S_MB_2U_LIB.S9S_MB_2U(SCH_1):P5E_CPU1_PE1_TX_C_DN<5>

Q_CAP_DIFFBUS  I37  C731   [Q_CAP_DIFFBUS_C0201-DIFF BUS_0A]
    2  P5E_CPU1_PE1_TX_DP<5>      2  @S9S_MB_2U_LIB.S9S_MB_2U(SCH_1):P5E_CPU1_PE1_TX_DP<5>
    1  P5E_CPU1_PE1_TX_C_DP<5>      1  @S9S_MB_2U_LIB.S9S_MB_2U(SCH_1):P5E_CPU1_PE1_TX_C_DP<5>

Q_CAP_DIFFBUS  I28  C732   [Q_CAP_DIFFBUS_C0201-DIFF BUS_0A]
    2  P5E_CPU1_PE1_TX_DN<4>      2  @S9S_MB_2U_LIB.S9S_MB_2U(SCH_1):P5E_CPU1_PE1_TX_DN<4>
    1  P5E_CPU1_PE1_TX_C_DN<4>      1  @S9S_MB_2U_LIB.S9S_MB_2U(SCH_1):P5E_CPU1_PE1_TX_C_DN<4>

Q_CAP_DIFFBUS  I29  C733   [Q_CAP_DIFFBUS_C0201-DIFF BUS_0A]
    2  P5E_CPU1_PE1_TX_DP<4>      2  @S9S_MB_2U_LIB.S9S_MB_2U(SCH_1):P5E_CPU1_PE1_TX_DP<4>
    1  P5E_CPU1_PE1_TX_C_DP<4>      1  @S9S_MB_2U_LIB.S9S_MB_2U(SCH_1):P5E_CPU1_PE1_TX_C_DP<4>

Q_CAP_DIFFBUS  I30  C734   [Q_CAP_DIFFBUS_C0201-DIFF BUS_0A]
    2  P5E_CPU1_PE1_TX_DN<3>      2  @S9S_MB_2U_LIB.S9S_MB_2U(SCH_1):P5E_CPU1_PE1_TX_DN<3>
    1  P5E_CPU1_PE1_TX_C_DN<3>      1  @S9S_MB_2U_LIB.S9S_MB_2U(SCH_1):P5E_CPU1_PE1_TX_C_DN<3>

Q_CAP_DIFFBUS  I26  C735   [Q_CAP_DIFFBUS_C0201-DIFF BUS_0A]
    2  P5E_CPU1_PE1_TX_DP<3>      2  @S9S_MB_2U_LIB.S9S_MB_2U(SCH_1):P5E_CPU1_PE1_TX_DP<3>
    1  P5E_CPU1_PE1_TX_C_DP<3>      1  @S9S_MB_2U_LIB.S9S_MB_2U(SCH_1):P5E_CPU1_PE1_TX_C_DP<3>

Q_CAP_DIFFBUS  I27  C736   [Q_CAP_DIFFBUS_C0201-DIFF BUS_0A]
    2  P5E_CPU1_PE1_TX_DN<2>      2  @S9S_MB_2U_LIB.S9S_MB_2U(SCH_1):P5E_CPU1_PE1_TX_DN<2>
    1  P5E_CPU1_PE1_TX_C_DN<2>      1  @S9S_MB_2U_LIB.S9S_MB_2U(SCH_1):P5E_CPU1_PE1_TX_C_DN<2>

Q_CAP_DIFFBUS  I25  C737   [Q_CAP_DIFFBUS_C0201-DIFF BUS_0A]
    2  P5E_CPU1_PE1_TX_DP<2>      2  @S9S_MB_2U_LIB.S9S_MB_2U(SCH_1):P5E_CPU1_PE1_TX_DP<2>
    1  P5E_CPU1_PE1_TX_C_DP<2>      1  @S9S_MB_2U_LIB.S9S_MB_2U(SCH_1):P5E_CPU1_PE1_TX_C_DP<2>

Q_CAP_DIFFBUS  I23  C738   [Q_CAP_DIFFBUS_C0201-DIFF BUS_0A]
    2  P5E_CPU1_PE1_TX_DN<1>      2  @S9S_MB_2U_LIB.S9S_MB_2U(SCH_1):P5E_CPU1_PE1_TX_DN<1>
    1  P5E_CPU1_PE1_TX_C_DN<1>      1  @S9S_MB_2U_LIB.S9S_MB_2U(SCH_1):P5E_CPU1_PE1_TX_C_DN<1>

Q_CAP_DIFFBUS  I24  C739   [Q_CAP_DIFFBUS_C0201-DIFF BUS_0A]
    2  P5E_CPU1_PE1_TX_DP<1>      2  @S9S_MB_2U_LIB.S9S_MB_2U(SCH_1):P5E_CPU1_PE1_TX_DP<1>
    1  P5E_CPU1_PE1_TX_C_DP<1>      1  @S9S_MB_2U_LIB.S9S_MB_2U(SCH_1):P5E_CPU1_PE1_TX_C_DP<1>

Q_CAP_DIFFBUS  I22  C740   [Q_CAP_DIFFBUS_C0201-DIFF BUS_0A]
    2  P5E_CPU1_PE1_TX_DN<0>      2  @S9S_MB_2U_LIB.S9S_MB_2U(SCH_1):P5E_CPU1_PE1_TX_DN<0>
    1  P5E_CPU1_PE1_TX_C_DN<0>      1  @S9S_MB_2U_LIB.S9S_MB_2U(SCH_1):P5E_CPU1_PE1_TX_C_DN<0>

Q_CAP_DIFFBUS  I21  C741   [Q_CAP_DIFFBUS_C0201-DIFF BUS_0A]
    2  P5E_CPU1_PE1_TX_DP<0>      2  @S9S_MB_2U_LIB.S9S_MB_2U(SCH_1):P5E_CPU1_PE1_TX_DP<0>
    1  P5E_CPU1_PE1_TX_C_DP<0>      1  @S9S_MB_2U_LIB.S9S_MB_2U(SCH_1):P5E_CPU1_PE1_TX_C_DP<0>

Q_CAP_DIFFBUS  I172  C742   [Q_CAP_DIFFBUS_C0201-DIFF BUS_0A]
    2  P5E_CPU1_PE2_TX_DN<15>      2  @S9S_MB_2U_LIB.S9S_MB_2U(SCH_1):P5E_CPU1_PE2_TX_DN<15>
    1  P5E_CPU1_PE2_TX_C_DN<15>      1  @S9S_MB_2U_LIB.S9S_MB_2U(SCH_1):P5E_CPU1_PE2_TX_C_DN<15>

Q_CAP_DIFFBUS  I171  C743   [Q_CAP_DIFFBUS_C0201-DIFF BUS_0A]
    2  P5E_CPU1_PE2_TX_DP<15>      2  @S9S_MB_2U_LIB.S9S_MB_2U(SCH_1):P5E_CPU1_PE2_TX_DP<15>
    1  P5E_CPU1_PE2_TX_C_DP<15>      1  @S9S_MB_2U_LIB.S9S_MB_2U(SCH_1):P5E_CPU1_PE2_TX_C_DP<15>

Q_CAP_DIFFBUS  I170  C744   [Q_CAP_DIFFBUS_C0201-DIFF BUS_0A]
    2  P5E_CPU1_PE2_TX_DN<14>      2  @S9S_MB_2U_LIB.S9S_MB_2U(SCH_1):P5E_CPU1_PE2_TX_DN<14>
    1  P5E_CPU1_PE2_TX_C_DN<14>      1  @S9S_MB_2U_LIB.S9S_MB_2U(SCH_1):P5E_CPU1_PE2_TX_C_DN<14>

Q_CAP_DIFFBUS  I169  C745   [Q_CAP_DIFFBUS_C0201-DIFF BUS_0A]
    2  P5E_CPU1_PE2_TX_DP<14>      2  @S9S_MB_2U_LIB.S9S_MB_2U(SCH_1):P5E_CPU1_PE2_TX_DP<14>
    1  P5E_CPU1_PE2_TX_C_DP<14>      1  @S9S_MB_2U_LIB.S9S_MB_2U(SCH_1):P5E_CPU1_PE2_TX_C_DP<14>

Q_CAP_DIFFBUS  I168  C746   [Q_CAP_DIFFBUS_C0201-DIFF BUS_0A]
    2  P5E_CPU1_PE2_TX_DN<13>      2  @S9S_MB_2U_LIB.S9S_MB_2U(SCH_1):P5E_CPU1_PE2_TX_DN<13>
    1  P5E_CPU1_PE2_TX_C_DN<13>      1  @S9S_MB_2U_LIB.S9S_MB_2U(SCH_1):P5E_CPU1_PE2_TX_C_DN<13>

Q_CAP_DIFFBUS  I167  C747   [Q_CAP_DIFFBUS_C0201-DIFF BUS_0A]
    2  P5E_CPU1_PE2_TX_DP<13>      2  @S9S_MB_2U_LIB.S9S_MB_2U(SCH_1):P5E_CPU1_PE2_TX_DP<13>
    1  P5E_CPU1_PE2_TX_C_DP<13>      1  @S9S_MB_2U_LIB.S9S_MB_2U(SCH_1):P5E_CPU1_PE2_TX_C_DP<13>

Q_CAP_DIFFBUS  I163  C748   [Q_CAP_DIFFBUS_C0201-DIFF BUS_0A]
    2  P5E_CPU1_PE2_TX_DN<12>      2  @S9S_MB_2U_LIB.S9S_MB_2U(SCH_1):P5E_CPU1_PE2_TX_DN<12>
    1  P5E_CPU1_PE2_TX_C_DN<12>      1  @S9S_MB_2U_LIB.S9S_MB_2U(SCH_1):P5E_CPU1_PE2_TX_C_DN<12>

Q_CAP_DIFFBUS  I162  C749   [Q_CAP_DIFFBUS_C0201-DIFF BUS_0A]
    2  P5E_CPU1_PE2_TX_DP<12>      2  @S9S_MB_2U_LIB.S9S_MB_2U(SCH_1):P5E_CPU1_PE2_TX_DP<12>
    1  P5E_CPU1_PE2_TX_C_DP<12>      1  @S9S_MB_2U_LIB.S9S_MB_2U(SCH_1):P5E_CPU1_PE2_TX_C_DP<12>

Q_CAP_DIFFBUS  I160  C750   [Q_CAP_DIFFBUS_C0201-DIFF BUS_0A]
    2  P5E_CPU1_PE2_TX_DN<11>      2  @S9S_MB_2U_LIB.S9S_MB_2U(SCH_1):P5E_CPU1_PE2_TX_DN<11>
    1  P5E_CPU1_PE2_TX_C_DN<11>      1  @S9S_MB_2U_LIB.S9S_MB_2U(SCH_1):P5E_CPU1_PE2_TX_C_DN<11>

Q_CAP_DIFFBUS  I161  C751   [Q_CAP_DIFFBUS_C0201-DIFF BUS_0A]
    2  P5E_CPU1_PE2_TX_DP<11>      2  @S9S_MB_2U_LIB.S9S_MB_2U(SCH_1):P5E_CPU1_PE2_TX_DP<11>
    1  P5E_CPU1_PE2_TX_C_DP<11>      1  @S9S_MB_2U_LIB.S9S_MB_2U(SCH_1):P5E_CPU1_PE2_TX_C_DP<11>

Q_CAP_DIFFBUS  I159  C752   [Q_CAP_DIFFBUS_C0201-DIFF BUS_0A]
    2  P5E_CPU1_PE2_TX_DN<10>      2  @S9S_MB_2U_LIB.S9S_MB_2U(SCH_1):P5E_CPU1_PE2_TX_DN<10>
    1  P5E_CPU1_PE2_TX_C_DN<10>      1  @S9S_MB_2U_LIB.S9S_MB_2U(SCH_1):P5E_CPU1_PE2_TX_C_DN<10>

Q_CAP_DIFFBUS  I158  C753   [Q_CAP_DIFFBUS_C0201-DIFF BUS_0A]
    2  P5E_CPU1_PE2_TX_DP<10>      2  @S9S_MB_2U_LIB.S9S_MB_2U(SCH_1):P5E_CPU1_PE2_TX_DP<10>
    1  P5E_CPU1_PE2_TX_C_DP<10>      1  @S9S_MB_2U_LIB.S9S_MB_2U(SCH_1):P5E_CPU1_PE2_TX_C_DP<10>

Q_CAP_DIFFBUS  I157  C754   [Q_CAP_DIFFBUS_C0201-DIFF BUS_0A]
    2  P5E_CPU1_PE2_TX_DN<9>      2  @S9S_MB_2U_LIB.S9S_MB_2U(SCH_1):P5E_CPU1_PE2_TX_DN<9>
    1  P5E_CPU1_PE2_TX_C_DN<9>      1  @S9S_MB_2U_LIB.S9S_MB_2U(SCH_1):P5E_CPU1_PE2_TX_C_DN<9>

Q_CAP_DIFFBUS  I156  C755   [Q_CAP_DIFFBUS_C0201-DIFF BUS_0A]
    2  P5E_CPU1_PE2_TX_DP<9>      2  @S9S_MB_2U_LIB.S9S_MB_2U(SCH_1):P5E_CPU1_PE2_TX_DP<9>
    1  P5E_CPU1_PE2_TX_C_DP<9>      1  @S9S_MB_2U_LIB.S9S_MB_2U(SCH_1):P5E_CPU1_PE2_TX_C_DP<9>

Q_CAP_DIFFBUS  I154  C756   [Q_CAP_DIFFBUS_C0201-DIFF BUS_0A]
    2  P5E_CPU1_PE2_TX_DN<8>      2  @S9S_MB_2U_LIB.S9S_MB_2U(SCH_1):P5E_CPU1_PE2_TX_DN<8>
    1  P5E_CPU1_PE2_TX_C_DN<8>      1  @S9S_MB_2U_LIB.S9S_MB_2U(SCH_1):P5E_CPU1_PE2_TX_C_DN<8>

Q_CAP_DIFFBUS  I155  C757   [Q_CAP_DIFFBUS_C0201-DIFF BUS_0A]
    2  P5E_CPU1_PE2_TX_DP<8>      2  @S9S_MB_2U_LIB.S9S_MB_2U(SCH_1):P5E_CPU1_PE2_TX_DP<8>
    1  P5E_CPU1_PE2_TX_C_DP<8>      1  @S9S_MB_2U_LIB.S9S_MB_2U(SCH_1):P5E_CPU1_PE2_TX_C_DP<8>

Q_CAP_DIFFBUS  I140  C758   [Q_CAP_DIFFBUS_C0201-DIFF BUS_0A]
    2  P5E_CPU1_PE2_TX_DN<7>      2  @S9S_MB_2U_LIB.S9S_MB_2U(SCH_1):P5E_CPU1_PE2_TX_DN<7>
    1  P5E_CPU1_PE2_TX_C_DN<7>      1  @S9S_MB_2U_LIB.S9S_MB_2U(SCH_1):P5E_CPU1_PE2_TX_C_DN<7>

Q_CAP_DIFFBUS  I139  C759   [Q_CAP_DIFFBUS_C0201-DIFF BUS_0A]
    2  P5E_CPU1_PE2_TX_DP<7>      2  @S9S_MB_2U_LIB.S9S_MB_2U(SCH_1):P5E_CPU1_PE2_TX_DP<7>
    1  P5E_CPU1_PE2_TX_C_DP<7>      1  @S9S_MB_2U_LIB.S9S_MB_2U(SCH_1):P5E_CPU1_PE2_TX_C_DP<7>

Q_CAP_DIFFBUS  I138  C760   [Q_CAP_DIFFBUS_C0201-DIFF BUS_0A]
    2  P5E_CPU1_PE2_TX_DN<6>      2  @S9S_MB_2U_LIB.S9S_MB_2U(SCH_1):P5E_CPU1_PE2_TX_DN<6>
    1  P5E_CPU1_PE2_TX_C_DN<6>      1  @S9S_MB_2U_LIB.S9S_MB_2U(SCH_1):P5E_CPU1_PE2_TX_C_DN<6>

Q_CAP_DIFFBUS  I137  C761   [Q_CAP_DIFFBUS_C0201-DIFF BUS_0A]
    2  P5E_CPU1_PE2_TX_DP<6>      2  @S9S_MB_2U_LIB.S9S_MB_2U(SCH_1):P5E_CPU1_PE2_TX_DP<6>
    1  P5E_CPU1_PE2_TX_C_DP<6>      1  @S9S_MB_2U_LIB.S9S_MB_2U(SCH_1):P5E_CPU1_PE2_TX_C_DP<6>

Q_CAP_DIFFBUS  I136  C762   [Q_CAP_DIFFBUS_C0201-DIFF BUS_0A]
    2  P5E_CPU1_PE2_TX_DN<5>      2  @S9S_MB_2U_LIB.S9S_MB_2U(SCH_1):P5E_CPU1_PE2_TX_DN<5>
    1  P5E_CPU1_PE2_TX_C_DN<5>      1  @S9S_MB_2U_LIB.S9S_MB_2U(SCH_1):P5E_CPU1_PE2_TX_C_DN<5>

Q_CAP_DIFFBUS  I135  C763   [Q_CAP_DIFFBUS_C0201-DIFF BUS_0A]
    2  P5E_CPU1_PE2_TX_DP<5>      2  @S9S_MB_2U_LIB.S9S_MB_2U(SCH_1):P5E_CPU1_PE2_TX_DP<5>
    1  P5E_CPU1_PE2_TX_C_DP<5>      1  @S9S_MB_2U_LIB.S9S_MB_2U(SCH_1):P5E_CPU1_PE2_TX_C_DP<5>

Q_CAP_DIFFBUS  I130  C764   [Q_CAP_DIFFBUS_C0201-DIFF BUS_0A]
    2  P5E_CPU1_PE2_TX_DN<4>      2  @S9S_MB_2U_LIB.S9S_MB_2U(SCH_1):P5E_CPU1_PE2_TX_DN<4>
    1  P5E_CPU1_PE2_TX_C_DN<4>      1  @S9S_MB_2U_LIB.S9S_MB_2U(SCH_1):P5E_CPU1_PE2_TX_C_DN<4>

Q_CAP_DIFFBUS  I131  C765   [Q_CAP_DIFFBUS_C0201-DIFF BUS_0A]
    2  P5E_CPU1_PE2_TX_DP<4>      2  @S9S_MB_2U_LIB.S9S_MB_2U(SCH_1):P5E_CPU1_PE2_TX_DP<4>
    1  P5E_CPU1_PE2_TX_C_DP<4>      1  @S9S_MB_2U_LIB.S9S_MB_2U(SCH_1):P5E_CPU1_PE2_TX_C_DP<4>

Q_CAP_DIFFBUS  I129  C766   [Q_CAP_DIFFBUS_C0201-DIFF BUS_0A]
    2  P5E_CPU1_PE2_TX_DN<3>      2  @S9S_MB_2U_LIB.S9S_MB_2U(SCH_1):P5E_CPU1_PE2_TX_DN<3>
    1  P5E_CPU1_PE2_TX_C_DN<3>      1  @S9S_MB_2U_LIB.S9S_MB_2U(SCH_1):P5E_CPU1_PE2_TX_C_DN<3>

Q_CAP_DIFFBUS  I128  C767   [Q_CAP_DIFFBUS_C0201-DIFF BUS_0A]
    2  P5E_CPU1_PE2_TX_DP<3>      2  @S9S_MB_2U_LIB.S9S_MB_2U(SCH_1):P5E_CPU1_PE2_TX_DP<3>
    1  P5E_CPU1_PE2_TX_C_DP<3>      1  @S9S_MB_2U_LIB.S9S_MB_2U(SCH_1):P5E_CPU1_PE2_TX_C_DP<3>

Q_CAP_DIFFBUS  I127  C768   [Q_CAP_DIFFBUS_C0201-DIFF BUS_0A]
    2  P5E_CPU1_PE2_TX_DN<2>      2  @S9S_MB_2U_LIB.S9S_MB_2U(SCH_1):P5E_CPU1_PE2_TX_DN<2>
    1  P5E_CPU1_PE2_TX_C_DN<2>      1  @S9S_MB_2U_LIB.S9S_MB_2U(SCH_1):P5E_CPU1_PE2_TX_C_DN<2>

Q_CAP_DIFFBUS  I126  C769   [Q_CAP_DIFFBUS_C0201-DIFF BUS_0A]
    2  P5E_CPU1_PE2_TX_DP<2>      2  @S9S_MB_2U_LIB.S9S_MB_2U(SCH_1):P5E_CPU1_PE2_TX_DP<2>
    1  P5E_CPU1_PE2_TX_C_DP<2>      1  @S9S_MB_2U_LIB.S9S_MB_2U(SCH_1):P5E_CPU1_PE2_TX_C_DP<2>

Q_CAP_DIFFBUS  I125  C770   [Q_CAP_DIFFBUS_C0201-DIFF BUS_0A]
    2  P5E_CPU1_PE2_TX_DN<1>      2  @S9S_MB_2U_LIB.S9S_MB_2U(SCH_1):P5E_CPU1_PE2_TX_DN<1>
    1  P5E_CPU1_PE2_TX_C_DN<1>      1  @S9S_MB_2U_LIB.S9S_MB_2U(SCH_1):P5E_CPU1_PE2_TX_C_DN<1>

Q_CAP_DIFFBUS  I124  C771   [Q_CAP_DIFFBUS_C0201-DIFF BUS_0A]
    2  P5E_CPU1_PE2_TX_DP<1>      2  @S9S_MB_2U_LIB.S9S_MB_2U(SCH_1):P5E_CPU1_PE2_TX_DP<1>
    1  P5E_CPU1_PE2_TX_C_DP<1>      1  @S9S_MB_2U_LIB.S9S_MB_2U(SCH_1):P5E_CPU1_PE2_TX_C_DP<1>

Q_CAP_DIFFBUS  I123  C772   [Q_CAP_DIFFBUS_C0201-DIFF BUS_0A]
    2  P5E_CPU1_PE2_TX_DN<0>      2  @S9S_MB_2U_LIB.S9S_MB_2U(SCH_1):P5E_CPU1_PE2_TX_DN<0>
    1  P5E_CPU1_PE2_TX_C_DN<0>      1  @S9S_MB_2U_LIB.S9S_MB_2U(SCH_1):P5E_CPU1_PE2_TX_C_DN<0>

Q_CAP_DIFFBUS  I122  C773   [Q_CAP_DIFFBUS_C0201-DIFF BUS_0A]
    2  P5E_CPU1_PE2_TX_DP<0>      2  @S9S_MB_2U_LIB.S9S_MB_2U(SCH_1):P5E_CPU1_PE2_TX_DP<0>
    1  P5E_CPU1_PE2_TX_C_DP<0>      1  @S9S_MB_2U_LIB.S9S_MB_2U(SCH_1):P5E_CPU1_PE2_TX_C_DP<0>

Q_CAP_DIFFBUS  I352  C806   [Q_CAP_DIFFBUS_C0201-DIFF BUS_0A]
    2  P5E_CPU1_PE0_TX_DN<15>      2  @S9S_MB_2U_LIB.S9S_MB_2U(SCH_1):P5E_CPU1_PE0_TX_DN<15>
    1  P5E_CPU1_PE0_TX_C_DN<15>      1  @S9S_MB_2U_LIB.S9S_MB_2U(SCH_1):P5E_CPU1_PE0_TX_C_DN<15>

Q_CAP_DIFFBUS  I351  C807   [Q_CAP_DIFFBUS_C0201-DIFF BUS_0A]
    2  P5E_CPU1_PE0_TX_DP<15>      2  @S9S_MB_2U_LIB.S9S_MB_2U(SCH_1):P5E_CPU1_PE0_TX_DP<15>
    1  P5E_CPU1_PE0_TX_C_DP<15>      1  @S9S_MB_2U_LIB.S9S_MB_2U(SCH_1):P5E_CPU1_PE0_TX_C_DP<15>

Q_CAP_DIFFBUS  I353  C808   [Q_CAP_DIFFBUS_C0201-DIFF BUS_0A]
    2  P5E_CPU1_PE0_TX_DN<14>      2  @S9S_MB_2U_LIB.S9S_MB_2U(SCH_1):P5E_CPU1_PE0_TX_DN<14>
    1  P5E_CPU1_PE0_TX_C_DN<14>      1  @S9S_MB_2U_LIB.S9S_MB_2U(SCH_1):P5E_CPU1_PE0_TX_C_DN<14>

Q_CAP_DIFFBUS  I354  C809   [Q_CAP_DIFFBUS_C0201-DIFF BUS_0A]
    2  P5E_CPU1_PE0_TX_DP<14>      2  @S9S_MB_2U_LIB.S9S_MB_2U(SCH_1):P5E_CPU1_PE0_TX_DP<14>
    1  P5E_CPU1_PE0_TX_C_DP<14>      1  @S9S_MB_2U_LIB.S9S_MB_2U(SCH_1):P5E_CPU1_PE0_TX_C_DP<14>

Q_CAP_DIFFBUS  I355  C810   [Q_CAP_DIFFBUS_C0201-DIFF BUS_0A]
    2  P5E_CPU1_PE0_TX_DN<13>      2  @S9S_MB_2U_LIB.S9S_MB_2U(SCH_1):P5E_CPU1_PE0_TX_DN<13>
    1  P5E_CPU1_PE0_TX_C_DN<13>      1  @S9S_MB_2U_LIB.S9S_MB_2U(SCH_1):P5E_CPU1_PE0_TX_C_DN<13>

Q_CAP_DIFFBUS  I356  C811   [Q_CAP_DIFFBUS_C0201-DIFF BUS_0A]
    2  P5E_CPU1_PE0_TX_DP<13>      2  @S9S_MB_2U_LIB.S9S_MB_2U(SCH_1):P5E_CPU1_PE0_TX_DP<13>
    1  P5E_CPU1_PE0_TX_C_DP<13>      1  @S9S_MB_2U_LIB.S9S_MB_2U(SCH_1):P5E_CPU1_PE0_TX_C_DP<13>

Q_CAP_DIFFBUS  I357  C812   [Q_CAP_DIFFBUS_C0201-DIFF BUS_0A]
    2  P5E_CPU1_PE0_TX_DN<12>      2  @S9S_MB_2U_LIB.S9S_MB_2U(SCH_1):P5E_CPU1_PE0_TX_DN<12>
    1  P5E_CPU1_PE0_TX_C_DN<12>      1  @S9S_MB_2U_LIB.S9S_MB_2U(SCH_1):P5E_CPU1_PE0_TX_C_DN<12>

Q_CAP_DIFFBUS  I358  C813   [Q_CAP_DIFFBUS_C0201-DIFF BUS_0A]
    2  P5E_CPU1_PE0_TX_DP<12>      2  @S9S_MB_2U_LIB.S9S_MB_2U(SCH_1):P5E_CPU1_PE0_TX_DP<12>
    1  P5E_CPU1_PE0_TX_C_DP<12>      1  @S9S_MB_2U_LIB.S9S_MB_2U(SCH_1):P5E_CPU1_PE0_TX_C_DP<12>

Q_CAP_DIFFBUS  I359  C814   [Q_CAP_DIFFBUS_C0201-DIFF BUS_0A]
    2  P5E_CPU1_PE0_TX_DN<11>      2  @S9S_MB_2U_LIB.S9S_MB_2U(SCH_1):P5E_CPU1_PE0_TX_DN<11>
    1  P5E_CPU1_PE0_TX_C_DN<11>      1  @S9S_MB_2U_LIB.S9S_MB_2U(SCH_1):P5E_CPU1_PE0_TX_C_DN<11>

Q_CAP_DIFFBUS  I360  C815   [Q_CAP_DIFFBUS_C0201-DIFF BUS_0A]
    2  P5E_CPU1_PE0_TX_DP<11>      2  @S9S_MB_2U_LIB.S9S_MB_2U(SCH_1):P5E_CPU1_PE0_TX_DP<11>
    1  P5E_CPU1_PE0_TX_C_DP<11>      1  @S9S_MB_2U_LIB.S9S_MB_2U(SCH_1):P5E_CPU1_PE0_TX_C_DP<11>

Q_CAP_DIFFBUS  I361  C816   [Q_CAP_DIFFBUS_C0201-DIFF BUS_0A]
    2  P5E_CPU1_PE0_TX_DN<10>      2  @S9S_MB_2U_LIB.S9S_MB_2U(SCH_1):P5E_CPU1_PE0_TX_DN<10>
    1  P5E_CPU1_PE0_TX_C_DN<10>      1  @S9S_MB_2U_LIB.S9S_MB_2U(SCH_1):P5E_CPU1_PE0_TX_C_DN<10>

Q_CAP_DIFFBUS  I362  C817   [Q_CAP_DIFFBUS_C0201-DIFF BUS_0A]
    2  P5E_CPU1_PE0_TX_DP<10>      2  @S9S_MB_2U_LIB.S9S_MB_2U(SCH_1):P5E_CPU1_PE0_TX_DP<10>
    1  P5E_CPU1_PE0_TX_C_DP<10>      1  @S9S_MB_2U_LIB.S9S_MB_2U(SCH_1):P5E_CPU1_PE0_TX_C_DP<10>

Q_CAP_DIFFBUS  I313  C818   [Q_CAP_DIFFBUS_C0201-DIFF BUS_0A]
    2  P5E_CPU1_PE0_TX_DN<9>      2  @S9S_MB_2U_LIB.S9S_MB_2U(SCH_1):P5E_CPU1_PE0_TX_DN<9>
    1  P5E_CPU1_PE0_TX_C_DN<9>      1  @S9S_MB_2U_LIB.S9S_MB_2U(SCH_1):P5E_CPU1_PE0_TX_C_DN<9>

Q_CAP_DIFFBUS  I363  C819   [Q_CAP_DIFFBUS_C0201-DIFF BUS_0A]
    2  P5E_CPU1_PE0_TX_DP<9>      2  @S9S_MB_2U_LIB.S9S_MB_2U(SCH_1):P5E_CPU1_PE0_TX_DP<9>
    1  P5E_CPU1_PE0_TX_C_DP<9>      1  @S9S_MB_2U_LIB.S9S_MB_2U(SCH_1):P5E_CPU1_PE0_TX_C_DP<9>

Q_CAP_DIFFBUS  I364  C820   [Q_CAP_DIFFBUS_C0201-DIFF BUS_0A]
    2  P5E_CPU1_PE0_TX_DN<8>      2  @S9S_MB_2U_LIB.S9S_MB_2U(SCH_1):P5E_CPU1_PE0_TX_DN<8>
    1  P5E_CPU1_PE0_TX_C_DN<8>      1  @S9S_MB_2U_LIB.S9S_MB_2U(SCH_1):P5E_CPU1_PE0_TX_C_DN<8>

Q_CAP_DIFFBUS  I365  C821   [Q_CAP_DIFFBUS_C0201-DIFF BUS_0A]
    2  P5E_CPU1_PE0_TX_DP<8>      2  @S9S_MB_2U_LIB.S9S_MB_2U(SCH_1):P5E_CPU1_PE0_TX_DP<8>
    1  P5E_CPU1_PE0_TX_C_DP<8>      1  @S9S_MB_2U_LIB.S9S_MB_2U(SCH_1):P5E_CPU1_PE0_TX_C_DP<8>

Q_CAP_DIFFBUS  I382  C822   [Q_CAP_DIFFBUS_C0201-DIFF BUS_0A]
    2  P5E_CPU1_PE0_TX_DN<7>      2  @S9S_MB_2U_LIB.S9S_MB_2U(SCH_1):P5E_CPU1_PE0_TX_DN<7>
    1  P5E_CPU1_PE0_TX_C_DN<7>      1  @S9S_MB_2U_LIB.S9S_MB_2U(SCH_1):P5E_CPU1_PE0_TX_C_DN<7>

Q_CAP_DIFFBUS  I383  C823   [Q_CAP_DIFFBUS_C0201-DIFF BUS_0A]
    2  P5E_CPU1_PE0_TX_DP<7>      2  @S9S_MB_2U_LIB.S9S_MB_2U(SCH_1):P5E_CPU1_PE0_TX_DP<7>
    1  P5E_CPU1_PE0_TX_C_DP<7>      1  @S9S_MB_2U_LIB.S9S_MB_2U(SCH_1):P5E_CPU1_PE0_TX_C_DP<7>

Q_CAP_DIFFBUS  I385  C824   [Q_CAP_DIFFBUS_C0201-DIFF BUS_0A]
    2  P5E_CPU1_PE0_TX_DN<6>      2  @S9S_MB_2U_LIB.S9S_MB_2U(SCH_1):P5E_CPU1_PE0_TX_DN<6>
    1  P5E_CPU1_PE0_TX_C_DN<6>      1  @S9S_MB_2U_LIB.S9S_MB_2U(SCH_1):P5E_CPU1_PE0_TX_C_DN<6>

Q_CAP_DIFFBUS  I384  C825   [Q_CAP_DIFFBUS_C0201-DIFF BUS_0A]
    2  P5E_CPU1_PE0_TX_DP<6>      2  @S9S_MB_2U_LIB.S9S_MB_2U(SCH_1):P5E_CPU1_PE0_TX_DP<6>
    1  P5E_CPU1_PE0_TX_C_DP<6>      1  @S9S_MB_2U_LIB.S9S_MB_2U(SCH_1):P5E_CPU1_PE0_TX_C_DP<6>

Q_CAP_DIFFBUS  I386  C826   [Q_CAP_DIFFBUS_C0201-DIFF BUS_0A]
    2  P5E_CPU1_PE0_TX_DN<5>      2  @S9S_MB_2U_LIB.S9S_MB_2U(SCH_1):P5E_CPU1_PE0_TX_DN<5>
    1  P5E_CPU1_PE0_TX_C_DN<5>      1  @S9S_MB_2U_LIB.S9S_MB_2U(SCH_1):P5E_CPU1_PE0_TX_C_DN<5>

Q_CAP_DIFFBUS  I387  C827   [Q_CAP_DIFFBUS_C0201-DIFF BUS_0A]
    2  P5E_CPU1_PE0_TX_DP<5>      2  @S9S_MB_2U_LIB.S9S_MB_2U(SCH_1):P5E_CPU1_PE0_TX_DP<5>
    1  P5E_CPU1_PE0_TX_C_DP<5>      1  @S9S_MB_2U_LIB.S9S_MB_2U(SCH_1):P5E_CPU1_PE0_TX_C_DP<5>

Q_CAP_DIFFBUS  I388  C828   [Q_CAP_DIFFBUS_C0201-DIFF BUS_0A]
    2  P5E_CPU1_PE0_TX_DN<4>      2  @S9S_MB_2U_LIB.S9S_MB_2U(SCH_1):P5E_CPU1_PE0_TX_DN<4>
    1  P5E_CPU1_PE0_TX_C_DN<4>      1  @S9S_MB_2U_LIB.S9S_MB_2U(SCH_1):P5E_CPU1_PE0_TX_C_DN<4>

Q_CAP_DIFFBUS  I389  C829   [Q_CAP_DIFFBUS_C0201-DIFF BUS_0A]
    2  P5E_CPU1_PE0_TX_DP<4>      2  @S9S_MB_2U_LIB.S9S_MB_2U(SCH_1):P5E_CPU1_PE0_TX_DP<4>
    1  P5E_CPU1_PE0_TX_C_DP<4>      1  @S9S_MB_2U_LIB.S9S_MB_2U(SCH_1):P5E_CPU1_PE0_TX_C_DP<4>

Q_CAP_DIFFBUS  I390  C830   [Q_CAP_DIFFBUS_C0201-DIFF BUS_0A]
    2  P5E_CPU1_PE0_TX_DN<3>      2  @S9S_MB_2U_LIB.S9S_MB_2U(SCH_1):P5E_CPU1_PE0_TX_DN<3>
    1  P5E_CPU1_PE0_TX_C_DN<3>      1  @S9S_MB_2U_LIB.S9S_MB_2U(SCH_1):P5E_CPU1_PE0_TX_C_DN<3>

Q_CAP_DIFFBUS  I314  C831   [Q_CAP_DIFFBUS_C0201-DIFF BUS_0A]
    2  P5E_CPU1_PE0_TX_DP<3>      2  @S9S_MB_2U_LIB.S9S_MB_2U(SCH_1):P5E_CPU1_PE0_TX_DP<3>
    1  P5E_CPU1_PE0_TX_C_DP<3>      1  @S9S_MB_2U_LIB.S9S_MB_2U(SCH_1):P5E_CPU1_PE0_TX_C_DP<3>

Q_CAP_DIFFBUS  I392  C832   [Q_CAP_DIFFBUS_C0201-DIFF BUS_0A]
    2  P5E_CPU1_PE0_TX_DN<2>      2  @S9S_MB_2U_LIB.S9S_MB_2U(SCH_1):P5E_CPU1_PE0_TX_DN<2>
    1  P5E_CPU1_PE0_TX_C_DN<2>      1  @S9S_MB_2U_LIB.S9S_MB_2U(SCH_1):P5E_CPU1_PE0_TX_C_DN<2>

Q_CAP_DIFFBUS  I391  C833   [Q_CAP_DIFFBUS_C0201-DIFF BUS_0A]
    2  P5E_CPU1_PE0_TX_DP<2>      2  @S9S_MB_2U_LIB.S9S_MB_2U(SCH_1):P5E_CPU1_PE0_TX_DP<2>
    1  P5E_CPU1_PE0_TX_C_DP<2>      1  @S9S_MB_2U_LIB.S9S_MB_2U(SCH_1):P5E_CPU1_PE0_TX_C_DP<2>

Q_CAP_DIFFBUS  I393  C834   [Q_CAP_DIFFBUS_C0201-DIFF BUS_0A]
    2  P5E_CPU1_PE0_TX_DN<1>      2  @S9S_MB_2U_LIB.S9S_MB_2U(SCH_1):P5E_CPU1_PE0_TX_DN<1>
    1  P5E_CPU1_PE0_TX_C_DN<1>      1  @S9S_MB_2U_LIB.S9S_MB_2U(SCH_1):P5E_CPU1_PE0_TX_C_DN<1>

Q_CAP_DIFFBUS  I394  C835   [Q_CAP_DIFFBUS_C0201-DIFF BUS_0A]
    2  P5E_CPU1_PE0_TX_DP<1>      2  @S9S_MB_2U_LIB.S9S_MB_2U(SCH_1):P5E_CPU1_PE0_TX_DP<1>
    1  P5E_CPU1_PE0_TX_C_DP<1>      1  @S9S_MB_2U_LIB.S9S_MB_2U(SCH_1):P5E_CPU1_PE0_TX_C_DP<1>

Q_CAP_DIFFBUS  I395  C836   [Q_CAP_DIFFBUS_C0201-DIFF BUS_0A]
    2  P5E_CPU1_PE0_TX_DN<0>      2  @S9S_MB_2U_LIB.S9S_MB_2U(SCH_1):P5E_CPU1_PE0_TX_DN<0>
    1  P5E_CPU1_PE0_TX_C_DN<0>      1  @S9S_MB_2U_LIB.S9S_MB_2U(SCH_1):P5E_CPU1_PE0_TX_C_DN<0>

Q_CAP_DIFFBUS  I396  C837   [Q_CAP_DIFFBUS_C0201-DIFF BUS_0A]
    2  P5E_CPU1_PE0_TX_DP<0>      2  @S9S_MB_2U_LIB.S9S_MB_2U(SCH_1):P5E_CPU1_PE0_TX_DP<0>
    1  P5E_CPU1_PE0_TX_C_DP<0>      1  @S9S_MB_2U_LIB.S9S_MB_2U(SCH_1):P5E_CPU1_PE0_TX_C_DP<0>

Q_CAP_DIFFBUS  I287  C838   [Q_CAP_DIFFBUS_C0201-DIFF BUS_0A]
    2  P5E_CPU0_PE2_TX_DN<15>      2  @S9S_MB_2U_LIB.S9S_MB_2U(SCH_1):P5E_CPU0_PE2_TX_DN<15>
    1  P5E_CPU0_PE2_TX_C_DN<15>      1  @S9S_MB_2U_LIB.S9S_MB_2U(SCH_1):P5E_CPU0_PE2_TX_C_DN<15>

Q_CAP_DIFFBUS  I286  C839   [Q_CAP_DIFFBUS_C0201-DIFF BUS_0A]
    2  P5E_CPU0_PE2_TX_DP<15>      2  @S9S_MB_2U_LIB.S9S_MB_2U(SCH_1):P5E_CPU0_PE2_TX_DP<15>
    1  P5E_CPU0_PE2_TX_C_DP<15>      1  @S9S_MB_2U_LIB.S9S_MB_2U(SCH_1):P5E_CPU0_PE2_TX_C_DP<15>

Q_CAP_DIFFBUS  I288  C840   [Q_CAP_DIFFBUS_C0201-DIFF BUS_0A]
    2  P5E_CPU0_PE2_TX_DN<14>      2  @S9S_MB_2U_LIB.S9S_MB_2U(SCH_1):P5E_CPU0_PE2_TX_DN<14>
    1  P5E_CPU0_PE2_TX_C_DN<14>      1  @S9S_MB_2U_LIB.S9S_MB_2U(SCH_1):P5E_CPU0_PE2_TX_C_DN<14>

Q_CAP_DIFFBUS  I284  C841   [Q_CAP_DIFFBUS_C0201-DIFF BUS_0A]
    2  P5E_CPU0_PE2_TX_DP<14>      2  @S9S_MB_2U_LIB.S9S_MB_2U(SCH_1):P5E_CPU0_PE2_TX_DP<14>
    1  P5E_CPU0_PE2_TX_C_DP<14>      1  @S9S_MB_2U_LIB.S9S_MB_2U(SCH_1):P5E_CPU0_PE2_TX_C_DP<14>

Q_CAP_DIFFBUS  I285  C842   [Q_CAP_DIFFBUS_C0201-DIFF BUS_0A]
    2  P5E_CPU0_PE2_TX_DN<13>      2  @S9S_MB_2U_LIB.S9S_MB_2U(SCH_1):P5E_CPU0_PE2_TX_DN<13>
    1  P5E_CPU0_PE2_TX_C_DN<13>      1  @S9S_MB_2U_LIB.S9S_MB_2U(SCH_1):P5E_CPU0_PE2_TX_C_DN<13>

Q_CAP_DIFFBUS  I283  C843   [Q_CAP_DIFFBUS_C0201-DIFF BUS_0A]
    2  P5E_CPU0_PE2_TX_DP<13>      2  @S9S_MB_2U_LIB.S9S_MB_2U(SCH_1):P5E_CPU0_PE2_TX_DP<13>
    1  P5E_CPU0_PE2_TX_C_DP<13>      1  @S9S_MB_2U_LIB.S9S_MB_2U(SCH_1):P5E_CPU0_PE2_TX_C_DP<13>

Q_CAP_DIFFBUS  I276  C844   [Q_CAP_DIFFBUS_C0201-DIFF BUS_0A]
    2  P5E_CPU0_PE2_TX_DN<12>      2  @S9S_MB_2U_LIB.S9S_MB_2U(SCH_1):P5E_CPU0_PE2_TX_DN<12>
    1  P5E_CPU0_PE2_TX_C_DN<12>      1  @S9S_MB_2U_LIB.S9S_MB_2U(SCH_1):P5E_CPU0_PE2_TX_C_DN<12>

Q_CAP_DIFFBUS  I277  C845   [Q_CAP_DIFFBUS_C0201-DIFF BUS_0A]
    2  P5E_CPU0_PE2_TX_DP<12>      2  @S9S_MB_2U_LIB.S9S_MB_2U(SCH_1):P5E_CPU0_PE2_TX_DP<12>
    1  P5E_CPU0_PE2_TX_C_DP<12>      1  @S9S_MB_2U_LIB.S9S_MB_2U(SCH_1):P5E_CPU0_PE2_TX_C_DP<12>

Q_CAP_DIFFBUS  I274  C846   [Q_CAP_DIFFBUS_C0201-DIFF BUS_0A]
    2  P5E_CPU0_PE2_TX_DN<11>      2  @S9S_MB_2U_LIB.S9S_MB_2U(SCH_1):P5E_CPU0_PE2_TX_DN<11>
    1  P5E_CPU0_PE2_TX_C_DN<11>      1  @S9S_MB_2U_LIB.S9S_MB_2U(SCH_1):P5E_CPU0_PE2_TX_C_DN<11>

Q_CAP_DIFFBUS  I275  C847   [Q_CAP_DIFFBUS_C0201-DIFF BUS_0A]
    2  P5E_CPU0_PE2_TX_DP<11>      2  @S9S_MB_2U_LIB.S9S_MB_2U(SCH_1):P5E_CPU0_PE2_TX_DP<11>
    1  P5E_CPU0_PE2_TX_C_DP<11>      1  @S9S_MB_2U_LIB.S9S_MB_2U(SCH_1):P5E_CPU0_PE2_TX_C_DP<11>

Q_CAP_DIFFBUS  I273  C848   [Q_CAP_DIFFBUS_C0201-DIFF BUS_0A]
    2  P5E_CPU0_PE2_TX_DN<10>      2  @S9S_MB_2U_LIB.S9S_MB_2U(SCH_1):P5E_CPU0_PE2_TX_DN<10>
    1  P5E_CPU0_PE2_TX_C_DN<10>      1  @S9S_MB_2U_LIB.S9S_MB_2U(SCH_1):P5E_CPU0_PE2_TX_C_DN<10>

Q_CAP_DIFFBUS  I271  C849   [Q_CAP_DIFFBUS_C0201-DIFF BUS_0A]
    2  P5E_CPU0_PE2_TX_DP<10>      2  @S9S_MB_2U_LIB.S9S_MB_2U(SCH_1):P5E_CPU0_PE2_TX_DP<10>
    1  P5E_CPU0_PE2_TX_C_DP<10>      1  @S9S_MB_2U_LIB.S9S_MB_2U(SCH_1):P5E_CPU0_PE2_TX_C_DP<10>

Q_CAP_DIFFBUS  I272  C850   [Q_CAP_DIFFBUS_C0201-DIFF BUS_0A]
    2  P5E_CPU0_PE2_TX_DN<9>      2  @S9S_MB_2U_LIB.S9S_MB_2U(SCH_1):P5E_CPU0_PE2_TX_DN<9>
    1  P5E_CPU0_PE2_TX_C_DN<9>      1  @S9S_MB_2U_LIB.S9S_MB_2U(SCH_1):P5E_CPU0_PE2_TX_C_DN<9>

Q_CAP_DIFFBUS  I270  C851   [Q_CAP_DIFFBUS_C0201-DIFF BUS_0A]
    2  P5E_CPU0_PE2_TX_DP<9>      2  @S9S_MB_2U_LIB.S9S_MB_2U(SCH_1):P5E_CPU0_PE2_TX_DP<9>
    1  P5E_CPU0_PE2_TX_C_DP<9>      1  @S9S_MB_2U_LIB.S9S_MB_2U(SCH_1):P5E_CPU0_PE2_TX_C_DP<9>

Q_CAP_DIFFBUS  I269  C852   [Q_CAP_DIFFBUS_C0201-DIFF BUS_0A]
    2  P5E_CPU0_PE2_TX_DN<8>      2  @S9S_MB_2U_LIB.S9S_MB_2U(SCH_1):P5E_CPU0_PE2_TX_DN<8>
    1  P5E_CPU0_PE2_TX_C_DN<8>      1  @S9S_MB_2U_LIB.S9S_MB_2U(SCH_1):P5E_CPU0_PE2_TX_C_DN<8>

Q_CAP_DIFFBUS  I268  C853   [Q_CAP_DIFFBUS_C0201-DIFF BUS_0A]
    2  P5E_CPU0_PE2_TX_DP<8>      2  @S9S_MB_2U_LIB.S9S_MB_2U(SCH_1):P5E_CPU0_PE2_TX_DP<8>
    1  P5E_CPU0_PE2_TX_C_DP<8>      1  @S9S_MB_2U_LIB.S9S_MB_2U(SCH_1):P5E_CPU0_PE2_TX_C_DP<8>

Q_CAP_DIFFBUS  I248  C854   [Q_CAP_DIFFBUS_C0201-DIFF BUS_0A]
    2  P5E_CPU0_PE2_TX_DN<7>      2  @S9S_MB_2U_LIB.S9S_MB_2U(SCH_1):P5E_CPU0_PE2_TX_DN<7>
    1  P5E_CPU0_PE2_TX_C_DN<7>      1  @S9S_MB_2U_LIB.S9S_MB_2U(SCH_1):P5E_CPU0_PE2_TX_C_DN<7>

Q_CAP_DIFFBUS  I247  C855   [Q_CAP_DIFFBUS_C0201-DIFF BUS_0A]
    2  P5E_CPU0_PE2_TX_DP<7>      2  @S9S_MB_2U_LIB.S9S_MB_2U(SCH_1):P5E_CPU0_PE2_TX_DP<7>
    1  P5E_CPU0_PE2_TX_C_DP<7>      1  @S9S_MB_2U_LIB.S9S_MB_2U(SCH_1):P5E_CPU0_PE2_TX_C_DP<7>

Q_CAP_DIFFBUS  I245  C856   [Q_CAP_DIFFBUS_C0201-DIFF BUS_0A]
    2  P5E_CPU0_PE2_TX_DN<6>      2  @S9S_MB_2U_LIB.S9S_MB_2U(SCH_1):P5E_CPU0_PE2_TX_DN<6>
    1  P5E_CPU0_PE2_TX_C_DN<6>      1  @S9S_MB_2U_LIB.S9S_MB_2U(SCH_1):P5E_CPU0_PE2_TX_C_DN<6>

Q_CAP_DIFFBUS  I246  C857   [Q_CAP_DIFFBUS_C0201-DIFF BUS_0A]
    2  P5E_CPU0_PE2_TX_DP<6>      2  @S9S_MB_2U_LIB.S9S_MB_2U(SCH_1):P5E_CPU0_PE2_TX_DP<6>
    1  P5E_CPU0_PE2_TX_C_DP<6>      1  @S9S_MB_2U_LIB.S9S_MB_2U(SCH_1):P5E_CPU0_PE2_TX_C_DP<6>

Q_CAP_DIFFBUS  I243  C858   [Q_CAP_DIFFBUS_C0201-DIFF BUS_0A]
    2  P5E_CPU0_PE2_TX_DN<5>      2  @S9S_MB_2U_LIB.S9S_MB_2U(SCH_1):P5E_CPU0_PE2_TX_DN<5>
    1  P5E_CPU0_PE2_TX_C_DN<5>      1  @S9S_MB_2U_LIB.S9S_MB_2U(SCH_1):P5E_CPU0_PE2_TX_C_DN<5>

Q_CAP_DIFFBUS  I244  C859   [Q_CAP_DIFFBUS_C0201-DIFF BUS_0A]
    2  P5E_CPU0_PE2_TX_DP<5>      2  @S9S_MB_2U_LIB.S9S_MB_2U(SCH_1):P5E_CPU0_PE2_TX_DP<5>
    1  P5E_CPU0_PE2_TX_C_DP<5>      1  @S9S_MB_2U_LIB.S9S_MB_2U(SCH_1):P5E_CPU0_PE2_TX_C_DP<5>

Q_CAP_DIFFBUS  I235  C860   [Q_CAP_DIFFBUS_C0201-DIFF BUS_0A]
    2  P5E_CPU0_PE2_TX_DN<4>      2  @S9S_MB_2U_LIB.S9S_MB_2U(SCH_1):P5E_CPU0_PE2_TX_DN<4>
    1  P5E_CPU0_PE2_TX_C_DN<4>      1  @S9S_MB_2U_LIB.S9S_MB_2U(SCH_1):P5E_CPU0_PE2_TX_C_DN<4>

Q_CAP_DIFFBUS  I236  C861   [Q_CAP_DIFFBUS_C0201-DIFF BUS_0A]
    2  P5E_CPU0_PE2_TX_DP<4>      2  @S9S_MB_2U_LIB.S9S_MB_2U(SCH_1):P5E_CPU0_PE2_TX_DP<4>
    1  P5E_CPU0_PE2_TX_C_DP<4>      1  @S9S_MB_2U_LIB.S9S_MB_2U(SCH_1):P5E_CPU0_PE2_TX_C_DP<4>

Q_CAP_DIFFBUS  I237  C862   [Q_CAP_DIFFBUS_C0201-DIFF BUS_0A]
    2  P5E_CPU0_PE2_TX_DN<3>      2  @S9S_MB_2U_LIB.S9S_MB_2U(SCH_1):P5E_CPU0_PE2_TX_DN<3>
    1  P5E_CPU0_PE2_TX_C_DN<3>      1  @S9S_MB_2U_LIB.S9S_MB_2U(SCH_1):P5E_CPU0_PE2_TX_C_DN<3>

Q_CAP_DIFFBUS  I233  C863   [Q_CAP_DIFFBUS_C0201-DIFF BUS_0A]
    2  P5E_CPU0_PE2_TX_DP<3>      2  @S9S_MB_2U_LIB.S9S_MB_2U(SCH_1):P5E_CPU0_PE2_TX_DP<3>
    1  P5E_CPU0_PE2_TX_C_DP<3>      1  @S9S_MB_2U_LIB.S9S_MB_2U(SCH_1):P5E_CPU0_PE2_TX_C_DP<3>

Q_CAP_DIFFBUS  I234  C864   [Q_CAP_DIFFBUS_C0201-DIFF BUS_0A]
    2  P5E_CPU0_PE2_TX_DN<2>      2  @S9S_MB_2U_LIB.S9S_MB_2U(SCH_1):P5E_CPU0_PE2_TX_DN<2>
    1  P5E_CPU0_PE2_TX_C_DN<2>      1  @S9S_MB_2U_LIB.S9S_MB_2U(SCH_1):P5E_CPU0_PE2_TX_C_DN<2>

Q_CAP_DIFFBUS  I232  C865   [Q_CAP_DIFFBUS_C0201-DIFF BUS_0A]
    2  P5E_CPU0_PE2_TX_DP<2>      2  @S9S_MB_2U_LIB.S9S_MB_2U(SCH_1):P5E_CPU0_PE2_TX_DP<2>
    1  P5E_CPU0_PE2_TX_C_DP<2>      1  @S9S_MB_2U_LIB.S9S_MB_2U(SCH_1):P5E_CPU0_PE2_TX_C_DP<2>

Q_CAP_DIFFBUS  I230  C866   [Q_CAP_DIFFBUS_C0201-DIFF BUS_0A]
    2  P5E_CPU0_PE2_TX_DN<1>      2  @S9S_MB_2U_LIB.S9S_MB_2U(SCH_1):P5E_CPU0_PE2_TX_DN<1>
    1  P5E_CPU0_PE2_TX_C_DN<1>      1  @S9S_MB_2U_LIB.S9S_MB_2U(SCH_1):P5E_CPU0_PE2_TX_C_DN<1>

Q_CAP_DIFFBUS  I231  C867   [Q_CAP_DIFFBUS_C0201-DIFF BUS_0A]
    2  P5E_CPU0_PE2_TX_DP<1>      2  @S9S_MB_2U_LIB.S9S_MB_2U(SCH_1):P5E_CPU0_PE2_TX_DP<1>
    1  P5E_CPU0_PE2_TX_C_DP<1>      1  @S9S_MB_2U_LIB.S9S_MB_2U(SCH_1):P5E_CPU0_PE2_TX_C_DP<1>

Q_CAP_DIFFBUS  I229  C868   [Q_CAP_DIFFBUS_C0201-DIFF BUS_0A]
    2  P5E_CPU0_PE2_TX_DN<0>      2  @S9S_MB_2U_LIB.S9S_MB_2U(SCH_1):P5E_CPU0_PE2_TX_DN<0>
    1  P5E_CPU0_PE2_TX_C_DN<0>      1  @S9S_MB_2U_LIB.S9S_MB_2U(SCH_1):P5E_CPU0_PE2_TX_C_DN<0>

Q_CAP_DIFFBUS  I228  C869   [Q_CAP_DIFFBUS_C0201-DIFF BUS_0A]
    2  P5E_CPU0_PE2_TX_DP<0>      2  @S9S_MB_2U_LIB.S9S_MB_2U(SCH_1):P5E_CPU0_PE2_TX_DP<0>
    1  P5E_CPU0_PE2_TX_C_DP<0>      1  @S9S_MB_2U_LIB.S9S_MB_2U(SCH_1):P5E_CPU0_PE2_TX_C_DP<0>

Q_CAP_DIFFBUS  I170  C870   [Q_CAP_DIFFBUS_C0201-DIFF BUS_0A]
    2  P5E_CPU0_PE3_TX_DN<15>      2  @S9S_MB_2U_LIB.S9S_MB_2U(SCH_1):P5E_CPU0_PE3_TX_DN<15>
    1  P5E_CPU0_PE3_TX_C_DN<15>      1  @S9S_MB_2U_LIB.S9S_MB_2U(SCH_1):P5E_CPU0_PE3_TX_C_DN<15>

Q_CAP_DIFFBUS  I169  C871   [Q_CAP_DIFFBUS_C0201-DIFF BUS_0A]
    2  P5E_CPU0_PE3_TX_DP<15>      2  @S9S_MB_2U_LIB.S9S_MB_2U(SCH_1):P5E_CPU0_PE3_TX_DP<15>
    1  P5E_CPU0_PE3_TX_C_DP<15>      1  @S9S_MB_2U_LIB.S9S_MB_2U(SCH_1):P5E_CPU0_PE3_TX_C_DP<15>

Q_CAP_DIFFBUS  I168  C872   [Q_CAP_DIFFBUS_C0201-DIFF BUS_0A]
    2  P5E_CPU0_PE3_TX_DN<14>      2  @S9S_MB_2U_LIB.S9S_MB_2U(SCH_1):P5E_CPU0_PE3_TX_DN<14>
    1  P5E_CPU0_PE3_TX_C_DN<14>      1  @S9S_MB_2U_LIB.S9S_MB_2U(SCH_1):P5E_CPU0_PE3_TX_C_DN<14>

Q_CAP_DIFFBUS  I167  C873   [Q_CAP_DIFFBUS_C0201-DIFF BUS_0A]
    2  P5E_CPU0_PE3_TX_DP<14>      2  @S9S_MB_2U_LIB.S9S_MB_2U(SCH_1):P5E_CPU0_PE3_TX_DP<14>
    1  P5E_CPU0_PE3_TX_C_DP<14>      1  @S9S_MB_2U_LIB.S9S_MB_2U(SCH_1):P5E_CPU0_PE3_TX_C_DP<14>

Q_CAP_DIFFBUS  I166  C874   [Q_CAP_DIFFBUS_C0201-DIFF BUS_0A]
    2  P5E_CPU0_PE3_TX_DN<13>      2  @S9S_MB_2U_LIB.S9S_MB_2U(SCH_1):P5E_CPU0_PE3_TX_DN<13>
    1  P5E_CPU0_PE3_TX_C_DN<13>      1  @S9S_MB_2U_LIB.S9S_MB_2U(SCH_1):P5E_CPU0_PE3_TX_C_DN<13>

Q_CAP_DIFFBUS  I165  C875   [Q_CAP_DIFFBUS_C0201-DIFF BUS_0A]
    2  P5E_CPU0_PE3_TX_DP<13>      2  @S9S_MB_2U_LIB.S9S_MB_2U(SCH_1):P5E_CPU0_PE3_TX_DP<13>
    1  P5E_CPU0_PE3_TX_C_DP<13>      1  @S9S_MB_2U_LIB.S9S_MB_2U(SCH_1):P5E_CPU0_PE3_TX_C_DP<13>

Q_CAP_DIFFBUS  I161  C876   [Q_CAP_DIFFBUS_C0201-DIFF BUS_0A]
    2  P5E_CPU0_PE3_TX_DN<12>      2  @S9S_MB_2U_LIB.S9S_MB_2U(SCH_1):P5E_CPU0_PE3_TX_DN<12>
    1  P5E_CPU0_PE3_TX_C_DN<12>      1  @S9S_MB_2U_LIB.S9S_MB_2U(SCH_1):P5E_CPU0_PE3_TX_C_DN<12>

Q_CAP_DIFFBUS  I160  C877   [Q_CAP_DIFFBUS_C0201-DIFF BUS_0A]
    2  P5E_CPU0_PE3_TX_DP<12>      2  @S9S_MB_2U_LIB.S9S_MB_2U(SCH_1):P5E_CPU0_PE3_TX_DP<12>
    1  P5E_CPU0_PE3_TX_C_DP<12>      1  @S9S_MB_2U_LIB.S9S_MB_2U(SCH_1):P5E_CPU0_PE3_TX_C_DP<12>

Q_CAP_DIFFBUS  I159  C878   [Q_CAP_DIFFBUS_C0201-DIFF BUS_0A]
    2  P5E_CPU0_PE3_TX_DN<11>      2  @S9S_MB_2U_LIB.S9S_MB_2U(SCH_1):P5E_CPU0_PE3_TX_DN<11>
    1  P5E_CPU0_PE3_TX_C_DN<11>      1  @S9S_MB_2U_LIB.S9S_MB_2U(SCH_1):P5E_CPU0_PE3_TX_C_DN<11>

Q_CAP_DIFFBUS  I158  C879   [Q_CAP_DIFFBUS_C0201-DIFF BUS_0A]
    2  P5E_CPU0_PE3_TX_DP<11>      2  @S9S_MB_2U_LIB.S9S_MB_2U(SCH_1):P5E_CPU0_PE3_TX_DP<11>
    1  P5E_CPU0_PE3_TX_C_DP<11>      1  @S9S_MB_2U_LIB.S9S_MB_2U(SCH_1):P5E_CPU0_PE3_TX_C_DP<11>

Q_CAP_DIFFBUS  I157  C880   [Q_CAP_DIFFBUS_C0201-DIFF BUS_0A]
    2  P5E_CPU0_PE3_TX_DN<10>      2  @S9S_MB_2U_LIB.S9S_MB_2U(SCH_1):P5E_CPU0_PE3_TX_DN<10>
    1  P5E_CPU0_PE3_TX_C_DN<10>      1  @S9S_MB_2U_LIB.S9S_MB_2U(SCH_1):P5E_CPU0_PE3_TX_C_DN<10>

Q_CAP_DIFFBUS  I156  C881   [Q_CAP_DIFFBUS_C0201-DIFF BUS_0A]
    2  P5E_CPU0_PE3_TX_DP<10>      2  @S9S_MB_2U_LIB.S9S_MB_2U(SCH_1):P5E_CPU0_PE3_TX_DP<10>
    1  P5E_CPU0_PE3_TX_C_DP<10>      1  @S9S_MB_2U_LIB.S9S_MB_2U(SCH_1):P5E_CPU0_PE3_TX_C_DP<10>

Q_CAP_DIFFBUS  I155  C882   [Q_CAP_DIFFBUS_C0201-DIFF BUS_0A]
    2  P5E_CPU0_PE3_TX_DN<9>      2  @S9S_MB_2U_LIB.S9S_MB_2U(SCH_1):P5E_CPU0_PE3_TX_DN<9>
    1  P5E_CPU0_PE3_TX_C_DN<9>      1  @S9S_MB_2U_LIB.S9S_MB_2U(SCH_1):P5E_CPU0_PE3_TX_C_DN<9>

Q_CAP_DIFFBUS  I154  C883   [Q_CAP_DIFFBUS_C0201-DIFF BUS_0A]
    2  P5E_CPU0_PE3_TX_DP<9>      2  @S9S_MB_2U_LIB.S9S_MB_2U(SCH_1):P5E_CPU0_PE3_TX_DP<9>
    1  P5E_CPU0_PE3_TX_C_DP<9>      1  @S9S_MB_2U_LIB.S9S_MB_2U(SCH_1):P5E_CPU0_PE3_TX_C_DP<9>

Q_CAP_DIFFBUS  I153  C884   [Q_CAP_DIFFBUS_C0201-DIFF BUS_0A]
    2  P5E_CPU0_PE3_TX_DN<8>      2  @S9S_MB_2U_LIB.S9S_MB_2U(SCH_1):P5E_CPU0_PE3_TX_DN<8>
    1  P5E_CPU0_PE3_TX_C_DN<8>      1  @S9S_MB_2U_LIB.S9S_MB_2U(SCH_1):P5E_CPU0_PE3_TX_C_DN<8>

Q_CAP_DIFFBUS  I152  C885   [Q_CAP_DIFFBUS_C0201-DIFF BUS_0A]
    2  P5E_CPU0_PE3_TX_DP<8>      2  @S9S_MB_2U_LIB.S9S_MB_2U(SCH_1):P5E_CPU0_PE3_TX_DP<8>
    1  P5E_CPU0_PE3_TX_C_DP<8>      1  @S9S_MB_2U_LIB.S9S_MB_2U(SCH_1):P5E_CPU0_PE3_TX_C_DP<8>

Q_CAP_DIFFBUS  I139  C886   [Q_CAP_DIFFBUS_C0201-DIFF BUS_0A]
    2  P5E_CPU0_PE3_TX_DN<7>      2  @S9S_MB_2U_LIB.S9S_MB_2U(SCH_1):P5E_CPU0_PE3_TX_DN<7>
    1  P5E_CPU0_PE3_TX_C_DN<7>      1  @S9S_MB_2U_LIB.S9S_MB_2U(SCH_1):P5E_CPU0_PE3_TX_C_DN<7>

Q_CAP_DIFFBUS  I138  C887   [Q_CAP_DIFFBUS_C0201-DIFF BUS_0A]
    2  P5E_CPU0_PE3_TX_DP<7>      2  @S9S_MB_2U_LIB.S9S_MB_2U(SCH_1):P5E_CPU0_PE3_TX_DP<7>
    1  P5E_CPU0_PE3_TX_C_DP<7>      1  @S9S_MB_2U_LIB.S9S_MB_2U(SCH_1):P5E_CPU0_PE3_TX_C_DP<7>

Q_CAP_DIFFBUS  I137  C888   [Q_CAP_DIFFBUS_C0201-DIFF BUS_0A]
    2  P5E_CPU0_PE3_TX_DN<6>      2  @S9S_MB_2U_LIB.S9S_MB_2U(SCH_1):P5E_CPU0_PE3_TX_DN<6>
    1  P5E_CPU0_PE3_TX_C_DN<6>      1  @S9S_MB_2U_LIB.S9S_MB_2U(SCH_1):P5E_CPU0_PE3_TX_C_DN<6>

Q_CAP_DIFFBUS  I136  C889   [Q_CAP_DIFFBUS_C0201-DIFF BUS_0A]
    2  P5E_CPU0_PE3_TX_DP<6>      2  @S9S_MB_2U_LIB.S9S_MB_2U(SCH_1):P5E_CPU0_PE3_TX_DP<6>
    1  P5E_CPU0_PE3_TX_C_DP<6>      1  @S9S_MB_2U_LIB.S9S_MB_2U(SCH_1):P5E_CPU0_PE3_TX_C_DP<6>

Q_CAP_DIFFBUS  I135  C890   [Q_CAP_DIFFBUS_C0201-DIFF BUS_0A]
    2  P5E_CPU0_PE3_TX_DN<5>      2  @S9S_MB_2U_LIB.S9S_MB_2U(SCH_1):P5E_CPU0_PE3_TX_DN<5>
    1  P5E_CPU0_PE3_TX_C_DN<5>      1  @S9S_MB_2U_LIB.S9S_MB_2U(SCH_1):P5E_CPU0_PE3_TX_C_DN<5>

Q_CAP_DIFFBUS  I134  C891   [Q_CAP_DIFFBUS_C0201-DIFF BUS_0A]
    2  P5E_CPU0_PE3_TX_DP<5>      2  @S9S_MB_2U_LIB.S9S_MB_2U(SCH_1):P5E_CPU0_PE3_TX_DP<5>
    1  P5E_CPU0_PE3_TX_C_DP<5>      1  @S9S_MB_2U_LIB.S9S_MB_2U(SCH_1):P5E_CPU0_PE3_TX_C_DP<5>

Q_CAP_DIFFBUS  I129  C892   [Q_CAP_DIFFBUS_C0201-DIFF BUS_0A]
    2  P5E_CPU0_PE3_TX_DN<4>      2  @S9S_MB_2U_LIB.S9S_MB_2U(SCH_1):P5E_CPU0_PE3_TX_DN<4>
    1  P5E_CPU0_PE3_TX_C_DN<4>      1  @S9S_MB_2U_LIB.S9S_MB_2U(SCH_1):P5E_CPU0_PE3_TX_C_DN<4>

Q_CAP_DIFFBUS  I128  C893   [Q_CAP_DIFFBUS_C0201-DIFF BUS_0A]
    2  P5E_CPU0_PE3_TX_DP<4>      2  @S9S_MB_2U_LIB.S9S_MB_2U(SCH_1):P5E_CPU0_PE3_TX_DP<4>
    1  P5E_CPU0_PE3_TX_C_DP<4>      1  @S9S_MB_2U_LIB.S9S_MB_2U(SCH_1):P5E_CPU0_PE3_TX_C_DP<4>

Q_CAP_DIFFBUS  I127  C894   [Q_CAP_DIFFBUS_C0201-DIFF BUS_0A]
    2  P5E_CPU0_PE3_TX_DN<3>      2  @S9S_MB_2U_LIB.S9S_MB_2U(SCH_1):P5E_CPU0_PE3_TX_DN<3>
    1  P5E_CPU0_PE3_TX_C_DN<3>      1  @S9S_MB_2U_LIB.S9S_MB_2U(SCH_1):P5E_CPU0_PE3_TX_C_DN<3>

Q_CAP_DIFFBUS  I126  C895   [Q_CAP_DIFFBUS_C0201-DIFF BUS_0A]
    2  P5E_CPU0_PE3_TX_DP<3>      2  @S9S_MB_2U_LIB.S9S_MB_2U(SCH_1):P5E_CPU0_PE3_TX_DP<3>
    1  P5E_CPU0_PE3_TX_C_DP<3>      1  @S9S_MB_2U_LIB.S9S_MB_2U(SCH_1):P5E_CPU0_PE3_TX_C_DP<3>

Q_CAP_DIFFBUS  I125  C896   [Q_CAP_DIFFBUS_C0201-DIFF BUS_0A]
    2  P5E_CPU0_PE3_TX_DN<2>      2  @S9S_MB_2U_LIB.S9S_MB_2U(SCH_1):P5E_CPU0_PE3_TX_DN<2>
    1  P5E_CPU0_PE3_TX_C_DN<2>      1  @S9S_MB_2U_LIB.S9S_MB_2U(SCH_1):P5E_CPU0_PE3_TX_C_DN<2>

Q_CAP_DIFFBUS  I124  C897   [Q_CAP_DIFFBUS_C0201-DIFF BUS_0A]
    2  P5E_CPU0_PE3_TX_DP<2>      2  @S9S_MB_2U_LIB.S9S_MB_2U(SCH_1):P5E_CPU0_PE3_TX_DP<2>
    1  P5E_CPU0_PE3_TX_C_DP<2>      1  @S9S_MB_2U_LIB.S9S_MB_2U(SCH_1):P5E_CPU0_PE3_TX_C_DP<2>

Q_CAP_DIFFBUS  I123  C898   [Q_CAP_DIFFBUS_C0201-DIFF BUS_0A]
    2  P5E_CPU0_PE3_TX_DN<1>      2  @S9S_MB_2U_LIB.S9S_MB_2U(SCH_1):P5E_CPU0_PE3_TX_DN<1>
    1  P5E_CPU0_PE3_TX_C_DN<1>      1  @S9S_MB_2U_LIB.S9S_MB_2U(SCH_1):P5E_CPU0_PE3_TX_C_DN<1>

Q_CAP_DIFFBUS  I122  C899   [Q_CAP_DIFFBUS_C0201-DIFF BUS_0A]
    2  P5E_CPU0_PE3_TX_DP<1>      2  @S9S_MB_2U_LIB.S9S_MB_2U(SCH_1):P5E_CPU0_PE3_TX_DP<1>
    1  P5E_CPU0_PE3_TX_C_DP<1>      1  @S9S_MB_2U_LIB.S9S_MB_2U(SCH_1):P5E_CPU0_PE3_TX_C_DP<1>

Q_CAP_DIFFBUS  I121  C900   [Q_CAP_DIFFBUS_C0201-DIFF BUS_0A]
    2  P5E_CPU0_PE3_TX_DN<0>      2  @S9S_MB_2U_LIB.S9S_MB_2U(SCH_1):P5E_CPU0_PE3_TX_DN<0>
    1  P5E_CPU0_PE3_TX_C_DN<0>      1  @S9S_MB_2U_LIB.S9S_MB_2U(SCH_1):P5E_CPU0_PE3_TX_C_DN<0>

Q_CAP_DIFFBUS  I120  C901   [Q_CAP_DIFFBUS_C0201-DIFF BUS_0A]
    2  P5E_CPU0_PE3_TX_DP<0>      2  @S9S_MB_2U_LIB.S9S_MB_2U(SCH_1):P5E_CPU0_PE3_TX_DP<0>
    1  P5E_CPU0_PE3_TX_C_DP<0>      1  @S9S_MB_2U_LIB.S9S_MB_2U(SCH_1):P5E_CPU0_PE3_TX_C_DP<0>

Q_CAP_DIFFBUS  I77  C902   [Q_CAP_DIFFBUS_C0201-DIFF BUS_0A]
    2  P5E_CPU0_PE0_TX_DN<15>      2  @S9S_MB_2U_LIB.S9S_MB_2U(SCH_1):P5E_CPU0_PE0_TX_DN<15>
    1  P5E_CPU0_PE0_TX_C_DN<15>      1  @S9S_MB_2U_LIB.S9S_MB_2U(SCH_1):P5E_CPU0_PE0_TX_C_DN<15>

Q_CAP_DIFFBUS  I78  C903   [Q_CAP_DIFFBUS_C0201-DIFF BUS_0A]
    2  P5E_CPU0_PE0_TX_DP<15>      2  @S9S_MB_2U_LIB.S9S_MB_2U(SCH_1):P5E_CPU0_PE0_TX_DP<15>
    1  P5E_CPU0_PE0_TX_C_DP<15>      1  @S9S_MB_2U_LIB.S9S_MB_2U(SCH_1):P5E_CPU0_PE0_TX_C_DP<15>

Q_CAP_DIFFBUS  I76  C904   [Q_CAP_DIFFBUS_C0201-DIFF BUS_0A]
    2  P5E_CPU0_PE0_TX_DN<14>      2  @S9S_MB_2U_LIB.S9S_MB_2U(SCH_1):P5E_CPU0_PE0_TX_DN<14>
    1  P5E_CPU0_PE0_TX_C_DN<14>      1  @S9S_MB_2U_LIB.S9S_MB_2U(SCH_1):P5E_CPU0_PE0_TX_C_DN<14>

Q_CAP_DIFFBUS  I75  C905   [Q_CAP_DIFFBUS_C0201-DIFF BUS_0A]
    2  P5E_CPU0_PE0_TX_DP<14>      2  @S9S_MB_2U_LIB.S9S_MB_2U(SCH_1):P5E_CPU0_PE0_TX_DP<14>
    1  P5E_CPU0_PE0_TX_C_DP<14>      1  @S9S_MB_2U_LIB.S9S_MB_2U(SCH_1):P5E_CPU0_PE0_TX_C_DP<14>

Q_CAP_DIFFBUS  I69  C906   [Q_CAP_DIFFBUS_C0201-DIFF BUS_0A]
    2  P5E_CPU0_PE0_TX_DN<13>      2  @S9S_MB_2U_LIB.S9S_MB_2U(SCH_1):P5E_CPU0_PE0_TX_DN<13>
    1  P5E_CPU0_PE0_TX_C_DN<13>      1  @S9S_MB_2U_LIB.S9S_MB_2U(SCH_1):P5E_CPU0_PE0_TX_C_DN<13>

Q_CAP_DIFFBUS  I70  C907   [Q_CAP_DIFFBUS_C0201-DIFF BUS_0A]
    2  P5E_CPU0_PE0_TX_DP<13>      2  @S9S_MB_2U_LIB.S9S_MB_2U(SCH_1):P5E_CPU0_PE0_TX_DP<13>
    1  P5E_CPU0_PE0_TX_C_DP<13>      1  @S9S_MB_2U_LIB.S9S_MB_2U(SCH_1):P5E_CPU0_PE0_TX_C_DP<13>

Q_CAP_DIFFBUS  I68  C908   [Q_CAP_DIFFBUS_C0201-DIFF BUS_0A]
    2  P5E_CPU0_PE0_TX_DN<12>      2  @S9S_MB_2U_LIB.S9S_MB_2U(SCH_1):P5E_CPU0_PE0_TX_DN<12>
    1  P5E_CPU0_PE0_TX_C_DN<12>      1  @S9S_MB_2U_LIB.S9S_MB_2U(SCH_1):P5E_CPU0_PE0_TX_C_DN<12>

Q_CAP_DIFFBUS  I67  C909   [Q_CAP_DIFFBUS_C0201-DIFF BUS_0A]
    2  P5E_CPU0_PE0_TX_DP<12>      2  @S9S_MB_2U_LIB.S9S_MB_2U(SCH_1):P5E_CPU0_PE0_TX_DP<12>
    1  P5E_CPU0_PE0_TX_C_DP<12>      1  @S9S_MB_2U_LIB.S9S_MB_2U(SCH_1):P5E_CPU0_PE0_TX_C_DP<12>

Q_CAP_DIFFBUS  I66  C910   [Q_CAP_DIFFBUS_C0201-DIFF BUS_0A]
    2  P5E_CPU0_PE0_TX_DN<11>      2  @S9S_MB_2U_LIB.S9S_MB_2U(SCH_1):P5E_CPU0_PE0_TX_DN<11>
    1  P5E_CPU0_PE0_TX_C_DN<11>      1  @S9S_MB_2U_LIB.S9S_MB_2U(SCH_1):P5E_CPU0_PE0_TX_C_DN<11>

Q_CAP_DIFFBUS  I65  C911   [Q_CAP_DIFFBUS_C0201-DIFF BUS_0A]
    2  P5E_CPU0_PE0_TX_DP<11>      2  @S9S_MB_2U_LIB.S9S_MB_2U(SCH_1):P5E_CPU0_PE0_TX_DP<11>
    1  P5E_CPU0_PE0_TX_C_DP<11>      1  @S9S_MB_2U_LIB.S9S_MB_2U(SCH_1):P5E_CPU0_PE0_TX_C_DP<11>

Q_CAP_DIFFBUS  I64  C912   [Q_CAP_DIFFBUS_C0201-DIFF BUS_0A]
    2  P5E_CPU0_PE0_TX_DN<10>      2  @S9S_MB_2U_LIB.S9S_MB_2U(SCH_1):P5E_CPU0_PE0_TX_DN<10>
    1  P5E_CPU0_PE0_TX_C_DN<10>      1  @S9S_MB_2U_LIB.S9S_MB_2U(SCH_1):P5E_CPU0_PE0_TX_C_DN<10>

Q_CAP_DIFFBUS  I63  C913   [Q_CAP_DIFFBUS_C0201-DIFF BUS_0A]
    2  P5E_CPU0_PE0_TX_DP<10>      2  @S9S_MB_2U_LIB.S9S_MB_2U(SCH_1):P5E_CPU0_PE0_TX_DP<10>
    1  P5E_CPU0_PE0_TX_C_DP<10>      1  @S9S_MB_2U_LIB.S9S_MB_2U(SCH_1):P5E_CPU0_PE0_TX_C_DP<10>

Q_CAP_DIFFBUS  I62  C914   [Q_CAP_DIFFBUS_C0201-DIFF BUS_0A]
    2  P5E_CPU0_PE0_TX_DN<9>      2  @S9S_MB_2U_LIB.S9S_MB_2U(SCH_1):P5E_CPU0_PE0_TX_DN<9>
    1  P5E_CPU0_PE0_TX_C_DN<9>      1  @S9S_MB_2U_LIB.S9S_MB_2U(SCH_1):P5E_CPU0_PE0_TX_C_DN<9>

Q_CAP_DIFFBUS  I61  C915   [Q_CAP_DIFFBUS_C0201-DIFF BUS_0A]
    2  P5E_CPU0_PE0_TX_DP<9>      2  @S9S_MB_2U_LIB.S9S_MB_2U(SCH_1):P5E_CPU0_PE0_TX_DP<9>
    1  P5E_CPU0_PE0_TX_C_DP<9>      1  @S9S_MB_2U_LIB.S9S_MB_2U(SCH_1):P5E_CPU0_PE0_TX_C_DP<9>

Q_CAP_DIFFBUS  I59  C916   [Q_CAP_DIFFBUS_C0201-DIFF BUS_0A]
    2  P5E_CPU0_PE0_TX_DN<8>      2  @S9S_MB_2U_LIB.S9S_MB_2U(SCH_1):P5E_CPU0_PE0_TX_DN<8>
    1  P5E_CPU0_PE0_TX_C_DN<8>      1  @S9S_MB_2U_LIB.S9S_MB_2U(SCH_1):P5E_CPU0_PE0_TX_C_DN<8>

Q_CAP_DIFFBUS  I58  C917   [Q_CAP_DIFFBUS_C0201-DIFF BUS_0A]
    2  P5E_CPU0_PE0_TX_DP<8>      2  @S9S_MB_2U_LIB.S9S_MB_2U(SCH_1):P5E_CPU0_PE0_TX_DP<8>
    1  P5E_CPU0_PE0_TX_C_DP<8>      1  @S9S_MB_2U_LIB.S9S_MB_2U(SCH_1):P5E_CPU0_PE0_TX_C_DP<8>

Q_CAP_DIFFBUS  I57  C918   [Q_CAP_DIFFBUS_C0201-DIFF BUS_0A]
    2  P5E_CPU0_PE0_TX_DN<7>      2  @S9S_MB_2U_LIB.S9S_MB_2U(SCH_1):P5E_CPU0_PE0_TX_DN<7>
    1  P5E_CPU0_PE0_TX_C_DN<7>      1  @S9S_MB_2U_LIB.S9S_MB_2U(SCH_1):P5E_CPU0_PE0_TX_C_DN<7>

Q_CAP_DIFFBUS  I56  C919   [Q_CAP_DIFFBUS_C0201-DIFF BUS_0A]
    2  P5E_CPU0_PE0_TX_DP<7>      2  @S9S_MB_2U_LIB.S9S_MB_2U(SCH_1):P5E_CPU0_PE0_TX_DP<7>
    1  P5E_CPU0_PE0_TX_C_DP<7>      1  @S9S_MB_2U_LIB.S9S_MB_2U(SCH_1):P5E_CPU0_PE0_TX_C_DP<7>

Q_CAP_DIFFBUS  I54  C920   [Q_CAP_DIFFBUS_C0201-DIFF BUS_0A]
    2  P5E_CPU0_PE0_TX_DN<6>      2  @S9S_MB_2U_LIB.S9S_MB_2U(SCH_1):P5E_CPU0_PE0_TX_DN<6>
    1  P5E_CPU0_PE0_TX_C_DN<6>      1  @S9S_MB_2U_LIB.S9S_MB_2U(SCH_1):P5E_CPU0_PE0_TX_C_DN<6>

Q_CAP_DIFFBUS  I55  C921   [Q_CAP_DIFFBUS_C0201-DIFF BUS_0A]
    2  P5E_CPU0_PE0_TX_DP<6>      2  @S9S_MB_2U_LIB.S9S_MB_2U(SCH_1):P5E_CPU0_PE0_TX_DP<6>
    1  P5E_CPU0_PE0_TX_C_DP<6>      1  @S9S_MB_2U_LIB.S9S_MB_2U(SCH_1):P5E_CPU0_PE0_TX_C_DP<6>

Q_CAP_DIFFBUS  I53  C922   [Q_CAP_DIFFBUS_C0201-DIFF BUS_0A]
    2  P5E_CPU0_PE0_TX_DN<5>      2  @S9S_MB_2U_LIB.S9S_MB_2U(SCH_1):P5E_CPU0_PE0_TX_DN<5>
    1  P5E_CPU0_PE0_TX_C_DN<5>      1  @S9S_MB_2U_LIB.S9S_MB_2U(SCH_1):P5E_CPU0_PE0_TX_C_DN<5>

Q_CAP_DIFFBUS  I25  C923   [Q_CAP_DIFFBUS_C0201-DIFF BUS_0A]
    2  P5E_CPU0_PE0_TX_DP<5>      2  @S9S_MB_2U_LIB.S9S_MB_2U(SCH_1):P5E_CPU0_PE0_TX_DP<5>
    1  P5E_CPU0_PE0_TX_C_DP<5>      1  @S9S_MB_2U_LIB.S9S_MB_2U(SCH_1):P5E_CPU0_PE0_TX_C_DP<5>

Q_CAP_DIFFBUS  I24  C924   [Q_CAP_DIFFBUS_C0201-DIFF BUS_0A]
    2  P5E_CPU0_PE0_TX_DN<4>      2  @S9S_MB_2U_LIB.S9S_MB_2U(SCH_1):P5E_CPU0_PE0_TX_DN<4>
    1  P5E_CPU0_PE0_TX_C_DN<4>      1  @S9S_MB_2U_LIB.S9S_MB_2U(SCH_1):P5E_CPU0_PE0_TX_C_DN<4>

Q_CAP_DIFFBUS  I23  C925   [Q_CAP_DIFFBUS_C0201-DIFF BUS_0A]
    2  P5E_CPU0_PE0_TX_DP<4>      2  @S9S_MB_2U_LIB.S9S_MB_2U(SCH_1):P5E_CPU0_PE0_TX_DP<4>
    1  P5E_CPU0_PE0_TX_C_DP<4>      1  @S9S_MB_2U_LIB.S9S_MB_2U(SCH_1):P5E_CPU0_PE0_TX_C_DP<4>

Q_CAP_DIFFBUS  I22  C926   [Q_CAP_DIFFBUS_C0201-DIFF BUS_0A]
    2  P5E_CPU0_PE0_TX_DN<3>      2  @S9S_MB_2U_LIB.S9S_MB_2U(SCH_1):P5E_CPU0_PE0_TX_DN<3>
    1  P5E_CPU0_PE0_TX_C_DN<3>      1  @S9S_MB_2U_LIB.S9S_MB_2U(SCH_1):P5E_CPU0_PE0_TX_C_DN<3>

Q_CAP_DIFFBUS  I21  C927   [Q_CAP_DIFFBUS_C0201-DIFF BUS_0A]
    2  P5E_CPU0_PE0_TX_DP<3>      2  @S9S_MB_2U_LIB.S9S_MB_2U(SCH_1):P5E_CPU0_PE0_TX_DP<3>
    1  P5E_CPU0_PE0_TX_C_DP<3>      1  @S9S_MB_2U_LIB.S9S_MB_2U(SCH_1):P5E_CPU0_PE0_TX_C_DP<3>

Q_CAP_DIFFBUS  I20  C928   [Q_CAP_DIFFBUS_C0201-DIFF BUS_0A]
    2  P5E_CPU0_PE0_TX_DN<2>      2  @S9S_MB_2U_LIB.S9S_MB_2U(SCH_1):P5E_CPU0_PE0_TX_DN<2>
    1  P5E_CPU0_PE0_TX_C_DN<2>      1  @S9S_MB_2U_LIB.S9S_MB_2U(SCH_1):P5E_CPU0_PE0_TX_C_DN<2>

Q_CAP_DIFFBUS  I19  C929   [Q_CAP_DIFFBUS_C0201-DIFF BUS_0A]
    2  P5E_CPU0_PE0_TX_DP<2>      2  @S9S_MB_2U_LIB.S9S_MB_2U(SCH_1):P5E_CPU0_PE0_TX_DP<2>
    1  P5E_CPU0_PE0_TX_C_DP<2>      1  @S9S_MB_2U_LIB.S9S_MB_2U(SCH_1):P5E_CPU0_PE0_TX_C_DP<2>

Q_CAP_DIFFBUS  I18  C930   [Q_CAP_DIFFBUS_C0201-DIFF BUS_0A]
    2  P5E_CPU0_PE0_TX_DN<1>      2  @S9S_MB_2U_LIB.S9S_MB_2U(SCH_1):P5E_CPU0_PE0_TX_DN<1>
    1  P5E_CPU0_PE0_TX_C_DN<1>      1  @S9S_MB_2U_LIB.S9S_MB_2U(SCH_1):P5E_CPU0_PE0_TX_C_DN<1>

Q_CAP_DIFFBUS  I17  C931   [Q_CAP_DIFFBUS_C0201-DIFF BUS_0A]
    2  P5E_CPU0_PE0_TX_DP<1>      2  @S9S_MB_2U_LIB.S9S_MB_2U(SCH_1):P5E_CPU0_PE0_TX_DP<1>
    1  P5E_CPU0_PE0_TX_C_DP<1>      1  @S9S_MB_2U_LIB.S9S_MB_2U(SCH_1):P5E_CPU0_PE0_TX_C_DP<1>

Q_CAP_DIFFBUS  I16  C932   [Q_CAP_DIFFBUS_C0201-DIFF BUS_0A]
    2  P5E_CPU0_PE0_TX_DN<0>      2  @S9S_MB_2U_LIB.S9S_MB_2U(SCH_1):P5E_CPU0_PE0_TX_DN<0>
    1  P5E_CPU0_PE0_TX_C_DN<0>      1  @S9S_MB_2U_LIB.S9S_MB_2U(SCH_1):P5E_CPU0_PE0_TX_C_DN<0>

Q_CAP_DIFFBUS  I15  C933   [Q_CAP_DIFFBUS_C0201-DIFF BUS_0A]
    2  P5E_CPU0_PE0_TX_DP<0>      2  @S9S_MB_2U_LIB.S9S_MB_2U(SCH_1):P5E_CPU0_PE0_TX_DP<0>
    1  P5E_CPU0_PE0_TX_C_DP<0>      1  @S9S_MB_2U_LIB.S9S_MB_2U(SCH_1):P5E_CPU0_PE0_TX_C_DP<0>

Q_CAP_DIFFBUS  I201  C934   [Q_CAP_DIFFBUS_C0201-DIFF BUS_0A]
    2  P5E_CPU0_PE1_TX_DN<15>      2  @S9S_MB_2U_LIB.S9S_MB_2U(SCH_1):P5E_CPU0_PE1_TX_DN<15>
    1  P5E_CPU0_PE1_TX_C_DN<15>      1  @S9S_MB_2U_LIB.S9S_MB_2U(SCH_1):P5E_CPU0_PE1_TX_C_DN<15>

Q_CAP_DIFFBUS  I202  C935   [Q_CAP_DIFFBUS_C0201-DIFF BUS_0A]
    2  P5E_CPU0_PE1_TX_DP<15>      2  @S9S_MB_2U_LIB.S9S_MB_2U(SCH_1):P5E_CPU0_PE1_TX_DP<15>
    1  P5E_CPU0_PE1_TX_C_DP<15>      1  @S9S_MB_2U_LIB.S9S_MB_2U(SCH_1):P5E_CPU0_PE1_TX_C_DP<15>

Q_CAP_DIFFBUS  I200  C936   [Q_CAP_DIFFBUS_C0201-DIFF BUS_0A]
    2  P5E_CPU0_PE1_TX_DN<14>      2  @S9S_MB_2U_LIB.S9S_MB_2U(SCH_1):P5E_CPU0_PE1_TX_DN<14>
    1  P5E_CPU0_PE1_TX_C_DN<14>      1  @S9S_MB_2U_LIB.S9S_MB_2U(SCH_1):P5E_CPU0_PE1_TX_C_DN<14>

Q_CAP_DIFFBUS  I199  C937   [Q_CAP_DIFFBUS_C0201-DIFF BUS_0A]
    2  P5E_CPU0_PE1_TX_DP<14>      2  @S9S_MB_2U_LIB.S9S_MB_2U(SCH_1):P5E_CPU0_PE1_TX_DP<14>
    1  P5E_CPU0_PE1_TX_C_DP<14>      1  @S9S_MB_2U_LIB.S9S_MB_2U(SCH_1):P5E_CPU0_PE1_TX_C_DP<14>

Q_CAP_DIFFBUS  I183  C938   [Q_CAP_DIFFBUS_C0201-DIFF BUS_0A]
    2  P5E_CPU0_PE1_TX_DN<13>      2  @S9S_MB_2U_LIB.S9S_MB_2U(SCH_1):P5E_CPU0_PE1_TX_DN<13>
    1  P5E_CPU0_PE1_TX_C_DN<13>      1  @S9S_MB_2U_LIB.S9S_MB_2U(SCH_1):P5E_CPU0_PE1_TX_C_DN<13>

Q_CAP_DIFFBUS  I184  C939   [Q_CAP_DIFFBUS_C0201-DIFF BUS_0A]
    2  P5E_CPU0_PE1_TX_DP<13>      2  @S9S_MB_2U_LIB.S9S_MB_2U(SCH_1):P5E_CPU0_PE1_TX_DP<13>
    1  P5E_CPU0_PE1_TX_C_DP<13>      1  @S9S_MB_2U_LIB.S9S_MB_2U(SCH_1):P5E_CPU0_PE1_TX_C_DP<13>

Q_CAP_DIFFBUS  I185  C940   [Q_CAP_DIFFBUS_C0201-DIFF BUS_0A]
    2  P5E_CPU0_PE1_TX_DN<12>      2  @S9S_MB_2U_LIB.S9S_MB_2U(SCH_1):P5E_CPU0_PE1_TX_DN<12>
    1  P5E_CPU0_PE1_TX_C_DN<12>      1  @S9S_MB_2U_LIB.S9S_MB_2U(SCH_1):P5E_CPU0_PE1_TX_C_DN<12>

Q_CAP_DIFFBUS  I180  C941   [Q_CAP_DIFFBUS_C0201-DIFF BUS_0A]
    2  P5E_CPU0_PE1_TX_DP<12>      2  @S9S_MB_2U_LIB.S9S_MB_2U(SCH_1):P5E_CPU0_PE1_TX_DP<12>
    1  P5E_CPU0_PE1_TX_C_DP<12>      1  @S9S_MB_2U_LIB.S9S_MB_2U(SCH_1):P5E_CPU0_PE1_TX_C_DP<12>

Q_CAP_DIFFBUS  I181  C942   [Q_CAP_DIFFBUS_C0201-DIFF BUS_0A]
    2  P5E_CPU0_PE1_TX_DN<11>      2  @S9S_MB_2U_LIB.S9S_MB_2U(SCH_1):P5E_CPU0_PE1_TX_DN<11>
    1  P5E_CPU0_PE1_TX_C_DN<11>      1  @S9S_MB_2U_LIB.S9S_MB_2U(SCH_1):P5E_CPU0_PE1_TX_C_DN<11>

Q_CAP_DIFFBUS  I182  C943   [Q_CAP_DIFFBUS_C0201-DIFF BUS_0A]
    2  P5E_CPU0_PE1_TX_DP<11>      2  @S9S_MB_2U_LIB.S9S_MB_2U(SCH_1):P5E_CPU0_PE1_TX_DP<11>
    1  P5E_CPU0_PE1_TX_C_DP<11>      1  @S9S_MB_2U_LIB.S9S_MB_2U(SCH_1):P5E_CPU0_PE1_TX_C_DP<11>

Q_CAP_DIFFBUS  I179  C944   [Q_CAP_DIFFBUS_C0201-DIFF BUS_0A]
    2  P5E_CPU0_PE1_TX_DN<10>      2  @S9S_MB_2U_LIB.S9S_MB_2U(SCH_1):P5E_CPU0_PE1_TX_DN<10>
    1  P5E_CPU0_PE1_TX_C_DN<10>      1  @S9S_MB_2U_LIB.S9S_MB_2U(SCH_1):P5E_CPU0_PE1_TX_C_DN<10>

Q_CAP_DIFFBUS  I178  C945   [Q_CAP_DIFFBUS_C0201-DIFF BUS_0A]
    2  P5E_CPU0_PE1_TX_DP<10>      2  @S9S_MB_2U_LIB.S9S_MB_2U(SCH_1):P5E_CPU0_PE1_TX_DP<10>
    1  P5E_CPU0_PE1_TX_C_DP<10>      1  @S9S_MB_2U_LIB.S9S_MB_2U(SCH_1):P5E_CPU0_PE1_TX_C_DP<10>

Q_CAP_DIFFBUS  I177  C946   [Q_CAP_DIFFBUS_C0201-DIFF BUS_0A]
    2  P5E_CPU0_PE1_TX_DN<9>      2  @S9S_MB_2U_LIB.S9S_MB_2U(SCH_1):P5E_CPU0_PE1_TX_DN<9>
    1  P5E_CPU0_PE1_TX_C_DN<9>      1  @S9S_MB_2U_LIB.S9S_MB_2U(SCH_1):P5E_CPU0_PE1_TX_C_DN<9>

Q_CAP_DIFFBUS  I176  C947   [Q_CAP_DIFFBUS_C0201-DIFF BUS_0A]
    2  P5E_CPU0_PE1_TX_DP<9>      2  @S9S_MB_2U_LIB.S9S_MB_2U(SCH_1):P5E_CPU0_PE1_TX_DP<9>
    1  P5E_CPU0_PE1_TX_C_DP<9>      1  @S9S_MB_2U_LIB.S9S_MB_2U(SCH_1):P5E_CPU0_PE1_TX_C_DP<9>

Q_CAP_DIFFBUS  I168  C948   [Q_CAP_DIFFBUS_C0201-DIFF BUS_0A]
    2  P5E_CPU0_PE1_TX_DN<8>      2  @S9S_MB_2U_LIB.S9S_MB_2U(SCH_1):P5E_CPU0_PE1_TX_DN<8>
    1  P5E_CPU0_PE1_TX_C_DN<8>      1  @S9S_MB_2U_LIB.S9S_MB_2U(SCH_1):P5E_CPU0_PE1_TX_C_DN<8>

Q_CAP_DIFFBUS  I167  C949   [Q_CAP_DIFFBUS_C0201-DIFF BUS_0A]
    2  P5E_CPU0_PE1_TX_DP<8>      2  @S9S_MB_2U_LIB.S9S_MB_2U(SCH_1):P5E_CPU0_PE1_TX_DP<8>
    1  P5E_CPU0_PE1_TX_C_DP<8>      1  @S9S_MB_2U_LIB.S9S_MB_2U(SCH_1):P5E_CPU0_PE1_TX_C_DP<8>

Q_CAP_DIFFBUS  I165  C950   [Q_CAP_DIFFBUS_C0201-DIFF BUS_0A]
    2  P5E_CPU0_PE1_TX_DN<7>      2  @S9S_MB_2U_LIB.S9S_MB_2U(SCH_1):P5E_CPU0_PE1_TX_DN<7>
    1  P5E_CPU0_PE1_TX_C_DN<7>      1  @S9S_MB_2U_LIB.S9S_MB_2U(SCH_1):P5E_CPU0_PE1_TX_C_DN<7>

Q_CAP_DIFFBUS  I166  C951   [Q_CAP_DIFFBUS_C0201-DIFF BUS_0A]
    2  P5E_CPU0_PE1_TX_DP<7>      2  @S9S_MB_2U_LIB.S9S_MB_2U(SCH_1):P5E_CPU0_PE1_TX_DP<7>
    1  P5E_CPU0_PE1_TX_C_DP<7>      1  @S9S_MB_2U_LIB.S9S_MB_2U(SCH_1):P5E_CPU0_PE1_TX_C_DP<7>

Q_CAP_DIFFBUS  I164  C952   [Q_CAP_DIFFBUS_C0201-DIFF BUS_0A]
    2  P5E_CPU0_PE1_TX_DN<6>      2  @S9S_MB_2U_LIB.S9S_MB_2U(SCH_1):P5E_CPU0_PE1_TX_DN<6>
    1  P5E_CPU0_PE1_TX_C_DN<6>      1  @S9S_MB_2U_LIB.S9S_MB_2U(SCH_1):P5E_CPU0_PE1_TX_C_DN<6>

Q_CAP_DIFFBUS  I163  C953   [Q_CAP_DIFFBUS_C0201-DIFF BUS_0A]
    2  P5E_CPU0_PE1_TX_DP<6>      2  @S9S_MB_2U_LIB.S9S_MB_2U(SCH_1):P5E_CPU0_PE1_TX_DP<6>
    1  P5E_CPU0_PE1_TX_C_DP<6>      1  @S9S_MB_2U_LIB.S9S_MB_2U(SCH_1):P5E_CPU0_PE1_TX_C_DP<6>

Q_CAP_DIFFBUS  I162  C954   [Q_CAP_DIFFBUS_C0201-DIFF BUS_0A]
    2  P5E_CPU0_PE1_TX_DN<5>      2  @S9S_MB_2U_LIB.S9S_MB_2U(SCH_1):P5E_CPU0_PE1_TX_DN<5>
    1  P5E_CPU0_PE1_TX_C_DN<5>      1  @S9S_MB_2U_LIB.S9S_MB_2U(SCH_1):P5E_CPU0_PE1_TX_C_DN<5>

Q_CAP_DIFFBUS  I125  C955   [Q_CAP_DIFFBUS_C0201-DIFF BUS_0A]
    2  P5E_CPU0_PE1_TX_DP<5>      2  @S9S_MB_2U_LIB.S9S_MB_2U(SCH_1):P5E_CPU0_PE1_TX_DP<5>
    1  P5E_CPU0_PE1_TX_C_DP<5>      1  @S9S_MB_2U_LIB.S9S_MB_2U(SCH_1):P5E_CPU0_PE1_TX_C_DP<5>

Q_CAP_DIFFBUS  I124  C956   [Q_CAP_DIFFBUS_C0201-DIFF BUS_0A]
    2  P5E_CPU0_PE1_TX_DN<4>      2  @S9S_MB_2U_LIB.S9S_MB_2U(SCH_1):P5E_CPU0_PE1_TX_DN<4>
    1  P5E_CPU0_PE1_TX_C_DN<4>      1  @S9S_MB_2U_LIB.S9S_MB_2U(SCH_1):P5E_CPU0_PE1_TX_C_DN<4>

Q_CAP_DIFFBUS  I123  C957   [Q_CAP_DIFFBUS_C0201-DIFF BUS_0A]
    2  P5E_CPU0_PE1_TX_DP<4>      2  @S9S_MB_2U_LIB.S9S_MB_2U(SCH_1):P5E_CPU0_PE1_TX_DP<4>
    1  P5E_CPU0_PE1_TX_C_DP<4>      1  @S9S_MB_2U_LIB.S9S_MB_2U(SCH_1):P5E_CPU0_PE1_TX_C_DP<4>

Q_CAP_DIFFBUS  I122  C958   [Q_CAP_DIFFBUS_C0201-DIFF BUS_0A]
    2  P5E_CPU0_PE1_TX_DN<3>      2  @S9S_MB_2U_LIB.S9S_MB_2U(SCH_1):P5E_CPU0_PE1_TX_DN<3>
    1  P5E_CPU0_PE1_TX_C_DN<3>      1  @S9S_MB_2U_LIB.S9S_MB_2U(SCH_1):P5E_CPU0_PE1_TX_C_DN<3>

Q_CAP_DIFFBUS  I121  C959   [Q_CAP_DIFFBUS_C0201-DIFF BUS_0A]
    2  P5E_CPU0_PE1_TX_DP<3>      2  @S9S_MB_2U_LIB.S9S_MB_2U(SCH_1):P5E_CPU0_PE1_TX_DP<3>
    1  P5E_CPU0_PE1_TX_C_DP<3>      1  @S9S_MB_2U_LIB.S9S_MB_2U(SCH_1):P5E_CPU0_PE1_TX_C_DP<3>

Q_CAP_DIFFBUS  I119  C960   [Q_CAP_DIFFBUS_C0201-DIFF BUS_0A]
    2  P5E_CPU0_PE1_TX_DN<2>      2  @S9S_MB_2U_LIB.S9S_MB_2U(SCH_1):P5E_CPU0_PE1_TX_DN<2>
    1  P5E_CPU0_PE1_TX_C_DN<2>      1  @S9S_MB_2U_LIB.S9S_MB_2U(SCH_1):P5E_CPU0_PE1_TX_C_DN<2>

Q_CAP_DIFFBUS  I120  C961   [Q_CAP_DIFFBUS_C0201-DIFF BUS_0A]
    2  P5E_CPU0_PE1_TX_DP<2>      2  @S9S_MB_2U_LIB.S9S_MB_2U(SCH_1):P5E_CPU0_PE1_TX_DP<2>
    1  P5E_CPU0_PE1_TX_C_DP<2>      1  @S9S_MB_2U_LIB.S9S_MB_2U(SCH_1):P5E_CPU0_PE1_TX_C_DP<2>

Q_CAP_DIFFBUS  I118  C962   [Q_CAP_DIFFBUS_C0201-DIFF BUS_0A]
    2  P5E_CPU0_PE1_TX_DN<1>      2  @S9S_MB_2U_LIB.S9S_MB_2U(SCH_1):P5E_CPU0_PE1_TX_DN<1>
    1  P5E_CPU0_PE1_TX_C_DN<1>      1  @S9S_MB_2U_LIB.S9S_MB_2U(SCH_1):P5E_CPU0_PE1_TX_C_DN<1>

Q_CAP_DIFFBUS  I116  C963   [Q_CAP_DIFFBUS_C0201-DIFF BUS_0A]
    2  P5E_CPU0_PE1_TX_DP<1>      2  @S9S_MB_2U_LIB.S9S_MB_2U(SCH_1):P5E_CPU0_PE1_TX_DP<1>
    1  P5E_CPU0_PE1_TX_C_DP<1>      1  @S9S_MB_2U_LIB.S9S_MB_2U(SCH_1):P5E_CPU0_PE1_TX_C_DP<1>

Q_CAP_DIFFBUS  I117  C964   [Q_CAP_DIFFBUS_C0201-DIFF BUS_0A]
    2  P5E_CPU0_PE1_TX_DN<0>      2  @S9S_MB_2U_LIB.S9S_MB_2U(SCH_1):P5E_CPU0_PE1_TX_DN<0>
    1  P5E_CPU0_PE1_TX_C_DN<0>      1  @S9S_MB_2U_LIB.S9S_MB_2U(SCH_1):P5E_CPU0_PE1_TX_C_DN<0>

Q_CAP_DIFFBUS  I115  C965   [Q_CAP_DIFFBUS_C0201-DIFF BUS_0A]
    2  P5E_CPU0_PE1_TX_DP<0>      2  @S9S_MB_2U_LIB.S9S_MB_2U(SCH_1):P5E_CPU0_PE1_TX_DP<0>
    1  P5E_CPU0_PE1_TX_C_DP<0>      1  @S9S_MB_2U_LIB.S9S_MB_2U(SCH_1):P5E_CPU0_PE1_TX_C_DP<0>

Q_CAP  I7   C966   [Q_CAP_C0402-22UF,4V,20%,X6S,CHA]
    1  PVCCIN_CPU0        A  @S9S_MB_2U_LIB.S9S_MB_2U(SCH_1):PVCCIN_CPU0
    2  GND                B  @S9S_MB_2U_LIB.S9S_MB_2U(SCH_1):GND

Q_CAP  I53  C967   [Q_CAP_C0402-22UF,4V,20%,X6S,CHA]
    1  PVCCIN_CPU0        A  @S9S_MB_2U_LIB.S9S_MB_2U(SCH_1):PVCCIN_CPU0
    2  GND                B  @S9S_MB_2U_LIB.S9S_MB_2U(SCH_1):GND

Q_CAP  I99  C968   [Q_CAP_C0402-22UF,4V,20%,X6S,CHA]
    1  PVCCIN_CPU0        A  @S9S_MB_2U_LIB.S9S_MB_2U(SCH_1):PVCCIN_CPU0
    2  GND                B  @S9S_MB_2U_LIB.S9S_MB_2U(SCH_1):GND

Q_CAP  I101  C969   [Q_CAP_C0402-22UF,4V,20%,X6S,CHA]
    1  PVCCIN_CPU0        A  @S9S_MB_2U_LIB.S9S_MB_2U(SCH_1):PVCCIN_CPU0
    2  GND                B  @S9S_MB_2U_LIB.S9S_MB_2U(SCH_1):GND

Q_CAP  I8   C970   [Q_CAP_C0402-22UF,4V,20%,X6S,CHA]
    1  PVCCIN_CPU0        A  @S9S_MB_2U_LIB.S9S_MB_2U(SCH_1):PVCCIN_CPU0
    2  GND                B  @S9S_MB_2U_LIB.S9S_MB_2U(SCH_1):GND

Q_CAP  I52  C971   [Q_CAP_C0402-22UF,4V,20%,X6S,CHA]
    1  PVCCIN_CPU0        A  @S9S_MB_2U_LIB.S9S_MB_2U(SCH_1):PVCCIN_CPU0
    2  GND                B  @S9S_MB_2U_LIB.S9S_MB_2U(SCH_1):GND

Q_CAP  I97  C972   [Q_CAP_C0402-22UF,4V,20%,X6S,CHA]
    1  PVCCIN_CPU0        A  @S9S_MB_2U_LIB.S9S_MB_2U(SCH_1):PVCCIN_CPU0
    2  GND                B  @S9S_MB_2U_LIB.S9S_MB_2U(SCH_1):GND

Q_CAP  I98  C973   [Q_CAP_C0402-22UF,4V,20%,X6S,CHA]
    1  PVCCIN_CPU0        A  @S9S_MB_2U_LIB.S9S_MB_2U(SCH_1):PVCCIN_CPU0
    2  GND                B  @S9S_MB_2U_LIB.S9S_MB_2U(SCH_1):GND

Q_CAP  I9   C974   [Q_CAP_C0402-22UF,4V,20%,X6S,CHA]
    1  PVCCIN_CPU0        A  @S9S_MB_2U_LIB.S9S_MB_2U(SCH_1):PVCCIN_CPU0
    2  GND                B  @S9S_MB_2U_LIB.S9S_MB_2U(SCH_1):GND

Q_CAP  I51  C975   [Q_CAP_C0402-22UF,4V,20%,X6S,CHA]
    1  PVCCIN_CPU0        A  @S9S_MB_2U_LIB.S9S_MB_2U(SCH_1):PVCCIN_CPU0
    2  GND                B  @S9S_MB_2U_LIB.S9S_MB_2U(SCH_1):GND

Q_CAP  I95  C976   [Q_CAP_C0402-22UF,4V,20%,X6S,CHA]
    1  PVCCIN_CPU0        A  @S9S_MB_2U_LIB.S9S_MB_2U(SCH_1):PVCCIN_CPU0
    2  GND                B  @S9S_MB_2U_LIB.S9S_MB_2U(SCH_1):GND

Q_CAP  I96  C977   [Q_CAP_C0402-22UF,4V,20%,X6S,CHA]
    1  PVCCIN_CPU0        A  @S9S_MB_2U_LIB.S9S_MB_2U(SCH_1):PVCCIN_CPU0
    2  GND                B  @S9S_MB_2U_LIB.S9S_MB_2U(SCH_1):GND

Q_CAP  I10  C978   [Q_CAP_C0402-22UF,4V,20%,X6S,CHA]
    1  PVCCIN_CPU0        A  @S9S_MB_2U_LIB.S9S_MB_2U(SCH_1):PVCCIN_CPU0
    2  GND                B  @S9S_MB_2U_LIB.S9S_MB_2U(SCH_1):GND

Q_CAP  I50  C979   [Q_CAP_C0402-22UF,4V,20%,X6S,CHA]
    1  PVCCIN_CPU0        A  @S9S_MB_2U_LIB.S9S_MB_2U(SCH_1):PVCCIN_CPU0
    2  GND                B  @S9S_MB_2U_LIB.S9S_MB_2U(SCH_1):GND

Q_CAP  I93  C980   [Q_CAP_C0402-22UF,4V,20%,X6S,CHA]
    1  PVCCIN_CPU0        A  @S9S_MB_2U_LIB.S9S_MB_2U(SCH_1):PVCCIN_CPU0
    2  GND                B  @S9S_MB_2U_LIB.S9S_MB_2U(SCH_1):GND

Q_CAP  I94  C981   [Q_CAP_C0402-22UF,4V,20%,X6S,CHA]
    1  PVCCIN_CPU0        A  @S9S_MB_2U_LIB.S9S_MB_2U(SCH_1):PVCCIN_CPU0
    2  GND                B  @S9S_MB_2U_LIB.S9S_MB_2U(SCH_1):GND

Q_CAP  I12  C982   [Q_CAP_C0402-22UF,4V,20%,X6S,CHA]
    1  PVCCIN_CPU0        A  @S9S_MB_2U_LIB.S9S_MB_2U(SCH_1):PVCCIN_CPU0
    2  GND                B  @S9S_MB_2U_LIB.S9S_MB_2U(SCH_1):GND

Q_CAP  I49  C983   [Q_CAP_C0402-22UF,4V,20%,X6S,CHA]
    1  PVCCIN_CPU0        A  @S9S_MB_2U_LIB.S9S_MB_2U(SCH_1):PVCCIN_CPU0
    2  GND                B  @S9S_MB_2U_LIB.S9S_MB_2U(SCH_1):GND

Q_CAP  I91  C984   [Q_CAP_C0402-22UF,4V,20%,X6S,CHA]
    1  PVCCIN_CPU0        A  @S9S_MB_2U_LIB.S9S_MB_2U(SCH_1):PVCCIN_CPU0
    2  GND                B  @S9S_MB_2U_LIB.S9S_MB_2U(SCH_1):GND

Q_CAP  I92  C985   [Q_CAP_C0402-22UF,4V,20%,X6S,CHA]
    1  PVCCIN_CPU0        A  @S9S_MB_2U_LIB.S9S_MB_2U(SCH_1):PVCCIN_CPU0
    2  GND                B  @S9S_MB_2U_LIB.S9S_MB_2U(SCH_1):GND

Q_CAP  I14  C986   [Q_CAP_C0402-22UF,4V,20%,X6S,CHA]
    1  PVCCIN_CPU0        A  @S9S_MB_2U_LIB.S9S_MB_2U(SCH_1):PVCCIN_CPU0
    2  GND                B  @S9S_MB_2U_LIB.S9S_MB_2U(SCH_1):GND

Q_CAP  I48  C987   [Q_CAP_C0402-22UF,4V,20%,X6S,CHA]
    1  PVCCIN_CPU0        A  @S9S_MB_2U_LIB.S9S_MB_2U(SCH_1):PVCCIN_CPU0
    2  GND                B  @S9S_MB_2U_LIB.S9S_MB_2U(SCH_1):GND

Q_CAP  I89  C988   [Q_CAP_C0402-22UF,4V,20%,X6S,CHA]
    1  PVCCIN_CPU0        A  @S9S_MB_2U_LIB.S9S_MB_2U(SCH_1):PVCCIN_CPU0
    2  GND                B  @S9S_MB_2U_LIB.S9S_MB_2U(SCH_1):GND

Q_CAP  I90  C989   [Q_CAP_C0402-22UF,4V,20%,X6S,CHA]
    1  PVCCIN_CPU0        A  @S9S_MB_2U_LIB.S9S_MB_2U(SCH_1):PVCCIN_CPU0
    2  GND                B  @S9S_MB_2U_LIB.S9S_MB_2U(SCH_1):GND

Q_CAP  I13  C990   [Q_CAP_C0402-22UF,4V,20%,X6S,CHA]
    1  PVCCIN_CPU0        A  @S9S_MB_2U_LIB.S9S_MB_2U(SCH_1):PVCCIN_CPU0
    2  GND                B  @S9S_MB_2U_LIB.S9S_MB_2U(SCH_1):GND

Q_CAP  I47  C991   [Q_CAP_C0402-22UF,4V,20%,X6S,CHA]
    1  PVCCIN_CPU0        A  @S9S_MB_2U_LIB.S9S_MB_2U(SCH_1):PVCCIN_CPU0
    2  GND                B  @S9S_MB_2U_LIB.S9S_MB_2U(SCH_1):GND

Q_CAP  I88  C992   [Q_CAP_C0402-22UF,4V,20%,X6S,CHA]
    1  PVCCIN_CPU0        A  @S9S_MB_2U_LIB.S9S_MB_2U(SCH_1):PVCCIN_CPU0
    2  GND                B  @S9S_MB_2U_LIB.S9S_MB_2U(SCH_1):GND

Q_CAP  I87  C993   [Q_CAP_C0402-22UF,4V,20%,X6S,CHA]
    1  PVCCIN_CPU0        A  @S9S_MB_2U_LIB.S9S_MB_2U(SCH_1):PVCCIN_CPU0
    2  GND                B  @S9S_MB_2U_LIB.S9S_MB_2U(SCH_1):GND

Q_CAP  I17  C994   [Q_CAP_C0402-22UF,4V,20%,X6S,CHA]
    1  PVCCIN_CPU0        A  @S9S_MB_2U_LIB.S9S_MB_2U(SCH_1):PVCCIN_CPU0
    2  GND                B  @S9S_MB_2U_LIB.S9S_MB_2U(SCH_1):GND

Q_CAP  I46  C995   [Q_CAP_C0402-22UF,4V,20%,X6S,CHA]
    1  PVCCIN_CPU0        A  @S9S_MB_2U_LIB.S9S_MB_2U(SCH_1):PVCCIN_CPU0
    2  GND                B  @S9S_MB_2U_LIB.S9S_MB_2U(SCH_1):GND

Q_CAP  I85  C996   [Q_CAP_C0402-22UF,4V,20%,X6S,CHA]
    1  PVCCIN_CPU0        A  @S9S_MB_2U_LIB.S9S_MB_2U(SCH_1):PVCCIN_CPU0
    2  GND                B  @S9S_MB_2U_LIB.S9S_MB_2U(SCH_1):GND

Q_CAP  I86  C997   [Q_CAP_C0402-22UF,4V,20%,X6S,CHA]
    1  PVCCIN_CPU0        A  @S9S_MB_2U_LIB.S9S_MB_2U(SCH_1):PVCCIN_CPU0
    2  GND                B  @S9S_MB_2U_LIB.S9S_MB_2U(SCH_1):GND

Q_CAP  I15  C998   [Q_CAP_C0402-22UF,4V,20%,X6S,CHA]
    1  PVCCIN_CPU0        A  @S9S_MB_2U_LIB.S9S_MB_2U(SCH_1):PVCCIN_CPU0
    2  GND                B  @S9S_MB_2U_LIB.S9S_MB_2U(SCH_1):GND

Q_CAP  I44  C999   [Q_CAP_C0402-22UF,4V,20%,X6S,CHA]
    1  PVCCIN_CPU0        A  @S9S_MB_2U_LIB.S9S_MB_2U(SCH_1):PVCCIN_CPU0
    2  GND                B  @S9S_MB_2U_LIB.S9S_MB_2U(SCH_1):GND

Q_CAP  I81  C1000  [Q_CAP_C0402-22UF,4V,20%,X6S,CHA]
    1  PVCCIN_CPU0        A  @S9S_MB_2U_LIB.S9S_MB_2U(SCH_1):PVCCIN_CPU0
    2  GND                B  @S9S_MB_2U_LIB.S9S_MB_2U(SCH_1):GND

Q_CAP  I82  C1001  [Q_CAP_C0402-22UF,4V,20%,X6S,CHA]
    1  PVCCIN_CPU0        A  @S9S_MB_2U_LIB.S9S_MB_2U(SCH_1):PVCCIN_CPU0
    2  GND                B  @S9S_MB_2U_LIB.S9S_MB_2U(SCH_1):GND

Q_CAP  I16  C1002  [Q_CAP_C0402-22UF,4V,20%,X6S,CHA]
    1  PVCCIN_CPU0        A  @S9S_MB_2U_LIB.S9S_MB_2U(SCH_1):PVCCIN_CPU0
    2  GND                B  @S9S_MB_2U_LIB.S9S_MB_2U(SCH_1):GND

Q_CAP  I42  C1003  [Q_CAP_C0402-22UF,4V,20%,X6S,CHA]
    1  PVCCIN_CPU0        A  @S9S_MB_2U_LIB.S9S_MB_2U(SCH_1):PVCCIN_CPU0
    2  GND                B  @S9S_MB_2U_LIB.S9S_MB_2U(SCH_1):GND

Q_CAP  I78  C1004  [Q_CAP_C0402-22UF,4V,20%,X6S,CHA]
    1  PVCCIN_CPU0        A  @S9S_MB_2U_LIB.S9S_MB_2U(SCH_1):PVCCIN_CPU0
    2  GND                B  @S9S_MB_2U_LIB.S9S_MB_2U(SCH_1):GND

Q_CAP  I80  C1005  [Q_CAP_C0402-22UF,4V,20%,X6S,CHA]
    1  PVCCIN_CPU0        A  @S9S_MB_2U_LIB.S9S_MB_2U(SCH_1):PVCCIN_CPU0
    2  GND                B  @S9S_MB_2U_LIB.S9S_MB_2U(SCH_1):GND

Q_CAP  I29  C1006  [Q_CAP_C0402-22UF,4V,20%,X6S,CHA]
    1  PVCCIN_CPU0        A  @S9S_MB_2U_LIB.S9S_MB_2U(SCH_1):PVCCIN_CPU0
    2  GND                B  @S9S_MB_2U_LIB.S9S_MB_2U(SCH_1):GND

Q_CAP  I41  C1007  [Q_CAP_C0402-22UF,4V,20%,X6S,CHA]
    1  PVCCIN_CPU0        A  @S9S_MB_2U_LIB.S9S_MB_2U(SCH_1):PVCCIN_CPU0
    2  GND                B  @S9S_MB_2U_LIB.S9S_MB_2U(SCH_1):GND

Q_CAP  I75  C1008  [Q_CAP_C0402-22UF,4V,20%,X6S,CHA]
    1  PVCCIN_CPU0        A  @S9S_MB_2U_LIB.S9S_MB_2U(SCH_1):PVCCIN_CPU0
    2  GND                B  @S9S_MB_2U_LIB.S9S_MB_2U(SCH_1):GND

Q_CAP  I77  C1009  [Q_CAP_C0402-22UF,4V,20%,X6S,CHA]
    1  PVCCIN_CPU0        A  @S9S_MB_2U_LIB.S9S_MB_2U(SCH_1):PVCCIN_CPU0
    2  GND                B  @S9S_MB_2U_LIB.S9S_MB_2U(SCH_1):GND

Q_CAP  I18  C1010  [Q_CAP_C0402-22UF,4V,20%,X6S,CHA]
    1  PVCCIN_CPU0        A  @S9S_MB_2U_LIB.S9S_MB_2U(SCH_1):PVCCIN_CPU0
    2  GND                B  @S9S_MB_2U_LIB.S9S_MB_2U(SCH_1):GND

Q_CAP  I40  C1011  [Q_CAP_C0402-22UF,4V,20%,X6S,CHA]
    1  PVCCIN_CPU0        A  @S9S_MB_2U_LIB.S9S_MB_2U(SCH_1):PVCCIN_CPU0
    2  GND                B  @S9S_MB_2U_LIB.S9S_MB_2U(SCH_1):GND

Q_CAP  I73  C1012  [Q_CAP_C0402-22UF,4V,20%,X6S,CHA]
    1  PVCCIN_CPU0        A  @S9S_MB_2U_LIB.S9S_MB_2U(SCH_1):PVCCIN_CPU0
    2  GND                B  @S9S_MB_2U_LIB.S9S_MB_2U(SCH_1):GND

Q_CAP  I74  C1013  [Q_CAP_C0402-22UF,4V,20%,X6S,CHA]
    1  PVCCIN_CPU0        A  @S9S_MB_2U_LIB.S9S_MB_2U(SCH_1):PVCCIN_CPU0
    2  GND                B  @S9S_MB_2U_LIB.S9S_MB_2U(SCH_1):GND

Q_CAP  I19  C1014  [Q_CAP_C0402-22UF,4V,20%,X6S,CHA]
    1  PVCCIN_CPU0        A  @S9S_MB_2U_LIB.S9S_MB_2U(SCH_1):PVCCIN_CPU0
    2  GND                B  @S9S_MB_2U_LIB.S9S_MB_2U(SCH_1):GND

Q_CAP  I39  C1015  [Q_CAP_C0402-22UF,4V,20%,X6S,CHA]
    1  PVCCIN_CPU0        A  @S9S_MB_2U_LIB.S9S_MB_2U(SCH_1):PVCCIN_CPU0
    2  GND                B  @S9S_MB_2U_LIB.S9S_MB_2U(SCH_1):GND

Q_CAP  I71  C1016  [Q_CAP_C0402-22UF,4V,20%,X6S,CHA]
    1  PVCCIN_CPU0        A  @S9S_MB_2U_LIB.S9S_MB_2U(SCH_1):PVCCIN_CPU0
    2  GND                B  @S9S_MB_2U_LIB.S9S_MB_2U(SCH_1):GND

Q_CAP  I72  C1017  [Q_CAP_C0402-22UF,4V,20%,X6S,CHA]
    1  PVCCIN_CPU0        A  @S9S_MB_2U_LIB.S9S_MB_2U(SCH_1):PVCCIN_CPU0
    2  GND                B  @S9S_MB_2U_LIB.S9S_MB_2U(SCH_1):GND

Q_CAP  I20  C1018  [Q_CAP_C0402-22UF,4V,20%,X6S,CHA]
    1  PVCCIN_CPU0        A  @S9S_MB_2U_LIB.S9S_MB_2U(SCH_1):PVCCIN_CPU0
    2  GND                B  @S9S_MB_2U_LIB.S9S_MB_2U(SCH_1):GND

Q_CAP  I38  C1019  [Q_CAP_C0402-22UF,4V,20%,X6S,CHA]
    1  PVCCIN_CPU0        A  @S9S_MB_2U_LIB.S9S_MB_2U(SCH_1):PVCCIN_CPU0
    2  GND                B  @S9S_MB_2U_LIB.S9S_MB_2U(SCH_1):GND

Q_CAP  I69  C1020  [Q_CAP_C0402-22UF,4V,20%,X6S,CHA]
    1  PVCCIN_CPU0        A  @S9S_MB_2U_LIB.S9S_MB_2U(SCH_1):PVCCIN_CPU0
    2  GND                B  @S9S_MB_2U_LIB.S9S_MB_2U(SCH_1):GND

Q_CAP  I70  C1021  [Q_CAP_C0402-22UF,4V,20%,X6S,CHA]
    1  PVCCIN_CPU0        A  @S9S_MB_2U_LIB.S9S_MB_2U(SCH_1):PVCCIN_CPU0
    2  GND                B  @S9S_MB_2U_LIB.S9S_MB_2U(SCH_1):GND

Q_CAP  I21  C1022  [Q_CAP_C0402-22UF,4V,20%,X6S,CHA]
    1  PVCCIN_CPU0        A  @S9S_MB_2U_LIB.S9S_MB_2U(SCH_1):PVCCIN_CPU0
    2  GND                B  @S9S_MB_2U_LIB.S9S_MB_2U(SCH_1):GND

Q_CAP  I37  C1023  [Q_CAP_C0402-22UF,4V,20%,X6S,CHA]
    1  PVCCIN_CPU0        A  @S9S_MB_2U_LIB.S9S_MB_2U(SCH_1):PVCCIN_CPU0
    2  GND                B  @S9S_MB_2U_LIB.S9S_MB_2U(SCH_1):GND

Q_CAP  I66  C1024  [Q_CAP_C0402-22UF,4V,20%,X6S,CHA]
    1  PVCCIN_CPU0        A  @S9S_MB_2U_LIB.S9S_MB_2U(SCH_1):PVCCIN_CPU0
    2  GND                B  @S9S_MB_2U_LIB.S9S_MB_2U(SCH_1):GND

Q_CAP  I68  C1025  [Q_CAP_C0402-22UF,4V,20%,X6S,CHA]
    1  PVCCIN_CPU0        A  @S9S_MB_2U_LIB.S9S_MB_2U(SCH_1):PVCCIN_CPU0
    2  GND                B  @S9S_MB_2U_LIB.S9S_MB_2U(SCH_1):GND

Q_CAP  I22  C1026  [Q_CAP_C0402-22UF,4V,20%,X6S,CHA]
    1  PVCCIN_CPU0        A  @S9S_MB_2U_LIB.S9S_MB_2U(SCH_1):PVCCIN_CPU0
    2  GND                B  @S9S_MB_2U_LIB.S9S_MB_2U(SCH_1):GND

Q_CAP  I36  C1027  [Q_CAP_C0402-22UF,4V,20%,X6S,CHA]
    1  PVCCIN_CPU0        A  @S9S_MB_2U_LIB.S9S_MB_2U(SCH_1):PVCCIN_CPU0
    2  GND                B  @S9S_MB_2U_LIB.S9S_MB_2U(SCH_1):GND

Q_CAP  I65  C1028  [Q_CAP_C0402-22UF,4V,20%,X6S,CHA]
    1  PVCCIN_CPU0        A  @S9S_MB_2U_LIB.S9S_MB_2U(SCH_1):PVCCIN_CPU0
    2  GND                B  @S9S_MB_2U_LIB.S9S_MB_2U(SCH_1):GND

Q_CAP  I67  C1029  [Q_CAP_C0402-22UF,4V,20%,X6S,CHA]
    1  PVCCIN_CPU0        A  @S9S_MB_2U_LIB.S9S_MB_2U(SCH_1):PVCCIN_CPU0
    2  GND                B  @S9S_MB_2U_LIB.S9S_MB_2U(SCH_1):GND

Q_CAP  I23  C1030  [Q_CAP_C0402-22UF,4V,20%,X6S,CHA]
    1  PVCCIN_CPU0        A  @S9S_MB_2U_LIB.S9S_MB_2U(SCH_1):PVCCIN_CPU0
    2  GND                B  @S9S_MB_2U_LIB.S9S_MB_2U(SCH_1):GND

Q_CAP  I35  C1031  [Q_CAP_C0402-22UF,4V,20%,X6S,CHA]
    1  PVCCIN_CPU0        A  @S9S_MB_2U_LIB.S9S_MB_2U(SCH_1):PVCCIN_CPU0
    2  GND                B  @S9S_MB_2U_LIB.S9S_MB_2U(SCH_1):GND

Q_CAP  I63  C1032  [Q_CAP_C0402-22UF,4V,20%,X6S,CHA]
    1  PVCCIN_CPU0        A  @S9S_MB_2U_LIB.S9S_MB_2U(SCH_1):PVCCIN_CPU0
    2  GND                B  @S9S_MB_2U_LIB.S9S_MB_2U(SCH_1):GND

Q_CAP  I64  C1033  [Q_CAP_C0402-22UF,4V,20%,X6S,CHA]
    1  PVCCIN_CPU0        A  @S9S_MB_2U_LIB.S9S_MB_2U(SCH_1):PVCCIN_CPU0
    2  GND                B  @S9S_MB_2U_LIB.S9S_MB_2U(SCH_1):GND

Q_CAP  I24  C1034  [Q_CAP_C0402-22UF,4V,20%,X6S,CHA]
    1  PVCCIN_CPU0        A  @S9S_MB_2U_LIB.S9S_MB_2U(SCH_1):PVCCIN_CPU0
    2  GND                B  @S9S_MB_2U_LIB.S9S_MB_2U(SCH_1):GND

Q_CAP  I33  C1035  [Q_CAP_C0402-22UF,4V,20%,X6S,CHA]
    1  PVCCIN_CPU0        A  @S9S_MB_2U_LIB.S9S_MB_2U(SCH_1):PVCCIN_CPU0
    2  GND                B  @S9S_MB_2U_LIB.S9S_MB_2U(SCH_1):GND

Q_CAP  I60  C1036  [Q_CAP_C0402-22UF,4V,20%,X6S,CHA]
    1  PVCCIN_CPU0        A  @S9S_MB_2U_LIB.S9S_MB_2U(SCH_1):PVCCIN_CPU0
    2  GND                B  @S9S_MB_2U_LIB.S9S_MB_2U(SCH_1):GND

Q_CAP  I61  C1037  [Q_CAP_C0402-22UF,4V,20%,X6S,CHA]
    1  PVCCIN_CPU0        A  @S9S_MB_2U_LIB.S9S_MB_2U(SCH_1):PVCCIN_CPU0
    2  GND                B  @S9S_MB_2U_LIB.S9S_MB_2U(SCH_1):GND

Q_CAP  I26  C1038  [Q_CAP_C0402-22UF,4V,20%,X6S,CHA]
    1  PVCCIN_CPU0        A  @S9S_MB_2U_LIB.S9S_MB_2U(SCH_1):PVCCIN_CPU0
    2  GND                B  @S9S_MB_2U_LIB.S9S_MB_2U(SCH_1):GND

Q_CAP  I32  C1039  [Q_CAP_C0402-22UF,4V,20%,X6S,CHA]
    1  PVCCIN_CPU0        A  @S9S_MB_2U_LIB.S9S_MB_2U(SCH_1):PVCCIN_CPU0
    2  GND                B  @S9S_MB_2U_LIB.S9S_MB_2U(SCH_1):GND

Q_CAP  I58  C1040  [Q_CAP_C0402-22UF,4V,20%,X6S,CHA]
    1  PVCCIN_CPU0        A  @S9S_MB_2U_LIB.S9S_MB_2U(SCH_1):PVCCIN_CPU0
    2  GND                B  @S9S_MB_2U_LIB.S9S_MB_2U(SCH_1):GND

Q_CAP  I59  C1041  [Q_CAP_C0402-22UF,4V,20%,X6S,CHA]
    1  PVCCIN_CPU0        A  @S9S_MB_2U_LIB.S9S_MB_2U(SCH_1):PVCCIN_CPU0
    2  GND                B  @S9S_MB_2U_LIB.S9S_MB_2U(SCH_1):GND

Q_CAP  I79  C1042  [Q_CAP_C0402-100NF,50V,10%,X7R,A]
    1  P5V_AUX            A  @S9S_MB_2U_LIB.S9S_MB_2U(SCH_1):P5V_AUX
    2  GND                B  @S9S_MB_2U_LIB.S9S_MB_2U(SCH_1):GND

Q_CAP  I30  C1043  [Q_CAP_C0402-22UF,4V,20%,X6S,CHA]
    1  PVCCIN_CPU0        A  @S9S_MB_2U_LIB.S9S_MB_2U(SCH_1):PVCCIN_CPU0
    2  GND                B  @S9S_MB_2U_LIB.S9S_MB_2U(SCH_1):GND

Q_CAP  I54  C1044  [Q_CAP_C0402-22UF,4V,20%,X6S,CHA]
    1  PVCCIN_CPU0        A  @S9S_MB_2U_LIB.S9S_MB_2U(SCH_1):PVCCIN_CPU0
    2  GND                B  @S9S_MB_2U_LIB.S9S_MB_2U(SCH_1):GND

Q_CAP  I56  C1045  [Q_CAP_C0402-22UF,4V,20%,X6S,CHA]
    1  PVCCIN_CPU0        A  @S9S_MB_2U_LIB.S9S_MB_2U(SCH_1):PVCCIN_CPU0
    2  GND                B  @S9S_MB_2U_LIB.S9S_MB_2U(SCH_1):GND

Q_CAP  I40  C1046  [Q_CAP_C0805-22UF,16V,20%,X6S,CA]
    1  P3V3_AUX           A  @S9S_MB_2U_LIB.S9S_MB_2U(SCH_1):P3V3_AUX
    2  GND                B  @S9S_MB_2U_LIB.S9S_MB_2U(SCH_1):GND

Q_CAP  I37  C1047  [Q_CAP_C0805-22UF,16V,20%,X6S,CA]
    1  P12V_REAR_CPU      A  @S9S_MB_2U_LIB.S9S_MB_2U(SCH_1):P12V_REAR_CPU
    2  GND                B  @S9S_MB_2U_LIB.S9S_MB_2U(SCH_1):GND

Q_CAP  I36  C1048  [Q_CAP_0402-0.1UF,25V,10%,X7R,CA]
    1  P12V_REAR_CPU      A  @S9S_MB_2U_LIB.S9S_MB_2U(SCH_1):P12V_REAR_CPU
    2  GND                B  @S9S_MB_2U_LIB.S9S_MB_2U(SCH_1):GND

Q_CAP  I35  C1049  [Q_CAP_0402-0.1UF,25V,10%,X7R,CA]
    1  P12V_REAR_CPU      A  @S9S_MB_2U_LIB.S9S_MB_2U(SCH_1):P12V_REAR_CPU
    2  GND                B  @S9S_MB_2U_LIB.S9S_MB_2U(SCH_1):GND

Q_CAP  I34  C1050  [Q_CAP_0402-0.1UF,25V,10%,X7R,CA]
    1  P12V_REAR_CPU      A  @S9S_MB_2U_LIB.S9S_MB_2U(SCH_1):P12V_REAR_CPU
    2  GND                B  @S9S_MB_2U_LIB.S9S_MB_2U(SCH_1):GND

Q_CAP  I33  C1051  [Q_CAP_0402-0.1UF,25V,10%,X7R,CA]
    1  P12V_REAR_CPU      A  @S9S_MB_2U_LIB.S9S_MB_2U(SCH_1):P12V_REAR_CPU
    2  GND                B  @S9S_MB_2U_LIB.S9S_MB_2U(SCH_1):GND

Q_CAP  I31  C1052  [Q_CAP_0402-0.1UF,25V,10%,X7R,CA]
    1  P12V_REAR_CPU      A  @S9S_MB_2U_LIB.S9S_MB_2U(SCH_1):P12V_REAR_CPU
    2  GND                B  @S9S_MB_2U_LIB.S9S_MB_2U(SCH_1):GND

Q_CAP  I29  C1053  [Q_CAP_C0805-22UF,16V,20%,X6S,CA]
    1  P3V3_AUX           A  @S9S_MB_2U_LIB.S9S_MB_2U(SCH_1):P3V3_AUX
    2  GND                B  @S9S_MB_2U_LIB.S9S_MB_2U(SCH_1):GND

Q_CAP  I30  C1054  [Q_CAP_C0805-22UF,16V,20%,X6S,CA]
    1  P3V3_AUX           A  @S9S_MB_2U_LIB.S9S_MB_2U(SCH_1):P3V3_AUX
    2  GND                B  @S9S_MB_2U_LIB.S9S_MB_2U(SCH_1):GND

Q_CAP  I60  C1055  [Q_CAP_C0805-22UF,16V,20%,X6S,CA]
    1  P12V_REAR_CPU      A  @S9S_MB_2U_LIB.S9S_MB_2U(SCH_1):P12V_REAR_CPU
    2  GND                B  @S9S_MB_2U_LIB.S9S_MB_2U(SCH_1):GND

Q_CAP  I59  C1056  [Q_CAP_0402-0.1UF,25V,10%,X7R,CA]
    1  P12V_REAR_CPU      A  @S9S_MB_2U_LIB.S9S_MB_2U(SCH_1):P12V_REAR_CPU
    2  GND                B  @S9S_MB_2U_LIB.S9S_MB_2U(SCH_1):GND

Q_CAP  I58  C1057  [Q_CAP_0402-0.1UF,25V,10%,X7R,CA]
    1  P12V_REAR_CPU      A  @S9S_MB_2U_LIB.S9S_MB_2U(SCH_1):P12V_REAR_CPU
    2  GND                B  @S9S_MB_2U_LIB.S9S_MB_2U(SCH_1):GND

Q_CAP  I57  C1058  [Q_CAP_0402-0.1UF,25V,10%,X7R,CA]
    1  P12V_REAR_CPU      A  @S9S_MB_2U_LIB.S9S_MB_2U(SCH_1):P12V_REAR_CPU
    2  GND                B  @S9S_MB_2U_LIB.S9S_MB_2U(SCH_1):GND

Q_CAP  I56  C1059  [Q_CAP_0402-0.1UF,25V,10%,X7R,CA]
    1  P12V_REAR_CPU      A  @S9S_MB_2U_LIB.S9S_MB_2U(SCH_1):P12V_REAR_CPU
    2  GND                B  @S9S_MB_2U_LIB.S9S_MB_2U(SCH_1):GND

Q_CAP  I54  C1060  [Q_CAP_0402-0.1UF,25V,10%,X7R,CA]
    1  P12V_REAR_CPU      A  @S9S_MB_2U_LIB.S9S_MB_2U(SCH_1):P12V_REAR_CPU
    2  GND                B  @S9S_MB_2U_LIB.S9S_MB_2U(SCH_1):GND

Q_CAP  I53  C1061  [Q_CAP_C0805-22UF,16V,20%,X6S,CA]
    1  P3V3_AUX           A  @S9S_MB_2U_LIB.S9S_MB_2U(SCH_1):P3V3_AUX
    2  GND                B  @S9S_MB_2U_LIB.S9S_MB_2U(SCH_1):GND

Q_CAP  I200  C1063  [Q_CAP_C0805-22UF,16V,20%,X6S,CA]
    1  P12V_REAR_CPU      A  @S9S_MB_2U_LIB.S9S_MB_2U(SCH_1):P12V_REAR_CPU
    2  GND                B  @S9S_MB_2U_LIB.S9S_MB_2U(SCH_1):GND

Q_CAP  I198  C1064  [Q_CAP_0402-0.1UF,25V,10%,X7R,CA]
    1  P12V_REAR_CPU      A  @S9S_MB_2U_LIB.S9S_MB_2U(SCH_1):P12V_REAR_CPU
    2  GND                B  @S9S_MB_2U_LIB.S9S_MB_2U(SCH_1):GND

Q_CAP  I197  C1065  [Q_CAP_0402-0.1UF,25V,10%,X7R,CA]
    1  P12V_REAR_CPU      A  @S9S_MB_2U_LIB.S9S_MB_2U(SCH_1):P12V_REAR_CPU
    2  GND                B  @S9S_MB_2U_LIB.S9S_MB_2U(SCH_1):GND

Q_CAP  I196  C1066  [Q_CAP_0402-0.1UF,25V,10%,X7R,CA]
    1  P12V_REAR_CPU      A  @S9S_MB_2U_LIB.S9S_MB_2U(SCH_1):P12V_REAR_CPU
    2  GND                B  @S9S_MB_2U_LIB.S9S_MB_2U(SCH_1):GND

Q_CAP  I195  C1067  [Q_CAP_0402-0.1UF,25V,10%,X7R,CA]
    1  P12V_REAR_CPU      A  @S9S_MB_2U_LIB.S9S_MB_2U(SCH_1):P12V_REAR_CPU
    2  GND                B  @S9S_MB_2U_LIB.S9S_MB_2U(SCH_1):GND

Q_CAP  I193  C1068  [Q_CAP_0402-0.1UF,25V,10%,X7R,CA]
    1  P12V_REAR_CPU      A  @S9S_MB_2U_LIB.S9S_MB_2U(SCH_1):P12V_REAR_CPU
    2  GND                B  @S9S_MB_2U_LIB.S9S_MB_2U(SCH_1):GND

Q_CAP  I191  C1069  [Q_CAP_C0805-22UF,16V,20%,X6S,CA]
    1  P3V3_AUX           A  @S9S_MB_2U_LIB.S9S_MB_2U(SCH_1):P3V3_AUX
    2  GND                B  @S9S_MB_2U_LIB.S9S_MB_2U(SCH_1):GND

Q_CAP  I88  C1078  [Q_CAP_C0603-22UF,6.3V,20%,X6S,A]
    1  P3V3               A  @S9S_MB_2U_LIB.S9S_MB_2U(SCH_1):P3V3
    2  GND                B  @S9S_MB_2U_LIB.S9S_MB_2U(SCH_1):GND

Q_CAP  I90  C1080  [Q_CAP_C0603-22UF,6.3V,20%,X6S,A]
    1  P3V3               A  @S9S_MB_2U_LIB.S9S_MB_2U(SCH_1):P3V3
    2  GND                B  @S9S_MB_2U_LIB.S9S_MB_2U(SCH_1):GND

Q_CAP  I96  C1082  [Q_CAP_C0603-22UF,6.3V,20%,X6S,A]
    1  P3V3               A  @S9S_MB_2U_LIB.S9S_MB_2U(SCH_1):P3V3
    2  GND                B  @S9S_MB_2U_LIB.S9S_MB_2U(SCH_1):GND

Q_CAP  I97  C1084  [Q_CAP_0402-0.1UF,25V,10%,X7R,CA]
    1  P3V3               A  @S9S_MB_2U_LIB.S9S_MB_2U(SCH_1):P3V3
    2  GND                B  @S9S_MB_2U_LIB.S9S_MB_2U(SCH_1):GND

Q_CAP  I98  C1086  [Q_CAP_0402-0.1UF,25V,10%,X7R,CA]
    1  P3V3               A  @S9S_MB_2U_LIB.S9S_MB_2U(SCH_1):P3V3
    2  GND                B  @S9S_MB_2U_LIB.S9S_MB_2U(SCH_1):GND

Q_CAP  I100  C1088  [Q_CAP_0402-0.1UF,25V,10%,X7R,CA]
    1  P3V3               A  @S9S_MB_2U_LIB.S9S_MB_2U(SCH_1):P3V3
    2  GND                B  @S9S_MB_2U_LIB.S9S_MB_2U(SCH_1):GND

Q_CAP_DIFFBUS  I199  C1096  [Q_CAP_DIFFBUS_C0201-DIFF BUS_0A]
    1  P3E_PCH_M2_TX_DP<4>      1  @S9S_MB_2U_LIB.S9S_MB_2U(SCH_1):P3E_PCH_M2_TX_DP<4>
    2  P3E_PCH_M2_TX_C_DP<4>      2  @S9S_MB_2U_LIB.S9S_MB_2U(SCH_1):P3E_PCH_M2_TX_C_DP<4>

Q_CAP_DIFFBUS  I198  C1097  [Q_CAP_DIFFBUS_C0201-DIFF BUS_0A]
    1  P3E_PCH_M2_TX_DN<4>      1  @S9S_MB_2U_LIB.S9S_MB_2U(SCH_1):P3E_PCH_M2_TX_DN<4>
    2  P3E_PCH_M2_TX_C_DN<4>      2  @S9S_MB_2U_LIB.S9S_MB_2U(SCH_1):P3E_PCH_M2_TX_C_DN<4>

Q_CAP_DIFFBUS  I162  C1098  [Q_CAP_DIFFBUS_C0201-DIFF BUS_0A]
    1  P3E_PCH_M2_TX_DP<3>      1  @S9S_MB_2U_LIB.S9S_MB_2U(SCH_1):P3E_PCH_M2_TX_DP<3>
    2  P3E_PCH_M2_TX_C_DP<3>      2  @S9S_MB_2U_LIB.S9S_MB_2U(SCH_1):P3E_PCH_M2_TX_C_DP<3>

Q_CAP_DIFFBUS  I163  C1099  [Q_CAP_DIFFBUS_C0201-DIFF BUS_0A]
    1  P3E_PCH_M2_TX_DN<3>      1  @S9S_MB_2U_LIB.S9S_MB_2U(SCH_1):P3E_PCH_M2_TX_DN<3>
    2  P3E_PCH_M2_TX_C_DN<3>      2  @S9S_MB_2U_LIB.S9S_MB_2U(SCH_1):P3E_PCH_M2_TX_C_DN<3>

Q_CAP_DIFFBUS  I165  C1100  [Q_CAP_DIFFBUS_C0201-DIFF BUS_0A]
    1  P3E_PCH_M2_TX_DP<2>      1  @S9S_MB_2U_LIB.S9S_MB_2U(SCH_1):P3E_PCH_M2_TX_DP<2>
    2  P3E_PCH_M2_TX_C_DP<2>      2  @S9S_MB_2U_LIB.S9S_MB_2U(SCH_1):P3E_PCH_M2_TX_C_DP<2>

Q_CAP_DIFFBUS  I164  C1101  [Q_CAP_DIFFBUS_C0201-DIFF BUS_0A]
    1  P3E_PCH_M2_TX_DN<2>      1  @S9S_MB_2U_LIB.S9S_MB_2U(SCH_1):P3E_PCH_M2_TX_DN<2>
    2  P3E_PCH_M2_TX_C_DN<2>      2  @S9S_MB_2U_LIB.S9S_MB_2U(SCH_1):P3E_PCH_M2_TX_C_DN<2>

Q_CAP_DIFFBUS  I168  C1102  [Q_CAP_DIFFBUS_C0201-DIFF BUS_0A]
    1  P3E_PCH_M2_TX_DP<1>      1  @S9S_MB_2U_LIB.S9S_MB_2U(SCH_1):P3E_PCH_M2_TX_DP<1>
    2  P3E_PCH_M2_TX_C_DP<1>      2  @S9S_MB_2U_LIB.S9S_MB_2U(SCH_1):P3E_PCH_M2_TX_C_DP<1>

Q_CAP_DIFFBUS  I166  C1103  [Q_CAP_DIFFBUS_C0201-DIFF BUS_0A]
    1  P3E_PCH_M2_TX_DN<1>      1  @S9S_MB_2U_LIB.S9S_MB_2U(SCH_1):P3E_PCH_M2_TX_DN<1>
    2  P3E_PCH_M2_TX_C_DN<1>      2  @S9S_MB_2U_LIB.S9S_MB_2U(SCH_1):P3E_PCH_M2_TX_C_DN<1>

Q_CAP_DIFFBUS  I167  C1104  [Q_CAP_DIFFBUS_C0201-DIFF BUS_0A]
    1  P3E_PCH_M2_TX_DP<0>      1  @S9S_MB_2U_LIB.S9S_MB_2U(SCH_1):P3E_PCH_M2_TX_DP<0>
    2  P3E_PCH_M2_TX_C_DP<0>      2  @S9S_MB_2U_LIB.S9S_MB_2U(SCH_1):P3E_PCH_M2_TX_C_DP<0>

Q_CAP_DIFFBUS  I169  C1105  [Q_CAP_DIFFBUS_C0201-DIFF BUS_0A]
    1  P3E_PCH_M2_TX_DN<0>      1  @S9S_MB_2U_LIB.S9S_MB_2U(SCH_1):P3E_PCH_M2_TX_DN<0>
    2  P3E_PCH_M2_TX_C_DN<0>      2  @S9S_MB_2U_LIB.S9S_MB_2U(SCH_1):P3E_PCH_M2_TX_C_DN<0>

Q_CAP  I248  C1107  [Q_CAP_0402-0.1UF,25V,10%,X7R,CA]
    1  P3V3_AUX           A  @S9S_MB_2U_LIB.S9S_MB_2U(SCH_1):P3V3_AUX
    2  GND                B  @S9S_MB_2U_LIB.S9S_MB_2U(SCH_1):GND

Q_CAP  I251  C1108  [Q_CAP_0402-0.1UF,25V,10%,X7R,CA]
    1  P3V3_AUX           A  @S9S_MB_2U_LIB.S9S_MB_2U(SCH_1):P3V3_AUX
    2  GND                B  @S9S_MB_2U_LIB.S9S_MB_2U(SCH_1):GND

Q_CAP  I240  C1110  [Q_CAP_0402-0.1UF,25V,10%,X7R,CA]
    1  P3V3_AUX           A  @S9S_MB_2U_LIB.S9S_MB_2U(SCH_1):P3V3_AUX
    2  GND                B  @S9S_MB_2U_LIB.S9S_MB_2U(SCH_1):GND

Q_CAP  I244  C1111  [Q_CAP_0402-0.1UF,25V,10%,X7R,CA]
    1  P3V3_AUX           A  @S9S_MB_2U_LIB.S9S_MB_2U(SCH_1):P3V3_AUX
    2  GND                B  @S9S_MB_2U_LIB.S9S_MB_2U(SCH_1):GND

Q_CAP  I239  C1113  [Q_CAP_0402-0.1UF,25V,10%,X7R,CA]
    1  P3V3_AUX           A  @S9S_MB_2U_LIB.S9S_MB_2U(SCH_1):P3V3_AUX
    2  GND                B  @S9S_MB_2U_LIB.S9S_MB_2U(SCH_1):GND

Q_CAP  I243  C1114  [Q_CAP_0402-0.1UF,25V,10%,X7R,CA]
    1  P3V3_AUX           A  @S9S_MB_2U_LIB.S9S_MB_2U(SCH_1):P3V3_AUX
    2  GND                B  @S9S_MB_2U_LIB.S9S_MB_2U(SCH_1):GND

Q_CAP  I227  C1115  [Q_CAP_C0402-2.2UF,6.3V,20%,EMPA]
    1  PVCCA_AUX_PLD      A  @S9S_MB_2U_LIB.S9S_MB_2U(SCH_1):PVCCA_AUX_PLD
    2  GND                B  @S9S_MB_2U_LIB.S9S_MB_2U(SCH_1):GND

Q_CAP  I236  C1118  [Q_CAP_0402-0.1UF,25V,10%,X7R,CA]
    1  P3V3_AUX           A  @S9S_MB_2U_LIB.S9S_MB_2U(SCH_1):P3V3_AUX
    2  GND                B  @S9S_MB_2U_LIB.S9S_MB_2U(SCH_1):GND

Q_CAP  I242  C1119  [Q_CAP_0402-0.1UF,25V,10%,X7R,CA]
    1  P3V3_AUX           A  @S9S_MB_2U_LIB.S9S_MB_2U(SCH_1):P3V3_AUX
    2  GND                B  @S9S_MB_2U_LIB.S9S_MB_2U(SCH_1):GND

Q_CAP  I265  C1120  [Q_CAP_0402-0.1UF,25V,10%,X7R,CA]
    1  PVCCIO_PLDIO2      A  @S9S_MB_2U_LIB.S9S_MB_2U(SCH_1):PVCCIO_PLDIO2
    2  GND                B  @S9S_MB_2U_LIB.S9S_MB_2U(SCH_1):GND

Q_CAP  I235  C1122  [Q_CAP_0402-0.1UF,25V,10%,X7R,CA]
    1  P3V3_AUX           A  @S9S_MB_2U_LIB.S9S_MB_2U(SCH_1):P3V3_AUX
    2  GND                B  @S9S_MB_2U_LIB.S9S_MB_2U(SCH_1):GND

Q_CAP  I241  C1123  [Q_CAP_0402-0.1UF,25V,10%,X7R,CA]
    1  P3V3_AUX           A  @S9S_MB_2U_LIB.S9S_MB_2U(SCH_1):P3V3_AUX
    2  GND                B  @S9S_MB_2U_LIB.S9S_MB_2U(SCH_1):GND

Q_CAP  I200  C1124  [Q_CAP_0402-0.1UF,25V,10%,EMPTYA]
    1  PVCCA_AUX_PLD      A  @S9S_MB_2U_LIB.S9S_MB_2U(SCH_1):PVCCA_AUX_PLD
    2  GND                B  @S9S_MB_2U_LIB.S9S_MB_2U(SCH_1):GND

Q_CAP  I222  C1127  [Q_CAP_0402-0.1UF,25V,10%,X7R,CA]
    1  P3V3_AUX           A  @S9S_MB_2U_LIB.S9S_MB_2U(SCH_1):P3V3_AUX
    2  GND                B  @S9S_MB_2U_LIB.S9S_MB_2U(SCH_1):GND

Q_CAP  I226  C1128  [Q_CAP_0402-0.1UF,25V,10%,X7R,CA]
    1  P3V3_AUX           A  @S9S_MB_2U_LIB.S9S_MB_2U(SCH_1):P3V3_AUX
    2  GND                B  @S9S_MB_2U_LIB.S9S_MB_2U(SCH_1):GND

Q_CAP  I263  C1129  [Q_CAP_0402-0.1UF,25V,10%,X7R,CA]
    1  PVCCIO_PLDIO2      A  @S9S_MB_2U_LIB.S9S_MB_2U(SCH_1):PVCCIO_PLDIO2
    2  GND                B  @S9S_MB_2U_LIB.S9S_MB_2U(SCH_1):GND

Q_CAP  I199  C1130  [Q_CAP_0402-0.1UF,25V,10%,EMPTYA]
    1  PVCCA_AUX_PLD      A  @S9S_MB_2U_LIB.S9S_MB_2U(SCH_1):PVCCA_AUX_PLD
    2  GND                B  @S9S_MB_2U_LIB.S9S_MB_2U(SCH_1):GND

Q_CAP  I221  C1133  [Q_CAP_0402-0.1UF,25V,10%,X7R,CA]
    1  P3V3_AUX           A  @S9S_MB_2U_LIB.S9S_MB_2U(SCH_1):P3V3_AUX
    2  GND                B  @S9S_MB_2U_LIB.S9S_MB_2U(SCH_1):GND

Q_CAP  I225  C1134  [Q_CAP_0402-0.1UF,25V,10%,X7R,CA]
    1  P3V3_AUX           A  @S9S_MB_2U_LIB.S9S_MB_2U(SCH_1):P3V3_AUX
    2  GND                B  @S9S_MB_2U_LIB.S9S_MB_2U(SCH_1):GND

Q_CAP  I262  C1135  [Q_CAP_0402-0.1UF,25V,10%,X7R,CA]
    1  PVCCIO_PLDIO2      A  @S9S_MB_2U_LIB.S9S_MB_2U(SCH_1):PVCCIO_PLDIO2
    2  GND                B  @S9S_MB_2U_LIB.S9S_MB_2U(SCH_1):GND

Q_CAP  I198  C1136  [Q_CAP_0402-0.1UF,25V,10%,EMPTYA]
    1  PVCCA_AUX_PLD      A  @S9S_MB_2U_LIB.S9S_MB_2U(SCH_1):PVCCA_AUX_PLD
    2  GND                B  @S9S_MB_2U_LIB.S9S_MB_2U(SCH_1):GND

Q_CAP  I218  C1138  [Q_CAP_0402-0.1UF,25V,10%,X7R,CA]
    1  P3V3_AUX           A  @S9S_MB_2U_LIB.S9S_MB_2U(SCH_1):P3V3_AUX
    2  GND                B  @S9S_MB_2U_LIB.S9S_MB_2U(SCH_1):GND

Q_CAP  I224  C1139  [Q_CAP_0402-0.1UF,25V,10%,X7R,CA]
    1  P3V3_AUX           A  @S9S_MB_2U_LIB.S9S_MB_2U(SCH_1):P3V3_AUX
    2  GND                B  @S9S_MB_2U_LIB.S9S_MB_2U(SCH_1):GND

Q_CAP  I197  C1140  [Q_CAP_0402-0.1UF,25V,10%,EMPTYA]
    1  PVCCA_AUX_PLD      A  @S9S_MB_2U_LIB.S9S_MB_2U(SCH_1):PVCCA_AUX_PLD
    2  GND                B  @S9S_MB_2U_LIB.S9S_MB_2U(SCH_1):GND

Q_CAP  I217  C1142  [Q_CAP_0402-0.1UF,25V,10%,X7R,CA]
    1  P3V3_AUX           A  @S9S_MB_2U_LIB.S9S_MB_2U(SCH_1):P3V3_AUX
    2  GND                B  @S9S_MB_2U_LIB.S9S_MB_2U(SCH_1):GND

Q_CAP  I223  C1143  [Q_CAP_0402-0.1UF,25V,10%,X7R,CA]
    1  P3V3_AUX           A  @S9S_MB_2U_LIB.S9S_MB_2U(SCH_1):P3V3_AUX
    2  GND                B  @S9S_MB_2U_LIB.S9S_MB_2U(SCH_1):GND

Q_CAP  I195  C1144  [Q_CAP_0402-0.1UF,25V,10%,EMPTYA]
    1  PVCCA_AUX_PLD      A  @S9S_MB_2U_LIB.S9S_MB_2U(SCH_1):PVCCA_AUX_PLD
    2  GND                B  @S9S_MB_2U_LIB.S9S_MB_2U(SCH_1):GND

Q_CAP  I210  C1146  [Q_CAP_0402-0.1UF,25V,10%,X7R,CA]
    1  P3V3_AUX           A  @S9S_MB_2U_LIB.S9S_MB_2U(SCH_1):P3V3_AUX
    2  GND                B  @S9S_MB_2U_LIB.S9S_MB_2U(SCH_1):GND

Q_CAP  I214  C1147  [Q_CAP_0402-0.1UF,25V,10%,X7R,CA]
    1  P3V3_AUX           A  @S9S_MB_2U_LIB.S9S_MB_2U(SCH_1):P3V3_AUX
    2  GND                B  @S9S_MB_2U_LIB.S9S_MB_2U(SCH_1):GND

Q_CAP  I194  C1148  [Q_CAP_0402-0.1UF,25V,10%,EMPTYA]
    1  PVCCA_AUX_PLD      A  @S9S_MB_2U_LIB.S9S_MB_2U(SCH_1):PVCCA_AUX_PLD
    2  GND                B  @S9S_MB_2U_LIB.S9S_MB_2U(SCH_1):GND

Q_CAP  I209  C1150  [Q_CAP_0402-0.1UF,25V,10%,X7R,CA]
    1  P3V3_AUX           A  @S9S_MB_2U_LIB.S9S_MB_2U(SCH_1):P3V3_AUX
    2  GND                B  @S9S_MB_2U_LIB.S9S_MB_2U(SCH_1):GND

Q_CAP  I213  C1151  [Q_CAP_0402-0.1UF,25V,10%,X7R,CA]
    1  P3V3_AUX           A  @S9S_MB_2U_LIB.S9S_MB_2U(SCH_1):P3V3_AUX
    2  GND                B  @S9S_MB_2U_LIB.S9S_MB_2U(SCH_1):GND

Q_CAP  I206  C1152  [Q_CAP_0402-0.1UF,25V,10%,X7R,CA]
    1  P3V3_AUX           A  @S9S_MB_2U_LIB.S9S_MB_2U(SCH_1):P3V3_AUX
    2  GND                B  @S9S_MB_2U_LIB.S9S_MB_2U(SCH_1):GND

Q_CAP  I212  C1153  [Q_CAP_0402-0.1UF,25V,10%,X7R,CA]
    1  P3V3_AUX           A  @S9S_MB_2U_LIB.S9S_MB_2U(SCH_1):P3V3_AUX
    2  GND                B  @S9S_MB_2U_LIB.S9S_MB_2U(SCH_1):GND

Q_CAP  I205  C1154  [Q_CAP_0402-0.1UF,25V,10%,X7R,CA]
    1  P3V3_AUX           A  @S9S_MB_2U_LIB.S9S_MB_2U(SCH_1):P3V3_AUX
    2  GND                B  @S9S_MB_2U_LIB.S9S_MB_2U(SCH_1):GND

Q_CAP  I211  C1155  [Q_CAP_0402-0.1UF,25V,10%,X7R,CA]
    1  P3V3_AUX           A  @S9S_MB_2U_LIB.S9S_MB_2U(SCH_1):P3V3_AUX
    2  GND                B  @S9S_MB_2U_LIB.S9S_MB_2U(SCH_1):GND

Q_CAP  I184  C1156  [Q_CAP_0402-0.1UF,25V,10%,X7R,CA]
    1  P3V3_AUX           A  @S9S_MB_2U_LIB.S9S_MB_2U(SCH_1):P3V3_AUX
    2  GND                B  @S9S_MB_2U_LIB.S9S_MB_2U(SCH_1):GND

Q_CAP  I187  C1157  [Q_CAP_0402-0.1UF,25V,10%,X7R,CA]
    1  P3V3_AUX           A  @S9S_MB_2U_LIB.S9S_MB_2U(SCH_1):P3V3_AUX
    2  GND                B  @S9S_MB_2U_LIB.S9S_MB_2U(SCH_1):GND

Q_CAP  I191  C1158  [Q_CAP_0402-0.1UF,25V,10%,X7R,CA]
    1  P3V3_AUX           A  @S9S_MB_2U_LIB.S9S_MB_2U(SCH_1):P3V3_AUX
    2  GND                B  @S9S_MB_2U_LIB.S9S_MB_2U(SCH_1):GND

Q_CAP  I183  C1159  [Q_CAP_0402-0.1UF,25V,10%,X7R,CA]
    1  P3V3_AUX           A  @S9S_MB_2U_LIB.S9S_MB_2U(SCH_1):P3V3_AUX
    2  GND                B  @S9S_MB_2U_LIB.S9S_MB_2U(SCH_1):GND

Q_CAP  I256  C1160  [Q_CAP_0402-0.1UF,25V,10%,X7R,CA]
    1  PVCCIO_PLDIO5      A  @S9S_MB_2U_LIB.S9S_MB_2U(SCH_1):PVCCIO_PLDIO5
    2  GND                B  @S9S_MB_2U_LIB.S9S_MB_2U(SCH_1):GND

Q_CAP  I186  C1161  [Q_CAP_0402-0.1UF,25V,10%,X7R,CA]
    1  P3V3_AUX           A  @S9S_MB_2U_LIB.S9S_MB_2U(SCH_1):P3V3_AUX
    2  GND                B  @S9S_MB_2U_LIB.S9S_MB_2U(SCH_1):GND

Q_CAP  I190  C1162  [Q_CAP_0402-0.1UF,25V,10%,X7R,CA]
    1  P3V3_AUX           A  @S9S_MB_2U_LIB.S9S_MB_2U(SCH_1):P3V3_AUX
    2  GND                B  @S9S_MB_2U_LIB.S9S_MB_2U(SCH_1):GND

Q_CAP  I180  C1163  [Q_CAP_0402-0.1UF,25V,10%,X7R,CA]
    1  P3V3_AUX           A  @S9S_MB_2U_LIB.S9S_MB_2U(SCH_1):P3V3_AUX
    2  GND                B  @S9S_MB_2U_LIB.S9S_MB_2U(SCH_1):GND

Q_CAP  I182  C1164  [Q_CAP_0402-0.1UF,25V,10%,X7R,CA]
    1  P3V3_AUX           A  @S9S_MB_2U_LIB.S9S_MB_2U(SCH_1):P3V3_AUX
    2  GND                B  @S9S_MB_2U_LIB.S9S_MB_2U(SCH_1):GND

Q_CAP  I189  C1165  [Q_CAP_0402-0.1UF,25V,10%,X7R,CA]
    1  P3V3_AUX           A  @S9S_MB_2U_LIB.S9S_MB_2U(SCH_1):P3V3_AUX
    2  GND                B  @S9S_MB_2U_LIB.S9S_MB_2U(SCH_1):GND

Q_CAP  I255  C1166  [Q_CAP_0402-0.1UF,25V,10%,X7R,CA]
    1  PVCCIO_PLDIO5      A  @S9S_MB_2U_LIB.S9S_MB_2U(SCH_1):PVCCIO_PLDIO5
    2  GND                B  @S9S_MB_2U_LIB.S9S_MB_2U(SCH_1):GND

Q_CAP  I181  C1167  [Q_CAP_0402-0.1UF,25V,10%,X7R,CA]
    1  P3V3_AUX           A  @S9S_MB_2U_LIB.S9S_MB_2U(SCH_1):P3V3_AUX
    2  GND                B  @S9S_MB_2U_LIB.S9S_MB_2U(SCH_1):GND

Q_CAP  I188  C1168  [Q_CAP_0402-0.1UF,25V,10%,X7R,CA]
    1  P3V3_AUX           A  @S9S_MB_2U_LIB.S9S_MB_2U(SCH_1):P3V3_AUX
    2  GND                B  @S9S_MB_2U_LIB.S9S_MB_2U(SCH_1):GND

Q_CAP  I254  C1169  [Q_CAP_0402-0.1UF,25V,10%,X7R,CA]
    1  PVCCIO_PLDIO5      A  @S9S_MB_2U_LIB.S9S_MB_2U(SCH_1):PVCCIO_PLDIO5
    2  GND                B  @S9S_MB_2U_LIB.S9S_MB_2U(SCH_1):GND

Q_CAP  I80  C1170  [Q_CAP_C0805-10UF,16V,10%,X6S,CA]
    1  P5V_AUX            A  @S9S_MB_2U_LIB.S9S_MB_2U(SCH_1):P5V_AUX
    2  GND                B  @S9S_MB_2U_LIB.S9S_MB_2U(SCH_1):GND

Q_CAP  I81  C1171  [Q_CAP_C0805-10UF,16V,10%,EMPTYA]
    1  P5V_AUX            A  @S9S_MB_2U_LIB.S9S_MB_2U(SCH_1):P5V_AUX
    2  GND                B  @S9S_MB_2U_LIB.S9S_MB_2U(SCH_1):GND

Q_CAP  I72  C1172  [Q_CAP_C0402-100NF,50V,10%,X7R,A]
    1  P5V                A  @S9S_MB_2U_LIB.S9S_MB_2U(SCH_1):P5V
    2  GND                B  @S9S_MB_2U_LIB.S9S_MB_2U(SCH_1):GND

Q_CAP  I4   C1173  [Q_CAP_0402-0.1UF,25V,10%,X7R,CA]
    1  P3V3_AUX           A  @S9S_MB_2U_LIB.S9S_MB_2U(SCH_1):P3V3_AUX
    2  GND                B  @S9S_MB_2U_LIB.S9S_MB_2U(SCH_1):GND

Q_CAP  I24  C1175  [Q_CAP_0402-0.1UF,25V,10%,X7R,CA]
    1  P3V3_AUX           A  @S9S_MB_2U_LIB.S9S_MB_2U(SCH_1):P3V3_AUX
    2  GND                B  @S9S_MB_2U_LIB.S9S_MB_2U(SCH_1):GND

Q_CAP  I67  C1177  [Q_CAP_C0402-1UF,25V,10%,X6S,CHA]
    1  RST_RTCRST_N       A  @S9S_MB_2U_LIB.S9S_MB_2U(SCH_1):RST_RTCRST_N
    2  GND                B  @S9S_MB_2U_LIB.S9S_MB_2U(SCH_1):GND

Q_CAP  I6   C1178  [Q_CAP_C0603-22UF,4V,20%,X6S,CHA]
    1  P1V05_PCH_AUX      A  @S9S_MB_2U_LIB.S9S_MB_2U(SCH_1):P1V05_PCH_AUX
    2  GND                B  @S9S_MB_2U_LIB.S9S_MB_2U(SCH_1):GND

Q_CAP  I27  C1181  [Q_CAP_C0603-22UF,4V,20%,X6S,CHA]
    1  P1V8_PCH_AUX       A  @S9S_MB_2U_LIB.S9S_MB_2U(SCH_1):P1V8_PCH_AUX
    2  GND                B  @S9S_MB_2U_LIB.S9S_MB_2U(SCH_1):GND

Q_CAP  I42  C1182  [Q_CAP_C0603-22UF,4V,20%,X6S,CHA]
    1  P1V05_PCH_AUX      A  @S9S_MB_2U_LIB.S9S_MB_2U(SCH_1):P1V05_PCH_AUX
    2  GND                B  @S9S_MB_2U_LIB.S9S_MB_2U(SCH_1):GND

Q_CAP  I51  C1183  [Q_CAP_C0402-2.2UF,10V,10%,X6S,A]
    1  P1V05_PCH_AUX      A  @S9S_MB_2U_LIB.S9S_MB_2U(SCH_1):P1V05_PCH_AUX
    2  GND                B  @S9S_MB_2U_LIB.S9S_MB_2U(SCH_1):GND

Q_CAP  I91  C1184  [Q_CAP_C0603-22UF,4V,20%,X6S,CHA]
    1  P3V3_AUX           A  @S9S_MB_2U_LIB.S9S_MB_2U(SCH_1):P3V3_AUX
    2  GND                B  @S9S_MB_2U_LIB.S9S_MB_2U(SCH_1):GND

Q_CAP  I7   C1185  [Q_CAP_C0603-22UF,4V,20%,X6S,CHA]
    1  P1V05_PCH_AUX      A  @S9S_MB_2U_LIB.S9S_MB_2U(SCH_1):P1V05_PCH_AUX
    2  GND                B  @S9S_MB_2U_LIB.S9S_MB_2U(SCH_1):GND

Q_CAP  I25  C1186  [Q_CAP_C0603-22UF,4V,20%,X6S,CHA]
    1  P1V8_PCH_AUX       A  @S9S_MB_2U_LIB.S9S_MB_2U(SCH_1):P1V8_PCH_AUX
    2  GND                B  @S9S_MB_2U_LIB.S9S_MB_2U(SCH_1):GND

Q_CAP  I40  C1187  [Q_CAP_C0603-22UF,4V,20%,X6S,CHA]
    1  P1V05_PCH_AUX      A  @S9S_MB_2U_LIB.S9S_MB_2U(SCH_1):P1V05_PCH_AUX
    2  GND                B  @S9S_MB_2U_LIB.S9S_MB_2U(SCH_1):GND

Q_CAP  I58  C1189  [Q_CAP_C0402-2.2UF,10V,10%,X6S,A]
    1  P1V05_PCH_AUX      A  @S9S_MB_2U_LIB.S9S_MB_2U(SCH_1):P1V05_PCH_AUX
    2  GND                B  @S9S_MB_2U_LIB.S9S_MB_2U(SCH_1):GND

Q_CAP  I89  C1191  [Q_CAP_C0603-22UF,4V,20%,X6S,CHA]
    1  P3V3_AUX           A  @S9S_MB_2U_LIB.S9S_MB_2U(SCH_1):P3V3_AUX
    2  GND                B  @S9S_MB_2U_LIB.S9S_MB_2U(SCH_1):GND

Q_CAP  I8   C1192  [Q_CAP_C0603-22UF,4V,20%,X6S,CHA]
    1  P1V05_PCH_AUX      A  @S9S_MB_2U_LIB.S9S_MB_2U(SCH_1):P1V05_PCH_AUX
    2  GND                B  @S9S_MB_2U_LIB.S9S_MB_2U(SCH_1):GND

Q_CAP  I30  C1197  [Q_CAP_C0603-22UF,4V,20%,X6S,CHA]
    1  P1V8_PCH_AUX       A  @S9S_MB_2U_LIB.S9S_MB_2U(SCH_1):P1V8_PCH_AUX
    2  GND                B  @S9S_MB_2U_LIB.S9S_MB_2U(SCH_1):GND

Q_CAP  I43  C1198  [Q_CAP_C0603-22UF,4V,20%,X6S,CHA]
    1  P1V05_PCH_AUX      A  @S9S_MB_2U_LIB.S9S_MB_2U(SCH_1):P1V05_PCH_AUX
    2  GND                B  @S9S_MB_2U_LIB.S9S_MB_2U(SCH_1):GND

Q_CAP  I59  C1200  [Q_CAP_C0402-2.2UF,10V,10%,X6S,A]
    1  P1V05_PCH_AUX      A  @S9S_MB_2U_LIB.S9S_MB_2U(SCH_1):P1V05_PCH_AUX
    2  GND                B  @S9S_MB_2U_LIB.S9S_MB_2U(SCH_1):GND

Q_CAP  I87  C1201  [Q_CAP_C0603-22UF,4V,20%,X6S,CHA]
    1  P3V3_AUX           A  @S9S_MB_2U_LIB.S9S_MB_2U(SCH_1):P3V3_AUX
    2  GND                B  @S9S_MB_2U_LIB.S9S_MB_2U(SCH_1):GND

Q_CAP  I29  C1202  [Q_CAP_C0603-22UF,4V,20%,X6S,CHA]
    1  P1V8_PCH_AUX       A  @S9S_MB_2U_LIB.S9S_MB_2U(SCH_1):P1V8_PCH_AUX
    2  GND                B  @S9S_MB_2U_LIB.S9S_MB_2U(SCH_1):GND

Q_CAP  I48  C1203  [Q_CAP_C0402-10UF,6.3V,20%,X6S,A]
    1  P1V05_PCH_AUX      A  @S9S_MB_2U_LIB.S9S_MB_2U(SCH_1):P1V05_PCH_AUX
    2  GND                B  @S9S_MB_2U_LIB.S9S_MB_2U(SCH_1):GND

Q_CAP  I60  C1204  [Q_CAP_C0402-2.2UF,10V,10%,X6S,A]
    1  P1V05_PCH_AUX      A  @S9S_MB_2U_LIB.S9S_MB_2U(SCH_1):P1V05_PCH_AUX
    2  GND                B  @S9S_MB_2U_LIB.S9S_MB_2U(SCH_1):GND

Q_CAP  I12  C1205  [Q_CAP_C0402-10UF,6.3V,20%,X6S,A]
    1  P1V05_PCH_AUX      A  @S9S_MB_2U_LIB.S9S_MB_2U(SCH_1):P1V05_PCH_AUX
    2  GND                B  @S9S_MB_2U_LIB.S9S_MB_2U(SCH_1):GND

Q_CAP  I78  C1206  [Q_CAP_C0402-10UF,6.3V,20%,X6S,A]
    1  P3V3_AUX           A  @S9S_MB_2U_LIB.S9S_MB_2U(SCH_1):P3V3_AUX
    2  GND                B  @S9S_MB_2U_LIB.S9S_MB_2U(SCH_1):GND

Q_CAP  I32  C1207  [Q_CAP_C0402-10UF,6.3V,20%,X6S,A]
    1  P1V8_PCH_AUX       A  @S9S_MB_2U_LIB.S9S_MB_2U(SCH_1):P1V8_PCH_AUX
    2  GND                B  @S9S_MB_2U_LIB.S9S_MB_2U(SCH_1):GND

Q_CAP  I94  C1208  [Q_CAP_0402-0.1UF,25V,10%,X7R,CA]
    1  P3V3               A  @S9S_MB_2U_LIB.S9S_MB_2U(SCH_1):P3V3
    2  GND                B  @S9S_MB_2U_LIB.S9S_MB_2U(SCH_1):GND

Q_CAP  I236  C1209  [Q_CAP_0402-100PF,50V,5%,X7R,CHA]
    1  PWRGD_SYS_PWROK_R      A  @S9S_MB_2U_LIB.S9S_MB_2U(SCH_1):PWRGD_SYS_PWROK_R
    2  GND                B  @S9S_MB_2U_LIB.S9S_MB_2U(SCH_1):GND

Q_CAP  I45  C1210  [Q_CAP_C0402-10UF,6.3V,20%,X6S,A]
    1  P1V05_PCH_AUX      A  @S9S_MB_2U_LIB.S9S_MB_2U(SCH_1):P1V05_PCH_AUX
    2  GND                B  @S9S_MB_2U_LIB.S9S_MB_2U(SCH_1):GND

Q_CAP  I240  C1211  [Q_CAP_0402-100PF,50V,5%,X7R,CHA]
    1  PWRGD_PCH_PWROK_R      A  @S9S_MB_2U_LIB.S9S_MB_2U(SCH_1):PWRGD_PCH_PWROK_R
    2  GND                B  @S9S_MB_2U_LIB.S9S_MB_2U(SCH_1):GND

Q_CAP  I316  C1213  [Q_CAP_C0805-22UF,16V,20%,X6S,CA]
    1  P12V_OCP_SFF       A  @S9S_MB_2U_LIB.S9S_MB_2U(SCH_1):P12V_OCP_SFF
    2  GND                B  @S9S_MB_2U_LIB.S9S_MB_2U(SCH_1):GND

Q_CAP  I61  C1214  [Q_CAP_C0402-2.2UF,10V,10%,X6S,A]
    1  P1V05_PCH_AUX      A  @S9S_MB_2U_LIB.S9S_MB_2U(SCH_1):P1V05_PCH_AUX
    2  GND                B  @S9S_MB_2U_LIB.S9S_MB_2U(SCH_1):GND

Q_CAP  I92  C1215  [Q_CAP_0402-0.1UF,25V,10%,X7R,CA]
    1  P3V3               A  @S9S_MB_2U_LIB.S9S_MB_2U(SCH_1):P3V3
    2  GND                B  @S9S_MB_2U_LIB.S9S_MB_2U(SCH_1):GND

Q_CAP  I91  C1216  [Q_CAP_0402-0.1UF,25V,10%,X7R,CA]
    1  P3V3               A  @S9S_MB_2U_LIB.S9S_MB_2U(SCH_1):P3V3
    2  GND                B  @S9S_MB_2U_LIB.S9S_MB_2U(SCH_1):GND

Q_CAP  I89  C1217  [Q_CAP_0402-0.1UF,25V,10%,X7R,CA]
    1  P3V3               A  @S9S_MB_2U_LIB.S9S_MB_2U(SCH_1):P3V3
    2  GND                B  @S9S_MB_2U_LIB.S9S_MB_2U(SCH_1):GND

Q_CAP  I189  C1218  [Q_CAP_0402-0.1UF,25V,10%,X7R,CA]
    1  P3V3               A  @S9S_MB_2U_LIB.S9S_MB_2U(SCH_1):P3V3
    2  GND                B  @S9S_MB_2U_LIB.S9S_MB_2U(SCH_1):GND

Q_CAP  I187  C1219  [Q_CAP_0402-0.1UF,25V,10%,X7R,CA]
    1  P3V3               A  @S9S_MB_2U_LIB.S9S_MB_2U(SCH_1):P3V3
    2  GND                B  @S9S_MB_2U_LIB.S9S_MB_2U(SCH_1):GND

Q_CAP  I78  C1226  [Q_CAP_0402-0.22UF,16V,10%,X7R,A]
    1  VR_P5V_EN_D_R      A  @S9S_MB_2U_LIB.S9S_MB_2U(SCH_1):VR_P5V_EN_D_R
    2  GND                B  @S9S_MB_2U_LIB.S9S_MB_2U(SCH_1):GND

Q_CAP  I82  C1227  [Q_CAP_C0402-100NF,50V,10%,X7R,A]
    1  P5V                A  @S9S_MB_2U_LIB.S9S_MB_2U(SCH_1):P5V
    2  GND                B  @S9S_MB_2U_LIB.S9S_MB_2U(SCH_1):GND

Q_CAP  I13  C1228  [Q_CAP_C0402-10UF,6.3V,20%,X6S,A]
    1  P1V05_PCH_AUX      A  @S9S_MB_2U_LIB.S9S_MB_2U(SCH_1):P1V05_PCH_AUX
    2  GND                B  @S9S_MB_2U_LIB.S9S_MB_2U(SCH_1):GND

Q_CAP  I168  C1229  [Q_CAP_0402-0.1UF,25V,10%,X7R,CA]
    1  PGPPA_AUX          A  @S9S_MB_2U_LIB.S9S_MB_2U(SCH_1):PGPPA_AUX
    2  GND                B  @S9S_MB_2U_LIB.S9S_MB_2U(SCH_1):GND

Q_CAP  I49  C1231  [Q_CAP_C0402-10UF,6.3V,20%,X6S,A]
    1  P1V05_PCH_AUX      A  @S9S_MB_2U_LIB.S9S_MB_2U(SCH_1):P1V05_PCH_AUX
    2  GND                B  @S9S_MB_2U_LIB.S9S_MB_2U(SCH_1):GND

Q_CAP  I331  C1232  [Q_CAP_C0805-22UF,16V,20%,X6S,CA]
    1  P12V_OCP_SFF       A  @S9S_MB_2U_LIB.S9S_MB_2U(SCH_1):P12V_OCP_SFF
    2  GND                B  @S9S_MB_2U_LIB.S9S_MB_2U(SCH_1):GND

Q_CAP  I319  C1233  [Q_CAP_0402-0.1UF,25V,10%,X7R,CA]
    1  P12V_OCP_SFF       A  @S9S_MB_2U_LIB.S9S_MB_2U(SCH_1):P12V_OCP_SFF
    2  GND                B  @S9S_MB_2U_LIB.S9S_MB_2U(SCH_1):GND

Q_CAP  I332  C1234  [Q_CAP_0402-0.1UF,25V,10%,X7R,CA]
    1  P12V_OCP_SFF       A  @S9S_MB_2U_LIB.S9S_MB_2U(SCH_1):P12V_OCP_SFF
    2  GND                B  @S9S_MB_2U_LIB.S9S_MB_2U(SCH_1):GND

Q_CAP  I333  C1235  [Q_CAP_0402-0.1UF,25V,10%,X7R,CA]
    1  P12V_OCP_SFF       A  @S9S_MB_2U_LIB.S9S_MB_2U(SCH_1):P12V_OCP_SFF
    2  GND                B  @S9S_MB_2U_LIB.S9S_MB_2U(SCH_1):GND

Q_CAP  I322  C1236  [Q_CAP_0402-0.1UF,25V,10%,X7R,CA]
    1  P12V_OCP_SFF       A  @S9S_MB_2U_LIB.S9S_MB_2U(SCH_1):P12V_OCP_SFF
    2  GND                B  @S9S_MB_2U_LIB.S9S_MB_2U(SCH_1):GND

Q_CAP  I334  C1237  [Q_CAP_0402-0.1UF,25V,10%,X7R,CA]
    1  P3V3_OCP_SFF       A  @S9S_MB_2U_LIB.S9S_MB_2U(SCH_1):P3V3_OCP_SFF
    2  GND                B  @S9S_MB_2U_LIB.S9S_MB_2U(SCH_1):GND

Q_CAP  I338  C1238  [Q_CAP_0402-0.1UF,25V,10%,X7R,CA]
    1  P3V3_OCP_SFF       A  @S9S_MB_2U_LIB.S9S_MB_2U(SCH_1):P3V3_OCP_SFF
    2  GND                B  @S9S_MB_2U_LIB.S9S_MB_2U(SCH_1):GND

Q_CAP  I337  C1239  [Q_CAP_0402-0.1UF,25V,10%,X7R,CA]
    1  P3V3_OCP_SFF       A  @S9S_MB_2U_LIB.S9S_MB_2U(SCH_1):P3V3_OCP_SFF
    2  GND                B  @S9S_MB_2U_LIB.S9S_MB_2U(SCH_1):GND

Q_CAP  I335  C1240  [Q_CAP_0402-0.1UF,25V,10%,X7R,CA]
    1  P3V3_OCP_SFF       A  @S9S_MB_2U_LIB.S9S_MB_2U(SCH_1):P3V3_OCP_SFF
    2  GND                B  @S9S_MB_2U_LIB.S9S_MB_2U(SCH_1):GND

Q_CAP  I115  C1241  [Q_CAP_0402-0.1UF,25V,10%,X7R,CA]
    1  P3V3_AUX           A  @S9S_MB_2U_LIB.S9S_MB_2U(SCH_1):P3V3_AUX
    2  GND                B  @S9S_MB_2U_LIB.S9S_MB_2U(SCH_1):GND

Q_CAP  I63  C1242  [Q_CAP_C0402-2.2UF,10V,10%,X6S,A]
    1  P1V05_PCH_AUX      A  @S9S_MB_2U_LIB.S9S_MB_2U(SCH_1):P1V05_PCH_AUX
    2  GND                B  @S9S_MB_2U_LIB.S9S_MB_2U(SCH_1):GND

Q_CAP  I83  C1243  [Q_CAP_0805-47UF,4V,20%,X6S,CH6A]
    1  P3V3_AUX           A  @S9S_MB_2U_LIB.S9S_MB_2U(SCH_1):P3V3_AUX
    2  GND                B  @S9S_MB_2U_LIB.S9S_MB_2U(SCH_1):GND

Q_CAP  I15  C1244  [Q_CAP_0805-47UF,4V,20%,X6S,CH6A]
    1  P1V05_PCH_AUX      A  @S9S_MB_2U_LIB.S9S_MB_2U(SCH_1):P1V05_PCH_AUX
    2  GND                B  @S9S_MB_2U_LIB.S9S_MB_2U(SCH_1):GND

Q_CAP  I81  C1245  [Q_CAP_0805-47UF,4V,20%,X6S,CH6A]
    1  P3V3_AUX           A  @S9S_MB_2U_LIB.S9S_MB_2U(SCH_1):P3V3_AUX
    2  GND                B  @S9S_MB_2U_LIB.S9S_MB_2U(SCH_1):GND

Q_CAP  I21  C1246  [Q_CAP_0805-47UF,4V,20%,X6S,CH6A]
    1  P1V05_PCH_AUX      A  @S9S_MB_2U_LIB.S9S_MB_2U(SCH_1):P1V05_PCH_AUX
    2  GND                B  @S9S_MB_2U_LIB.S9S_MB_2U(SCH_1):GND

Q_CAP  I65  C1247  [Q_CAP_0805-47UF,4V,20%,X6S,CH6A]
    1  P1V05_PCH_AUX      A  @S9S_MB_2U_LIB.S9S_MB_2U(SCH_1):P1V05_PCH_AUX
    2  GND                B  @S9S_MB_2U_LIB.S9S_MB_2U(SCH_1):GND

Q_CAP  I22  C1248  [Q_CAP_0805-47UF,4V,20%,X6S,CH6A]
    1  P1V05_PCH_AUX      A  @S9S_MB_2U_LIB.S9S_MB_2U(SCH_1):P1V05_PCH_AUX
    2  GND                B  @S9S_MB_2U_LIB.S9S_MB_2U(SCH_1):GND

Q_CAP  I66  C1249  [Q_CAP_0805-47UF,4V,20%,X6S,CH6A]
    1  P1V05_PCH_AUX      A  @S9S_MB_2U_LIB.S9S_MB_2U(SCH_1):P1V05_PCH_AUX
    2  GND                B  @S9S_MB_2U_LIB.S9S_MB_2U(SCH_1):GND

Q_CAP  I137  C1250  [Q_CAP_0402-1UF,6.3V,10%,EMPTY,A]
    1  P1V05_PCH_AUX      A  @S9S_MB_2U_LIB.S9S_MB_2U(SCH_1):P1V05_PCH_AUX
    2  GND                B  @S9S_MB_2U_LIB.S9S_MB_2U(SCH_1):GND

Q_CAP  I110  C1251  [Q_CAP_C0603-10UF,6.3V,20%,X6S,A]
    1  P1V05_PCH_PLL_AUX      A  @S9S_MB_2U_LIB.S9S_MB_2U(SCH_1):P1V05_PCH_PLL_AUX
    2  GND                B  @S9S_MB_2U_LIB.S9S_MB_2U(SCH_1):GND

Q_CAP  I125  C1252  [Q_CAP_C0603-10UF,6.3V,20%,X6S,A]
    1  P1V8_PCH_PLL_AUX      A  @S9S_MB_2U_LIB.S9S_MB_2U(SCH_1):P1V8_PCH_PLL_AUX
    2  GND                B  @S9S_MB_2U_LIB.S9S_MB_2U(SCH_1):GND

Q_CAP  I147  C1253  [Q_CAP_0402-1UF,6.3V,10%,EMPTY,A]
    1  P1V8_PCH_AUX       A  @S9S_MB_2U_LIB.S9S_MB_2U(SCH_1):P1V8_PCH_AUX
    2  GND                B  @S9S_MB_2U_LIB.S9S_MB_2U(SCH_1):GND

Q_CAP  I111  C1254  [Q_CAP_C0603-10UF,6.3V,20%,X6S,A]
    1  P1V05_PCH_PLL_AUX      A  @S9S_MB_2U_LIB.S9S_MB_2U(SCH_1):P1V05_PCH_PLL_AUX
    2  GND                B  @S9S_MB_2U_LIB.S9S_MB_2U(SCH_1):GND

Q_CAP  I123  C1255  [Q_CAP_C0603-10UF,6.3V,20%,X6S,A]
    1  P1V8_PCH_PLL_AUX      A  @S9S_MB_2U_LIB.S9S_MB_2U(SCH_1):P1V8_PCH_PLL_AUX
    2  GND                B  @S9S_MB_2U_LIB.S9S_MB_2U(SCH_1):GND

Q_CAP  I136  C1256  [Q_CAP_0402-1UF,6.3V,10%,EMPTY,A]
    1  P1V05_PCH_PLL_AUX      A  @S9S_MB_2U_LIB.S9S_MB_2U(SCH_1):P1V05_PCH_PLL_AUX
    2  GND                B  @S9S_MB_2U_LIB.S9S_MB_2U(SCH_1):GND

Q_CAP  I146  C1257  [Q_CAP_0402-1UF,6.3V,10%,EMPTY,A]
    1  P1V8_PCH_PLL_AUX      A  @S9S_MB_2U_LIB.S9S_MB_2U(SCH_1):P1V8_PCH_PLL_AUX
    2  GND                B  @S9S_MB_2U_LIB.S9S_MB_2U(SCH_1):GND

Q_CAP  I112  C1258  [Q_CAP_0805-47UF,4V,20%,X6S,CH6A]
    1  P1V05_PCH_PLL_AUX      A  @S9S_MB_2U_LIB.S9S_MB_2U(SCH_1):P1V05_PCH_PLL_AUX
    2  GND                B  @S9S_MB_2U_LIB.S9S_MB_2U(SCH_1):GND

Q_CAP  I121  C1259  [Q_CAP_0805-47UF,4V,20%,X6S,CH6A]
    1  P1V8_PCH_PLL_AUX      A  @S9S_MB_2U_LIB.S9S_MB_2U(SCH_1):P1V8_PCH_PLL_AUX
    2  GND                B  @S9S_MB_2U_LIB.S9S_MB_2U(SCH_1):GND

Q_CAP  I131  C1260  [Q_CAP_C0603-10UF,6.3V,20%,X6S,A]
    1  P1V05_PCH_PLL_AUX      A  @S9S_MB_2U_LIB.S9S_MB_2U(SCH_1):P1V05_PCH_PLL_AUX
    2  GND                B  @S9S_MB_2U_LIB.S9S_MB_2U(SCH_1):GND

Q_CAP  I142  C1261  [Q_CAP_C0603-10UF,6.3V,20%,X6S,A]
    1  P1V8_PCH_PLL_AUX      A  @S9S_MB_2U_LIB.S9S_MB_2U(SCH_1):P1V8_PCH_PLL_AUX
    2  GND                B  @S9S_MB_2U_LIB.S9S_MB_2U(SCH_1):GND

Q_CAP  I104  C1262  [Q_CAP_C0402-10UF,6.3V,20%,X6S,A]
    1  P1V05_PCH_PLL_AUX      A  @S9S_MB_2U_LIB.S9S_MB_2U(SCH_1):P1V05_PCH_PLL_AUX
    2  GND                B  @S9S_MB_2U_LIB.S9S_MB_2U(SCH_1):GND

Q_CAP  I119  C1263  [Q_CAP_C0402-10UF,6.3V,20%,X6S,A]
    1  P1V8_PCH_PLL_AUX      A  @S9S_MB_2U_LIB.S9S_MB_2U(SCH_1):P1V8_PCH_PLL_AUX
    2  GND                B  @S9S_MB_2U_LIB.S9S_MB_2U(SCH_1):GND

Q_CAP  I133  C1264  [Q_CAP_0402-1UF,6.3V,10%,EMPTY,A]
    1  P1V05_PCH_PLL_AUX      A  @S9S_MB_2U_LIB.S9S_MB_2U(SCH_1):P1V05_PCH_PLL_AUX
    2  GND                B  @S9S_MB_2U_LIB.S9S_MB_2U(SCH_1):GND

Q_CAP  I140  C1265  [Q_CAP_0402-1UF,6.3V,10%,EMPTY,A]
    1  P1V8_PCH_PLL_AUX      A  @S9S_MB_2U_LIB.S9S_MB_2U(SCH_1):P1V8_PCH_PLL_AUX
    2  GND                B  @S9S_MB_2U_LIB.S9S_MB_2U(SCH_1):GND

Q_CAP  I127  C1266  [Q_CAP_C0402-10UF,6.3V,20%,X6S,A]
    1  P1V8_PCH_PLL_AUX      A  @S9S_MB_2U_LIB.S9S_MB_2U(SCH_1):P1V8_PCH_PLL_AUX
    2  GND                B  @S9S_MB_2U_LIB.S9S_MB_2U(SCH_1):GND

Q_CAP  I100  C1272  [Q_CAP_0805-47UF,4V,20%,X6S,CH6A]
    1  P1V05_PCH_PLL_AUX      A  @S9S_MB_2U_LIB.S9S_MB_2U(SCH_1):P1V05_PCH_PLL_AUX
    2  GND                B  @S9S_MB_2U_LIB.S9S_MB_2U(SCH_1):GND

Q_CAP  I116  C1273  [Q_CAP_0805-47UF,4V,20%,X6S,CH6A]
    1  P1V8_PCH_PLL_AUX      A  @S9S_MB_2U_LIB.S9S_MB_2U(SCH_1):P1V8_PCH_PLL_AUX
    2  GND                B  @S9S_MB_2U_LIB.S9S_MB_2U(SCH_1):GND

Q_CAP  I59  C1274  [Q_CAP_0402-0.1UF,25V,10%,X7R,CA]
    1  P3V3_AUX           A  @S9S_MB_2U_LIB.S9S_MB_2U(SCH_1):P3V3_AUX
    2  GND                B  @S9S_MB_2U_LIB.S9S_MB_2U(SCH_1):GND

Q_CAP  I49  C1275  [Q_CAP_0402-0.1UF,25V,10%,X7R,CA]
    1  P3V3_AUX           A  @S9S_MB_2U_LIB.S9S_MB_2U(SCH_1):P3V3_AUX
    2  GND                B  @S9S_MB_2U_LIB.S9S_MB_2U(SCH_1):GND

Q_CAP  I45  C1276  [Q_CAP_C0805-22UF,16V,20%,X6S,CA]
    1  P12V_E1S_0         A  @S9S_MB_2U_LIB.S9S_MB_2U(SCH_1):P12V_E1S_0
    2  GND                B  @S9S_MB_2U_LIB.S9S_MB_2U(SCH_1):GND

Q_CAP  I44  C1277  [Q_CAP_C0805-22UF,16V,20%,X6S,CA]
    1  P12V_E1S_0         A  @S9S_MB_2U_LIB.S9S_MB_2U(SCH_1):P12V_E1S_0
    2  GND                B  @S9S_MB_2U_LIB.S9S_MB_2U(SCH_1):GND

Q_CAP  I15  C1278  [Q_CAP_0402-0.1UF,25V,10%,X7R,CA]
    1  P12V_E1S_0         A  @S9S_MB_2U_LIB.S9S_MB_2U(SCH_1):P12V_E1S_0
    2  GND                B  @S9S_MB_2U_LIB.S9S_MB_2U(SCH_1):GND

Q_CAP  I14  C1279  [Q_CAP_0402-0.1UF,25V,10%,X7R,CA]
    1  P12V_E1S_0         A  @S9S_MB_2U_LIB.S9S_MB_2U(SCH_1):P12V_E1S_0
    2  GND                B  @S9S_MB_2U_LIB.S9S_MB_2U(SCH_1):GND

Q_CAP  I32  C1280  [Q_CAP_0402-0.1UF,25V,10%,X7R,CA]
    1  P12V_E1S_1         A  @S9S_MB_2U_LIB.S9S_MB_2U(SCH_1):P12V_E1S_1
    2  GND                B  @S9S_MB_2U_LIB.S9S_MB_2U(SCH_1):GND

Q_CAP  I30  C1281  [Q_CAP_0402-0.1UF,25V,10%,X7R,CA]
    1  P12V_E1S_1         A  @S9S_MB_2U_LIB.S9S_MB_2U(SCH_1):P12V_E1S_1
    2  GND                B  @S9S_MB_2U_LIB.S9S_MB_2U(SCH_1):GND

Q_CAP  I8   C1282  [Q_CAP_0402-0.1UF,25V,10%,X7R,CA]
    1  P3V3_E1S_0         A  @S9S_MB_2U_LIB.S9S_MB_2U(SCH_1):P3V3_E1S_0
    2  GND                B  @S9S_MB_2U_LIB.S9S_MB_2U(SCH_1):GND

Q_CAP  I7   C1283  [Q_CAP_0402-0.1UF,25V,10%,X7R,CA]
    1  P3V3_E1S_0         A  @S9S_MB_2U_LIB.S9S_MB_2U(SCH_1):P3V3_E1S_0
    2  GND                B  @S9S_MB_2U_LIB.S9S_MB_2U(SCH_1):GND

Q_CAP  I29  C1284  [Q_CAP_0402-0.1UF,25V,10%,X7R,CA]
    1  P3V3_E1S_1         A  @S9S_MB_2U_LIB.S9S_MB_2U(SCH_1):P3V3_E1S_1
    2  GND                B  @S9S_MB_2U_LIB.S9S_MB_2U(SCH_1):GND

Q_CAP  I27  C1285  [Q_CAP_0402-0.1UF,25V,10%,X7R,CA]
    1  P3V3_E1S_1         A  @S9S_MB_2U_LIB.S9S_MB_2U(SCH_1):P3V3_E1S_1
    2  GND                B  @S9S_MB_2U_LIB.S9S_MB_2U(SCH_1):GND

Q_CAP  I30  C1286  [Q_CAP_0402-1000PF,50V,5%,EMPTYA]
    2  GND                B  @S9S_MB_2U_LIB.S9S_MB_2U(SCH_1):GND
    1  FM_P1V05_PCH_AUX_R_EN      A  @S9S_MB_2U_LIB.S9S_MB_2U(SCH_1):FM_P1V05_PCH_AUX_R_EN

Q_CAP  I112  C1288  [Q_CAP_0402-0.1UF,25V,10%,X7R,CA]
    1  P3V3_AUX           A  @S9S_MB_2U_LIB.S9S_MB_2U(SCH_1):P3V3_AUX
    2  GND                B  @S9S_MB_2U_LIB.S9S_MB_2U(SCH_1):GND

Q_CAP  I110  C1289  [Q_CAP_C0402-1UF,25V,10%,X6S,CHA]
    1  P3V3_AUX           A  @S9S_MB_2U_LIB.S9S_MB_2U(SCH_1):P3V3_AUX
    2  GND                B  @S9S_MB_2U_LIB.S9S_MB_2U(SCH_1):GND

Q_CAP  I43  C1290  [Q_CAP_C0402-1UF,25V,10%,X6S,CHA]
    1  P3V3_AUX           A  @S9S_MB_2U_LIB.S9S_MB_2U(SCH_1):P3V3_AUX
    2  GND                B  @S9S_MB_2U_LIB.S9S_MB_2U(SCH_1):GND

Q_CAP  I16  C1291  [Q_CAP_C0402-1UF,25V,10%,X6S,CHA]
    1  P3V3_AUX           A  @S9S_MB_2U_LIB.S9S_MB_2U(SCH_1):P3V3_AUX
    2  GND                B  @S9S_MB_2U_LIB.S9S_MB_2U(SCH_1):GND

Q_CAP  I90  C1292  [Q_CAP_0402-0.1UF,25V,10%,X7R,CA]
    1  P3V3_AUX           A  @S9S_MB_2U_LIB.S9S_MB_2U(SCH_1):P3V3_AUX
    2  GND                B  @S9S_MB_2U_LIB.S9S_MB_2U(SCH_1):GND

Q_CAP  I95  C1293  [Q_CAP_C0402-1UF,25V,10%,X6S,CHA]
    2  GND                B  @S9S_MB_2U_LIB.S9S_MB_2U(SCH_1):GND
    1  FM_BMC_EN_DET      A  @S9S_MB_2U_LIB.S9S_MB_2U(SCH_1):FM_BMC_EN_DET

Q_CAP  I178  C1296  [Q_CAP_0402-1000PF,50V,5%,X7R,TA]
    1  PWRGD_PVNN_MAIN_CPU0      A  @S9S_MB_2U_LIB.S9S_MB_2U(SCH_1):PWRGD_PVNN_MAIN_CPU0
    2  GND                B  @S9S_MB_2U_LIB.S9S_MB_2U(SCH_1):GND

Q_CAP  I186  C1297  [Q_CAP_0402-1000PF,50V,5%,X7R,TA]
    1  PWRGD_PVNN_MAIN_CPU1      A  @S9S_MB_2U_LIB.S9S_MB_2U(SCH_1):PWRGD_PVNN_MAIN_CPU1
    2  GND                B  @S9S_MB_2U_LIB.S9S_MB_2U(SCH_1):GND

Q_CAP  I14  C1300  [Q_CAP_0402-1000PF,50V,5%,EMPTYA]
    2  GND                B  @S9S_MB_2U_LIB.S9S_MB_2U(SCH_1):GND
    1  FM_PVPP_HBM_CPU0_EN      A  @S9S_MB_2U_LIB.S9S_MB_2U(SCH_1):FM_PVPP_HBM_CPU0_EN

Q_CAP  I27  C1301  [Q_CAP_0402-1000PF,50V,5%,EMPTYA]
    1  PWRGD_PVPP_HBM_CPU0_R      A  @S9S_MB_2U_LIB.S9S_MB_2U(SCH_1):PWRGD_PVPP_HBM_CPU0_R
    2  GND                B  @S9S_MB_2U_LIB.S9S_MB_2U(SCH_1):GND

Q_CAP  I101  C1302  [Q_CAP_C0402-22UF,4V,20%,X6S,CHA]
    1  PVNN_TERM_CPU0      A  @S9S_MB_2U_LIB.S9S_MB_2U(SCH_1):PVNN_TERM_CPU0
    2  GND                B  @S9S_MB_2U_LIB.S9S_MB_2U(SCH_1):GND

Q_CAP  I52  C1305  [Q_CAP_0402-0.1UF,25V,10%,X7R,CA]
    1  P3V3_AUX           A  @S9S_MB_2U_LIB.S9S_MB_2U(SCH_1):P3V3_AUX
    2  GND                B  @S9S_MB_2U_LIB.S9S_MB_2U(SCH_1):GND

Q_CAP  I154  C1307  [Q_CAP_0402-1000PF,50V,5%,EMPTYA]
    2  GND                B  @S9S_MB_2U_LIB.S9S_MB_2U(SCH_1):GND
    1  FM_PVNN_MAIN_CPU0_EN      A  @S9S_MB_2U_LIB.S9S_MB_2U(SCH_1):FM_PVNN_MAIN_CPU0_EN

Q_CAP  I166  C1308  [Q_CAP_0402-1000PF,50V,5%,EMPTYA]
    2  GND                B  @S9S_MB_2U_LIB.S9S_MB_2U(SCH_1):GND
    1  FM_PVNN_MAIN_CPU1_EN      A  @S9S_MB_2U_LIB.S9S_MB_2U(SCH_1):FM_PVNN_MAIN_CPU1_EN

Q_CAP  I44  C1309  [Q_CAP_C0603-10UF,6.3V,20%,X6S,A]
    1  P3V3_AUX_CLK_GEN_VDDXTAL_CK440      A  @S9S_MB_2U_LIB.S9S_MB_2U(SCH_1):P3V3_AUX_CLK_GEN_VDDXTAL_CK440
    2  GND                B  @S9S_MB_2U_LIB.S9S_MB_2U(SCH_1):GND

Q_CAP  I59  C1310  [Q_CAP_C0603-10UF,6.3V,20%,X6S,A]
    1  P3V3_AUX_CLK_GEN_VDDMXCK_CK440      A  @S9S_MB_2U_LIB.S9S_MB_2U(SCH_1):P3V3_AUX_CLK_GEN_VDDMXCK_CK440
    2  GND                B  @S9S_MB_2U_LIB.S9S_MB_2U(SCH_1):GND

Q_CAP  I43  C1311  [Q_CAP_C0402-1UF,25V,10%,X6S,CHA]
    1  P3V3_AUX_CLK_GEN_VDDXTAL_CK440      A  @S9S_MB_2U_LIB.S9S_MB_2U(SCH_1):P3V3_AUX_CLK_GEN_VDDXTAL_CK440
    2  GND                B  @S9S_MB_2U_LIB.S9S_MB_2U(SCH_1):GND

Q_CAP  I58  C1312  [Q_CAP_C0402-1UF,25V,10%,X6S,CHA]
    1  P3V3_AUX_CLK_GEN_VDDMXCK_CK440      A  @S9S_MB_2U_LIB.S9S_MB_2U(SCH_1):P3V3_AUX_CLK_GEN_VDDMXCK_CK440
    2  GND                B  @S9S_MB_2U_LIB.S9S_MB_2U(SCH_1):GND

Q_CAP  I48  C1313  [Q_CAP_C0603-10UF,6.3V,20%,X6S,A]
    1  P3V3_AUX_CLK_GEN_VDDA25M_CK440      A  @S9S_MB_2U_LIB.S9S_MB_2U(SCH_1):P3V3_AUX_CLK_GEN_VDDA25M_CK440
    2  GND                B  @S9S_MB_2U_LIB.S9S_MB_2U(SCH_1):GND

Q_CAP  I53  C1314  [Q_CAP_C0603-10UF,6.3V,20%,X6S,A]
    1  P3V3_AUX_CLK_GEN_VDDPT_CK440      A  @S9S_MB_2U_LIB.S9S_MB_2U(SCH_1):P3V3_AUX_CLK_GEN_VDDPT_CK440
    2  GND                B  @S9S_MB_2U_LIB.S9S_MB_2U(SCH_1):GND

Q_CAP  I8   C1315  [Q_CAP_C0402-1UF,25V,10%,X6S,CHA]
    1  P3V3_AUX           A  @S9S_MB_2U_LIB.S9S_MB_2U(SCH_1):P3V3_AUX
    2  GND                B  @S9S_MB_2U_LIB.S9S_MB_2U(SCH_1):GND

Q_CAP  I60  C1316  [Q_CAP_C0402-0.047UF,25V,10%,X7A]
    2  GND                B  @S9S_MB_2U_LIB.S9S_MB_2U(SCH_1):GND
    1  FM_COMP_P3V3_STBY_CEXT      A  @S9S_MB_2U_LIB.S9S_MB_2U(SCH_1):FM_COMP_P3V3_STBY_CEXT

Q_CAP  I51  C1317  [Q_CAP_0402-0.1UF,25V,10%,X7R,CA]
    1  P3V3_AUX           A  @S9S_MB_2U_LIB.S9S_MB_2U(SCH_1):P3V3_AUX
    2  GND                B  @S9S_MB_2U_LIB.S9S_MB_2U(SCH_1):GND

Q_CAP  I54  C1318  [Q_CAP_C0402-1UF,25V,10%,EMPTY,A]
    1  PWRGD_DSW_PWROK_R1      A  @S9S_MB_2U_LIB.S9S_MB_2U(SCH_1):PWRGD_DSW_PWROK_R1
    2  GND                B  @S9S_MB_2U_LIB.S9S_MB_2U(SCH_1):GND

Q_CAP  I47  C1319  [Q_CAP_C0402-1UF,25V,10%,X6S,CHA]
    1  PWRGD_DSW_PWROK      A  @S9S_MB_2U_LIB.S9S_MB_2U(SCH_1):PWRGD_DSW_PWROK
    2  GND                B  @S9S_MB_2U_LIB.S9S_MB_2U(SCH_1):GND

Q_CAP  I134  C1320  [Q_CAP_0402-0.1UF,25V,10%,X7R,CA]
    1  P3V3_AUX           A  @S9S_MB_2U_LIB.S9S_MB_2U(SCH_1):P3V3_AUX
    2  GND                B  @S9S_MB_2U_LIB.S9S_MB_2U(SCH_1):GND

Q_CAP  I55  C1321  [Q_CAP_0402-0.1UF,25V,10%,X7R,CA]
    1  P3V3_AUX           A  @S9S_MB_2U_LIB.S9S_MB_2U(SCH_1):P3V3_AUX
    2  GND                B  @S9S_MB_2U_LIB.S9S_MB_2U(SCH_1):GND

Q_CAP  I27  C1322  [Q_CAP_0402-0.1UF,25V,10%,X7R,CA]
    1  P3V3_AUX           A  @S9S_MB_2U_LIB.S9S_MB_2U(SCH_1):P3V3_AUX
    2  GND                B  @S9S_MB_2U_LIB.S9S_MB_2U(SCH_1):GND

Q_CAP  I28  C1323  [Q_CAP_0402-0.1UF,25V,10%,X7R,CA]
    1  P1V8_PCH_AUX       A  @S9S_MB_2U_LIB.S9S_MB_2U(SCH_1):P1V8_PCH_AUX
    2  GND                B  @S9S_MB_2U_LIB.S9S_MB_2U(SCH_1):GND

Q_CAP  I286  C1324  [Q_CAP_0402-0.1UF,25V,10%,EMPTYA]
    2  GND                B  @S9S_MB_2U_LIB.S9S_MB_2U(SCH_1):GND
    1  FM_CK440Q_DEV_25M_EN      A  @S9S_MB_2U_LIB.S9S_MB_2U(SCH_1):FM_CK440Q_DEV_25M_EN

Q_CAP  I412  C1325  [Q_CAP_0402-0.1UF,25V,10%,X7R,CA]
    2  GND                B  @S9S_MB_2U_LIB.S9S_MB_2U(SCH_1):GND
    1  FM_PLD_REV_N       A  @S9S_MB_2U_LIB.S9S_MB_2U(SCH_1):FM_PLD_REV_N

Q_CAP  I73  C1326  [Q_CAP_C0402-100NF,50V,10%,X7R,A]
    1  P5V_AUX            A  @S9S_MB_2U_LIB.S9S_MB_2U(SCH_1):P5V_AUX
    2  GND                B  @S9S_MB_2U_LIB.S9S_MB_2U(SCH_1):GND

Q_CAP  I83  C1331  [Q_CAP_C0805-10UF,16V,10%,X6S,CA]
    1  P5V                A  @S9S_MB_2U_LIB.S9S_MB_2U(SCH_1):P5V
    2  GND                B  @S9S_MB_2U_LIB.S9S_MB_2U(SCH_1):GND

Q_CAP  I63  C1332  [Q_CAP_C0402-100NF,50V,10%,X7R,A]
    1  P3V3_AUX           A  @S9S_MB_2U_LIB.S9S_MB_2U(SCH_1):P3V3_AUX
    2  GND                B  @S9S_MB_2U_LIB.S9S_MB_2U(SCH_1):GND

Q_CAP  I64  C1333  [Q_CAP_C0805-10UF,16V,10%,X6S,CA]
    1  P3V3_AUX           A  @S9S_MB_2U_LIB.S9S_MB_2U(SCH_1):P3V3_AUX
    2  GND                B  @S9S_MB_2U_LIB.S9S_MB_2U(SCH_1):GND

Q_CAP  I13  C1337  [Q_CAP_C0603-22UF,6.3V,20%,X6S,A]
    1  P5V                A  @S9S_MB_2U_LIB.S9S_MB_2U(SCH_1):P5V
    2  GND                B  @S9S_MB_2U_LIB.S9S_MB_2U(SCH_1):GND

Q_CAP  I65  C1338  [Q_CAP_C0805-10UF,16V,10%,EMPTYA]
    1  P3V3_AUX           A  @S9S_MB_2U_LIB.S9S_MB_2U(SCH_1):P3V3_AUX
    2  GND                B  @S9S_MB_2U_LIB.S9S_MB_2U(SCH_1):GND

Q_CAP  I66  C1339  [Q_CAP_C0402-100NF,50V,10%,X7R,A]
    1  P3V3               A  @S9S_MB_2U_LIB.S9S_MB_2U(SCH_1):P3V3
    2  GND                B  @S9S_MB_2U_LIB.S9S_MB_2U(SCH_1):GND

Q_CAP  I67  C1340  [Q_CAP_C0805-10UF,16V,10%,X6S,CA]
    1  P3V3               A  @S9S_MB_2U_LIB.S9S_MB_2U(SCH_1):P3V3
    2  GND                B  @S9S_MB_2U_LIB.S9S_MB_2U(SCH_1):GND

Q_CAP  I14  C1341  [Q_CAP_C0603-22UF,6.3V,20%,X6S,A]
    1  P5V                A  @S9S_MB_2U_LIB.S9S_MB_2U(SCH_1):P5V
    2  GND                B  @S9S_MB_2U_LIB.S9S_MB_2U(SCH_1):GND

Q_CAP  I50  C1342  [Q_CAP_C0603-22UF,6.3V,20%,X6S,A]
    1  P5V_USB_INT        A  @S9S_MB_2U_LIB.S9S_MB_2U(SCH_1):P5V_USB_INT
    2  GND                B  @S9S_MB_2U_LIB.S9S_MB_2U(SCH_1):GND

Q_CAP  I51  C1343  [Q_CAP_C0603-22UF,6.3V,20%,X6S,A]
    1  P5V_USB_INT        A  @S9S_MB_2U_LIB.S9S_MB_2U(SCH_1):P5V_USB_INT
    2  GND                B  @S9S_MB_2U_LIB.S9S_MB_2U(SCH_1):GND

Q_CAP  I37  C1344  [Q_CAP_0402-0.1UF,25V,10%,X7R,CA]
    1  P3V3_AUX_SENSE      A  @S9S_MB_2U_LIB.S9S_MB_2U(SCH_1):P3V3_AUX_SENSE
    2  GND                B  @S9S_MB_2U_LIB.S9S_MB_2U(SCH_1):GND

Q_CAP  I39  C1345  [Q_CAP_0402-0.1UF,25V,10%,X7R,CA]
    1  P3V3_SENSE         A  @S9S_MB_2U_LIB.S9S_MB_2U(SCH_1):P3V3_SENSE
    2  GND                B  @S9S_MB_2U_LIB.S9S_MB_2U(SCH_1):GND

Q_CAP  I42  C1346  [Q_CAP_0402-0.1UF,25V,10%,X7R,CA]
    1  P3V3_RTC_AUX_SENSE      A  @S9S_MB_2U_LIB.S9S_MB_2U(SCH_1):P3V3_RTC_AUX_SENSE
    2  GND                B  @S9S_MB_2U_LIB.S9S_MB_2U(SCH_1):GND

Q_CAP  I3   C1347  [Q_CAP_0402-0.1UF,25V,10%,X7R,CA]
    1  P3V3_AUX           A  @S9S_MB_2U_LIB.S9S_MB_2U(SCH_1):P3V3_AUX
    2  GND                B  @S9S_MB_2U_LIB.S9S_MB_2U(SCH_1):GND

Q_CAP  I45  C1351  [Q_CAP_0402-0.1UF,25V,10%,X7R,CA]
    1  P12V_AUX_SENSE      A  @S9S_MB_2U_LIB.S9S_MB_2U(SCH_1):P12V_AUX_SENSE
    2  GND                B  @S9S_MB_2U_LIB.S9S_MB_2U(SCH_1):GND

Q_CAP  I149  C1353  [Q_CAP_C0402-22UF,4V,20%,X6S,CHA]
    1  PVNN_MAIN_CPU1      A  @S9S_MB_2U_LIB.S9S_MB_2U(SCH_1):PVNN_MAIN_CPU1
    2  GND                B  @S9S_MB_2U_LIB.S9S_MB_2U(SCH_1):GND

Q_CAP  I148  C1358  [Q_CAP_0402-0.1UF,25V,10%,X7R,CA]
    1  P12V_AUX           A  @S9S_MB_2U_LIB.S9S_MB_2U(SCH_1):P12V_AUX
    2  GND                B  @S9S_MB_2U_LIB.S9S_MB_2U(SCH_1):GND

Q_CAP  I147  C1359  [Q_CAP_C0805-10UF,25V,10%,X6S,CA]
    1  P12V_AUX           A  @S9S_MB_2U_LIB.S9S_MB_2U(SCH_1):P12V_AUX
    2  GND                B  @S9S_MB_2U_LIB.S9S_MB_2U(SCH_1):GND

Q_CAP  I144  C1360  [Q_CAP_0402-0.1UF,25V,10%,X7R,CA]
    1  P12V_REAR_CPU      A  @S9S_MB_2U_LIB.S9S_MB_2U(SCH_1):P12V_REAR_CPU
    2  GND                B  @S9S_MB_2U_LIB.S9S_MB_2U(SCH_1):GND

Q_CAP  I145  C1361  [Q_CAP_C0805-10UF,25V,10%,X6S,CA]
    1  P12V_REAR_CPU      A  @S9S_MB_2U_LIB.S9S_MB_2U(SCH_1):P12V_REAR_CPU
    2  GND                B  @S9S_MB_2U_LIB.S9S_MB_2U(SCH_1):GND

Q_CAP  I119  C1362  [Q_CAP_C0402-22UF,4V,20%,X6S,CHA]
    1  PVNN_MAIN_CPU0      A  @S9S_MB_2U_LIB.S9S_MB_2U(SCH_1):PVNN_MAIN_CPU0
    2  GND                B  @S9S_MB_2U_LIB.S9S_MB_2U(SCH_1):GND

Q_CAP  I51  C1363  [Q_CAP_C0402-22UF,4V,20%,X6S,CHA]
    1  PVNN_MAIN_CPU0      A  @S9S_MB_2U_LIB.S9S_MB_2U(SCH_1):PVNN_MAIN_CPU0
    2  GND                B  @S9S_MB_2U_LIB.S9S_MB_2U(SCH_1):GND

Q_CAP  I53  C1364  [Q_CAP_C0402-22UF,4V,20%,X6S,CHA]
    1  PVNN_MAIN_CPU0      A  @S9S_MB_2U_LIB.S9S_MB_2U(SCH_1):PVNN_MAIN_CPU0
    2  GND                B  @S9S_MB_2U_LIB.S9S_MB_2U(SCH_1):GND

Q_CAP  I47  C1365  [Q_CAP_C0402-22UF,4V,20%,X6S,CHA]
    1  PVNN_MAIN_CPU1      A  @S9S_MB_2U_LIB.S9S_MB_2U(SCH_1):PVNN_MAIN_CPU1
    2  GND                B  @S9S_MB_2U_LIB.S9S_MB_2U(SCH_1):GND

Q_CAP  I49  C1366  [Q_CAP_C0402-22UF,4V,20%,X6S,CHA]
    1  PVNN_MAIN_CPU1      A  @S9S_MB_2U_LIB.S9S_MB_2U(SCH_1):PVNN_MAIN_CPU1
    2  GND                B  @S9S_MB_2U_LIB.S9S_MB_2U(SCH_1):GND

Q_CAP  I141  C1387  [Q_CAP_C0805-100UF,4V,20%,X6S,CA]
    1  PVNN_MAIN_CPU1      A  @S9S_MB_2U_LIB.S9S_MB_2U(SCH_1):PVNN_MAIN_CPU1
    2  GND                B  @S9S_MB_2U_LIB.S9S_MB_2U(SCH_1):GND

Q_CAP  I139  C1388  [Q_CAP_C0805-100UF,4V,20%,X6S,CA]
    1  PVPP_HBM_CPU1      A  @S9S_MB_2U_LIB.S9S_MB_2U(SCH_1):PVPP_HBM_CPU1
    2  GND                B  @S9S_MB_2U_LIB.S9S_MB_2U(SCH_1):GND

Q_CAP  I143  C1389  [Q_CAP_C0603-47UF,2.5V,20%,X6S,A]
    1  PVNN_MAIN_CPU1      A  @S9S_MB_2U_LIB.S9S_MB_2U(SCH_1):PVNN_MAIN_CPU1
    2  GND                B  @S9S_MB_2U_LIB.S9S_MB_2U(SCH_1):GND

Q_CAP  I140  C1390  [Q_CAP_C0805-100UF,4V,20%,X6S,CA]
    1  PVPP_HBM_CPU1      A  @S9S_MB_2U_LIB.S9S_MB_2U(SCH_1):PVPP_HBM_CPU1
    2  GND                B  @S9S_MB_2U_LIB.S9S_MB_2U(SCH_1):GND

Q_CAP  I147  C1391  [Q_CAP_C0603-47UF,2.5V,20%,X6S,A]
    1  PVNN_MAIN_CPU1      A  @S9S_MB_2U_LIB.S9S_MB_2U(SCH_1):PVNN_MAIN_CPU1
    2  GND                B  @S9S_MB_2U_LIB.S9S_MB_2U(SCH_1):GND

Q_CAP  I145  C1392  [Q_CAP_C0805-100UF,4V,20%,X6S,CA]
    1  PVPP_HBM_CPU1      A  @S9S_MB_2U_LIB.S9S_MB_2U(SCH_1):PVPP_HBM_CPU1
    2  GND                B  @S9S_MB_2U_LIB.S9S_MB_2U(SCH_1):GND

Q_CAP  I148  C1393  [Q_CAP_C0603-47UF,2.5V,20%,X6S,A]
    1  PVNN_MAIN_CPU1      A  @S9S_MB_2U_LIB.S9S_MB_2U(SCH_1):PVNN_MAIN_CPU1
    2  GND                B  @S9S_MB_2U_LIB.S9S_MB_2U(SCH_1):GND

Q_CAP  I227  C1396  [Q_CAP_C0805-100UF,4V,20%,X6S,CA]
    1  PVPP_HBM_CPU0      A  @S9S_MB_2U_LIB.S9S_MB_2U(SCH_1):PVPP_HBM_CPU0
    2  GND                B  @S9S_MB_2U_LIB.S9S_MB_2U(SCH_1):GND

Q_CAP  I229  C1397  [Q_CAP_C0805-100UF,4V,20%,X6S,CA]
    1  PVPP_HBM_CPU0      A  @S9S_MB_2U_LIB.S9S_MB_2U(SCH_1):PVPP_HBM_CPU0
    2  GND                B  @S9S_MB_2U_LIB.S9S_MB_2U(SCH_1):GND

Q_CAP  I230  C1398  [Q_CAP_C0805-100UF,4V,20%,X6S,CA]
    1  PVPP_HBM_CPU0      A  @S9S_MB_2U_LIB.S9S_MB_2U(SCH_1):PVPP_HBM_CPU0
    2  GND                B  @S9S_MB_2U_LIB.S9S_MB_2U(SCH_1):GND

Q_CAP  I111  C1399  [Q_CAP_C0805-100UF,4V,20%,X6S,CA]
    1  PVNN_MAIN_CPU0      A  @S9S_MB_2U_LIB.S9S_MB_2U(SCH_1):PVNN_MAIN_CPU0
    2  GND                B  @S9S_MB_2U_LIB.S9S_MB_2U(SCH_1):GND

Q_CAP  I112  C1400  [Q_CAP_C0805-100UF,4V,20%,X6S,CA]
    1  PVNN_MAIN_CPU0      A  @S9S_MB_2U_LIB.S9S_MB_2U(SCH_1):PVNN_MAIN_CPU0
    2  GND                B  @S9S_MB_2U_LIB.S9S_MB_2U(SCH_1):GND

Q_CAP  I146  C1403  [Q_CAP_C0805-100UF,4V,20%,X6S,CA]
    1  PVNN_MAIN_CPU1      A  @S9S_MB_2U_LIB.S9S_MB_2U(SCH_1):PVNN_MAIN_CPU1
    2  GND                B  @S9S_MB_2U_LIB.S9S_MB_2U(SCH_1):GND

Q_CAP  I147  C1404  [Q_CAP_C0805-100UF,4V,20%,X6S,CA]
    1  PVNN_MAIN_CPU1      A  @S9S_MB_2U_LIB.S9S_MB_2U(SCH_1):PVNN_MAIN_CPU1
    2  GND                B  @S9S_MB_2U_LIB.S9S_MB_2U(SCH_1):GND

Q_CAP  I238  C1405  [Q_CAP_C0603-47UF,2.5V,20%,X6S,A]
    1  PVNN_MAIN_CPU0      A  @S9S_MB_2U_LIB.S9S_MB_2U(SCH_1):PVNN_MAIN_CPU0
    2  GND                B  @S9S_MB_2U_LIB.S9S_MB_2U(SCH_1):GND

Q_CAP  I239  C1406  [Q_CAP_C0603-47UF,2.5V,20%,X6S,A]
    1  PVNN_MAIN_CPU0      A  @S9S_MB_2U_LIB.S9S_MB_2U(SCH_1):PVNN_MAIN_CPU0
    2  GND                B  @S9S_MB_2U_LIB.S9S_MB_2U(SCH_1):GND

Q_CAP  I240  C1407  [Q_CAP_C0603-47UF,2.5V,20%,X6S,A]
    1  PVNN_MAIN_CPU0      A  @S9S_MB_2U_LIB.S9S_MB_2U(SCH_1):PVNN_MAIN_CPU0
    2  GND                B  @S9S_MB_2U_LIB.S9S_MB_2U(SCH_1):GND

Q_CAP  I206  C1408  [Q_CAP_0402-0.1UF,25V,10%,X7R,CA]
    1  PGPPA_AUX          A  @S9S_MB_2U_LIB.S9S_MB_2U(SCH_1):PGPPA_AUX
    2  GND                B  @S9S_MB_2U_LIB.S9S_MB_2U(SCH_1):GND

Q_CAP  I419  C1409  [Q_CAP_C0603-10UF,6.3V,20%,X6S,A]
    1  P3V3_DB2000_VDD      A  @S9S_MB_2U_LIB.S9S_MB_2U(SCH_1):P3V3_DB2000_VDD
    2  GND                B  @S9S_MB_2U_LIB.S9S_MB_2U(SCH_1):GND

Q_CAP_DIFFBUS  I243  C1420  [Q_CAP_DIFFBUS_C0201-DIFF BUS_0B]
    2  P3E_PCH_M2_RX_DN<3>      2  @S9S_MB_2U_LIB.S9S_MB_2U(SCH_1):P3E_PCH_M2_RX_DN<3>
    1  P3E_PCH_M2_RX_C_DN<3>      1  @S9S_MB_2U_LIB.S9S_MB_2U(SCH_1):P3E_PCH_M2_RX_C_DN<3>

Q_CAP_DIFFBUS  I246  C1421  [Q_CAP_DIFFBUS_C0201-DIFF BUS_0B]
    2  P3E_PCH_M2_RX_DP<3>      2  @S9S_MB_2U_LIB.S9S_MB_2U(SCH_1):P3E_PCH_M2_RX_DP<3>
    1  P3E_PCH_M2_RX_C_DP<3>      1  @S9S_MB_2U_LIB.S9S_MB_2U(SCH_1):P3E_PCH_M2_RX_C_DP<3>

Q_CAP  I101  C1430  [Q_CAP_0402-0.1UF,25V,10%,X7R,CA]
    1  P12V_AUX           A  @S9S_MB_2U_LIB.S9S_MB_2U(SCH_1):P12V_AUX
    2  GND                B  @S9S_MB_2U_LIB.S9S_MB_2U(SCH_1):GND

Q_CAP  I100  C1431  [Q_CAP_C0805-10UF,25V,10%,X6S,CA]
    1  P12V_AUX           A  @S9S_MB_2U_LIB.S9S_MB_2U(SCH_1):P12V_AUX
    2  GND                B  @S9S_MB_2U_LIB.S9S_MB_2U(SCH_1):GND

Q_CAP  I97  C1432  [Q_CAP_0402-0.1UF,25V,10%,X7R,CA]
    1  P12V_FRONT_CPU      A  @S9S_MB_2U_LIB.S9S_MB_2U(SCH_1):P12V_FRONT_CPU
    2  GND                B  @S9S_MB_2U_LIB.S9S_MB_2U(SCH_1):GND

Q_CAP  I98  C1433  [Q_CAP_C0805-10UF,25V,10%,X6S,CA]
    1  P12V_FRONT_CPU      A  @S9S_MB_2U_LIB.S9S_MB_2U(SCH_1):P12V_FRONT_CPU
    2  GND                B  @S9S_MB_2U_LIB.S9S_MB_2U(SCH_1):GND

Q_CAP  I242  C1436  [Q_CAP_C0201-0.22UF,6.3V,10%,X6A]
    1  PVPP_HBM_CPU0      A  @S9S_MB_2U_LIB.S9S_MB_2U(SCH_1):PVPP_HBM_CPU0
    2  GND                B  @S9S_MB_2U_LIB.S9S_MB_2U(SCH_1):GND

Q_CAP  I149  C1437  [Q_CAP_C0201-0.22UF,6.3V,10%,X6A]
    1  PVPP_HBM_CPU1      A  @S9S_MB_2U_LIB.S9S_MB_2U(SCH_1):PVPP_HBM_CPU1
    2  GND                B  @S9S_MB_2U_LIB.S9S_MB_2U(SCH_1):GND

Q_CAP  I49  C1438  [Q_CAP_C0805-22UF,16V,20%,X6S,CA]
    1  P3V3_AUX           A  @S9S_MB_2U_LIB.S9S_MB_2U(SCH_1):P3V3_AUX
    2  GND                B  @S9S_MB_2U_LIB.S9S_MB_2U(SCH_1):GND

Q_CAP  I46  C1439  [Q_CAP_C0805-22UF,16V,20%,X6S,CA]
    1  P12V_REAR_CPU      A  @S9S_MB_2U_LIB.S9S_MB_2U(SCH_1):P12V_REAR_CPU
    2  GND                B  @S9S_MB_2U_LIB.S9S_MB_2U(SCH_1):GND

Q_CAP  I45  C1440  [Q_CAP_0402-0.1UF,25V,10%,X7R,CA]
    1  P12V_REAR_CPU      A  @S9S_MB_2U_LIB.S9S_MB_2U(SCH_1):P12V_REAR_CPU
    2  GND                B  @S9S_MB_2U_LIB.S9S_MB_2U(SCH_1):GND

Q_CAP  I44  C1441  [Q_CAP_0402-0.1UF,25V,10%,X7R,CA]
    1  P12V_REAR_CPU      A  @S9S_MB_2U_LIB.S9S_MB_2U(SCH_1):P12V_REAR_CPU
    2  GND                B  @S9S_MB_2U_LIB.S9S_MB_2U(SCH_1):GND

Q_CAP  I43  C1442  [Q_CAP_0402-0.1UF,25V,10%,X7R,CA]
    1  P12V_REAR_CPU      A  @S9S_MB_2U_LIB.S9S_MB_2U(SCH_1):P12V_REAR_CPU
    2  GND                B  @S9S_MB_2U_LIB.S9S_MB_2U(SCH_1):GND

Q_CAP  I42  C1443  [Q_CAP_0402-0.1UF,25V,10%,X7R,CA]
    1  P12V_REAR_CPU      A  @S9S_MB_2U_LIB.S9S_MB_2U(SCH_1):P12V_REAR_CPU
    2  GND                B  @S9S_MB_2U_LIB.S9S_MB_2U(SCH_1):GND

Q_CAP  I40  C1444  [Q_CAP_0402-0.1UF,25V,10%,X7R,CA]
    1  P12V_REAR_CPU      A  @S9S_MB_2U_LIB.S9S_MB_2U(SCH_1):P12V_REAR_CPU
    2  GND                B  @S9S_MB_2U_LIB.S9S_MB_2U(SCH_1):GND

Q_CAP  I38  C1445  [Q_CAP_C0805-22UF,16V,20%,X6S,CA]
    1  P3V3_AUX           A  @S9S_MB_2U_LIB.S9S_MB_2U(SCH_1):P3V3_AUX
    2  GND                B  @S9S_MB_2U_LIB.S9S_MB_2U(SCH_1):GND

Q_CAP  I37  C1446  [Q_CAP_0402-0.1UF,25V,10%,X7R,CA]
    1  P3V3               A  @S9S_MB_2U_LIB.S9S_MB_2U(SCH_1):P3V3
    2  GND                B  @S9S_MB_2U_LIB.S9S_MB_2U(SCH_1):GND

Q_CAP  I35  C1447  [Q_CAP_0402-0.1UF,25V,10%,X7R,CA]
    1  P3V3               A  @S9S_MB_2U_LIB.S9S_MB_2U(SCH_1):P3V3
    2  GND                B  @S9S_MB_2U_LIB.S9S_MB_2U(SCH_1):GND

Q_CAP  I31  C1448  [Q_CAP_C0805-22UF,16V,20%,X6S,CA]
    1  P3V3_AUX           A  @S9S_MB_2U_LIB.S9S_MB_2U(SCH_1):P3V3_AUX
    2  GND                B  @S9S_MB_2U_LIB.S9S_MB_2U(SCH_1):GND

Q_CAP  I66  C1449  [Q_CAP_C0805-22UF,16V,20%,X6S,CA]
    1  P12V_REAR_CPU      A  @S9S_MB_2U_LIB.S9S_MB_2U(SCH_1):P12V_REAR_CPU
    2  GND                B  @S9S_MB_2U_LIB.S9S_MB_2U(SCH_1):GND

Q_CAP  I65  C1450  [Q_CAP_0402-0.1UF,25V,10%,X7R,CA]
    1  P12V_REAR_CPU      A  @S9S_MB_2U_LIB.S9S_MB_2U(SCH_1):P12V_REAR_CPU
    2  GND                B  @S9S_MB_2U_LIB.S9S_MB_2U(SCH_1):GND

Q_CAP  I64  C1451  [Q_CAP_0402-0.1UF,25V,10%,X7R,CA]
    1  P12V_REAR_CPU      A  @S9S_MB_2U_LIB.S9S_MB_2U(SCH_1):P12V_REAR_CPU
    2  GND                B  @S9S_MB_2U_LIB.S9S_MB_2U(SCH_1):GND

Q_CAP  I63  C1452  [Q_CAP_0402-0.1UF,25V,10%,X7R,CA]
    1  P12V_REAR_CPU      A  @S9S_MB_2U_LIB.S9S_MB_2U(SCH_1):P12V_REAR_CPU
    2  GND                B  @S9S_MB_2U_LIB.S9S_MB_2U(SCH_1):GND

Q_CAP  I62  C1453  [Q_CAP_0402-0.1UF,25V,10%,X7R,CA]
    1  P12V_REAR_CPU      A  @S9S_MB_2U_LIB.S9S_MB_2U(SCH_1):P12V_REAR_CPU
    2  GND                B  @S9S_MB_2U_LIB.S9S_MB_2U(SCH_1):GND

Q_CAP  I60  C1454  [Q_CAP_0402-0.1UF,25V,10%,X7R,CA]
    1  P12V_REAR_CPU      A  @S9S_MB_2U_LIB.S9S_MB_2U(SCH_1):P12V_REAR_CPU
    2  GND                B  @S9S_MB_2U_LIB.S9S_MB_2U(SCH_1):GND

Q_CAP  I58  C1455  [Q_CAP_C0805-22UF,16V,20%,X6S,CA]
    1  P3V3_AUX           A  @S9S_MB_2U_LIB.S9S_MB_2U(SCH_1):P3V3_AUX
    2  GND                B  @S9S_MB_2U_LIB.S9S_MB_2U(SCH_1):GND

Q_CAP  I57  C1456  [Q_CAP_0402-0.1UF,25V,10%,X7R,CA]
    1  P3V3               A  @S9S_MB_2U_LIB.S9S_MB_2U(SCH_1):P3V3
    2  GND                B  @S9S_MB_2U_LIB.S9S_MB_2U(SCH_1):GND

Q_CAP  I55  C1457  [Q_CAP_0402-0.1UF,25V,10%,X7R,CA]
    1  P3V3               A  @S9S_MB_2U_LIB.S9S_MB_2U(SCH_1):P3V3
    2  GND                B  @S9S_MB_2U_LIB.S9S_MB_2U(SCH_1):GND

Q_CAP  I50  C1459  [Q_CAP_C0805-22UF,16V,20%,X6S,CA]
    1  P12V_REAR_CPU      A  @S9S_MB_2U_LIB.S9S_MB_2U(SCH_1):P12V_REAR_CPU
    2  GND                B  @S9S_MB_2U_LIB.S9S_MB_2U(SCH_1):GND

Q_CAP  I52  C1460  [Q_CAP_0402-0.1UF,25V,10%,X7R,CA]
    1  P12V_REAR_CPU      A  @S9S_MB_2U_LIB.S9S_MB_2U(SCH_1):P12V_REAR_CPU
    2  GND                B  @S9S_MB_2U_LIB.S9S_MB_2U(SCH_1):GND

Q_CAP  I53  C1461  [Q_CAP_0402-0.1UF,25V,10%,X7R,CA]
    1  P12V_REAR_CPU      A  @S9S_MB_2U_LIB.S9S_MB_2U(SCH_1):P12V_REAR_CPU
    2  GND                B  @S9S_MB_2U_LIB.S9S_MB_2U(SCH_1):GND

Q_CAP  I63  C1462  [Q_CAP_0402-0.1UF,25V,10%,X7R,CA]
    1  P12V_REAR_CPU      A  @S9S_MB_2U_LIB.S9S_MB_2U(SCH_1):P12V_REAR_CPU
    2  GND                B  @S9S_MB_2U_LIB.S9S_MB_2U(SCH_1):GND

Q_CAP  I64  C1463  [Q_CAP_0402-0.1UF,25V,10%,X7R,CA]
    1  P12V_REAR_CPU      A  @S9S_MB_2U_LIB.S9S_MB_2U(SCH_1):P12V_REAR_CPU
    2  GND                B  @S9S_MB_2U_LIB.S9S_MB_2U(SCH_1):GND

Q_CAP  I66  C1464  [Q_CAP_0402-0.1UF,25V,10%,X7R,CA]
    1  P12V_REAR_CPU      A  @S9S_MB_2U_LIB.S9S_MB_2U(SCH_1):P12V_REAR_CPU
    2  GND                B  @S9S_MB_2U_LIB.S9S_MB_2U(SCH_1):GND

Q_CAP  I68  C1465  [Q_CAP_C0805-22UF,16V,20%,X6S,CA]
    1  P3V3_AUX           A  @S9S_MB_2U_LIB.S9S_MB_2U(SCH_1):P3V3_AUX
    2  GND                B  @S9S_MB_2U_LIB.S9S_MB_2U(SCH_1):GND

Q_CAP  I88  C1466  [Q_CAP_0402-0.1UF,25V,10%,X7R,CA]
    1  P3V3               A  @S9S_MB_2U_LIB.S9S_MB_2U(SCH_1):P3V3
    2  GND                B  @S9S_MB_2U_LIB.S9S_MB_2U(SCH_1):GND

Q_CAP  I90  C1467  [Q_CAP_0402-0.1UF,25V,10%,X7R,CA]
    1  P3V3               A  @S9S_MB_2U_LIB.S9S_MB_2U(SCH_1):P3V3
    2  GND                B  @S9S_MB_2U_LIB.S9S_MB_2U(SCH_1):GND

Q_CAP  I50  C1469  [Q_CAP_C0805-22UF,16V,20%,X6S,CA]
    1  P12V_REAR_CPU      A  @S9S_MB_2U_LIB.S9S_MB_2U(SCH_1):P12V_REAR_CPU
    2  GND                B  @S9S_MB_2U_LIB.S9S_MB_2U(SCH_1):GND

Q_CAP  I52  C1470  [Q_CAP_0402-0.1UF,25V,10%,X7R,CA]
    1  P12V_REAR_CPU      A  @S9S_MB_2U_LIB.S9S_MB_2U(SCH_1):P12V_REAR_CPU
    2  GND                B  @S9S_MB_2U_LIB.S9S_MB_2U(SCH_1):GND

Q_CAP  I54  C1471  [Q_CAP_0402-0.1UF,25V,10%,X7R,CA]
    1  P12V_REAR_CPU      A  @S9S_MB_2U_LIB.S9S_MB_2U(SCH_1):P12V_REAR_CPU
    2  GND                B  @S9S_MB_2U_LIB.S9S_MB_2U(SCH_1):GND

Q_CAP  I55  C1472  [Q_CAP_0402-0.1UF,25V,10%,X7R,CA]
    1  P12V_REAR_CPU      A  @S9S_MB_2U_LIB.S9S_MB_2U(SCH_1):P12V_REAR_CPU
    2  GND                B  @S9S_MB_2U_LIB.S9S_MB_2U(SCH_1):GND

Q_CAP  I57  C1473  [Q_CAP_0402-0.1UF,25V,10%,X7R,CA]
    1  P12V_REAR_CPU      A  @S9S_MB_2U_LIB.S9S_MB_2U(SCH_1):P12V_REAR_CPU
    2  GND                B  @S9S_MB_2U_LIB.S9S_MB_2U(SCH_1):GND

Q_CAP  I58  C1474  [Q_CAP_0402-0.1UF,25V,10%,X7R,CA]
    1  P12V_REAR_CPU      A  @S9S_MB_2U_LIB.S9S_MB_2U(SCH_1):P12V_REAR_CPU
    2  GND                B  @S9S_MB_2U_LIB.S9S_MB_2U(SCH_1):GND

Q_CAP  I87  C1475  [Q_CAP_C0805-22UF,16V,20%,X6S,CA]
    1  P3V3_AUX           A  @S9S_MB_2U_LIB.S9S_MB_2U(SCH_1):P3V3_AUX
    2  GND                B  @S9S_MB_2U_LIB.S9S_MB_2U(SCH_1):GND

Q_CAP  I88  C1476  [Q_CAP_0402-0.1UF,25V,10%,X7R,CA]
    1  P3V3               A  @S9S_MB_2U_LIB.S9S_MB_2U(SCH_1):P3V3
    2  GND                B  @S9S_MB_2U_LIB.S9S_MB_2U(SCH_1):GND

Q_CAP  I91  C1477  [Q_CAP_0402-0.1UF,25V,10%,X7R,CA]
    1  P3V3               A  @S9S_MB_2U_LIB.S9S_MB_2U(SCH_1):P3V3
    2  GND                B  @S9S_MB_2U_LIB.S9S_MB_2U(SCH_1):GND

Q_CAP  I3   C1480  [Q_CAP_C0402-100NF,50V,10%,X7R,A]
    1  P3V3_E1S_2_DVDT      A  @S9S_MB_2U_LIB.S9S_MB_2U(SCH_1):P3V3_E1S_2_DVDT
    2  GND                B  @S9S_MB_2U_LIB.S9S_MB_2U(SCH_1):GND

Q_CAP  I41  C1481  [Q_CAP_0402-0.1UF,25V,10%,X7R,CA]
    1  P3V3_AUX           A  @S9S_MB_2U_LIB.S9S_MB_2U(SCH_1):P3V3_AUX
    2  GND                B  @S9S_MB_2U_LIB.S9S_MB_2U(SCH_1):GND

Q_CAP  I7   C1482  [Q_CAP_0402-0.1UF,25V,10%,X7R,CA]
    1  P3V3_AUX           A  @S9S_MB_2U_LIB.S9S_MB_2U(SCH_1):P3V3_AUX
    2  GND                B  @S9S_MB_2U_LIB.S9S_MB_2U(SCH_1):GND

Q_CAP  I12  C1483  [Q_CAP_C0805-10UF,25V,10%,X6S,CA]
    1  P3V3_E1S_2         A  @S9S_MB_2U_LIB.S9S_MB_2U(SCH_1):P3V3_E1S_2
    2  GND                B  @S9S_MB_2U_LIB.S9S_MB_2U(SCH_1):GND

Q_CAP  I54  C1484  [Q_CAP_C0402-100NF,50V,10%,X7R,A]
    1  P3V3_E1S_1_DVDT      A  @S9S_MB_2U_LIB.S9S_MB_2U(SCH_1):P3V3_E1S_1_DVDT
    2  GND                B  @S9S_MB_2U_LIB.S9S_MB_2U(SCH_1):GND

Q_CAP  I58  C1485  [Q_CAP_0402-0.1UF,25V,10%,X7R,CA]
    1  P3V3_AUX           A  @S9S_MB_2U_LIB.S9S_MB_2U(SCH_1):P3V3_AUX
    2  GND                B  @S9S_MB_2U_LIB.S9S_MB_2U(SCH_1):GND

Q_CAP  I24  C1486  [Q_CAP_0402-0.1UF,25V,10%,X7R,CA]
    1  P3V3_AUX           A  @S9S_MB_2U_LIB.S9S_MB_2U(SCH_1):P3V3_AUX
    2  GND                B  @S9S_MB_2U_LIB.S9S_MB_2U(SCH_1):GND

Q_CAP  I63  C1487  [Q_CAP_C0805-10UF,25V,10%,X6S,CA]
    1  P3V3_E1S_1         A  @S9S_MB_2U_LIB.S9S_MB_2U(SCH_1):P3V3_E1S_1
    2  GND                B  @S9S_MB_2U_LIB.S9S_MB_2U(SCH_1):GND

Q_CAP  I29  C1488  [Q_CAP_C0805-10UF,25V,10%,X6S,CA]
    1  P3V3_E1S_3         A  @S9S_MB_2U_LIB.S9S_MB_2U(SCH_1):P3V3_E1S_3
    2  GND                B  @S9S_MB_2U_LIB.S9S_MB_2U(SCH_1):GND

Q_CAP  I77  C1489  [Q_CAP_C0805-22UF,16V,20%,X6S,CA]
    1  P12V_E1S_1         A  @S9S_MB_2U_LIB.S9S_MB_2U(SCH_1):P12V_E1S_1
    2  GND                B  @S9S_MB_2U_LIB.S9S_MB_2U(SCH_1):GND

Q_CAP  I76  C1490  [Q_CAP_C0805-22UF,16V,20%,X6S,CA]
    1  P12V_E1S_1         A  @S9S_MB_2U_LIB.S9S_MB_2U(SCH_1):P12V_E1S_1
    2  GND                B  @S9S_MB_2U_LIB.S9S_MB_2U(SCH_1):GND

Q_CAP  I47  C1491  [Q_CAP_C0805-22UF,16V,20%,X6S,CA]
    1  P12V_E1S_2         A  @S9S_MB_2U_LIB.S9S_MB_2U(SCH_1):P12V_E1S_2
    2  GND                B  @S9S_MB_2U_LIB.S9S_MB_2U(SCH_1):GND

Q_CAP  I88  C1492  [Q_CAP_C0805-22UF,16V,20%,X6S,CA]
    1  P12V_E1S_3         A  @S9S_MB_2U_LIB.S9S_MB_2U(SCH_1):P12V_E1S_3
    2  GND                B  @S9S_MB_2U_LIB.S9S_MB_2U(SCH_1):GND

Q_CAP  I46  C1493  [Q_CAP_C0805-22UF,16V,20%,X6S,CA]
    1  P12V_E1S_2         A  @S9S_MB_2U_LIB.S9S_MB_2U(SCH_1):P12V_E1S_2
    2  GND                B  @S9S_MB_2U_LIB.S9S_MB_2U(SCH_1):GND

Q_CAP  I86  C1494  [Q_CAP_C0805-22UF,16V,20%,X6S,CA]
    1  P12V_E1S_3         A  @S9S_MB_2U_LIB.S9S_MB_2U(SCH_1):P12V_E1S_3
    2  GND                B  @S9S_MB_2U_LIB.S9S_MB_2U(SCH_1):GND

Q_CAP  I45  C1495  [Q_CAP_0402-0.1UF,25V,10%,X7R,CA]
    1  P12V_E1S_2         A  @S9S_MB_2U_LIB.S9S_MB_2U(SCH_1):P12V_E1S_2
    2  GND                B  @S9S_MB_2U_LIB.S9S_MB_2U(SCH_1):GND

Q_CAP  I85  C1496  [Q_CAP_0402-0.1UF,25V,10%,X7R,CA]
    1  P12V_E1S_3         A  @S9S_MB_2U_LIB.S9S_MB_2U(SCH_1):P12V_E1S_3
    2  GND                B  @S9S_MB_2U_LIB.S9S_MB_2U(SCH_1):GND

Q_CAP  I13  C1497  [Q_CAP_0402-0.1UF,25V,10%,X7R,CA]
    1  P12V_E1S_2         A  @S9S_MB_2U_LIB.S9S_MB_2U(SCH_1):P12V_E1S_2
    2  GND                B  @S9S_MB_2U_LIB.S9S_MB_2U(SCH_1):GND

Q_CAP  I27  C1498  [Q_CAP_0402-0.1UF,25V,10%,X7R,CA]
    1  P12V_E1S_3         A  @S9S_MB_2U_LIB.S9S_MB_2U(SCH_1):P12V_E1S_3
    2  GND                B  @S9S_MB_2U_LIB.S9S_MB_2U(SCH_1):GND

Q_CAP  I8   C1499  [Q_CAP_0402-0.1UF,25V,10%,X7R,CA]
    1  P3V3_E1S_2         A  @S9S_MB_2U_LIB.S9S_MB_2U(SCH_1):P3V3_E1S_2
    2  GND                B  @S9S_MB_2U_LIB.S9S_MB_2U(SCH_1):GND

Q_CAP  I25  C1500  [Q_CAP_0402-0.1UF,25V,10%,X7R,CA]
    1  P3V3_E1S_3         A  @S9S_MB_2U_LIB.S9S_MB_2U(SCH_1):P3V3_E1S_3
    2  GND                B  @S9S_MB_2U_LIB.S9S_MB_2U(SCH_1):GND

Q_CAP  I6   C1501  [Q_CAP_0402-0.1UF,25V,10%,X7R,CA]
    1  P3V3_E1S_2         A  @S9S_MB_2U_LIB.S9S_MB_2U(SCH_1):P3V3_E1S_2
    2  GND                B  @S9S_MB_2U_LIB.S9S_MB_2U(SCH_1):GND

Q_CAP  I23  C1502  [Q_CAP_0402-0.1UF,25V,10%,X7R,CA]
    1  P3V3_E1S_3         A  @S9S_MB_2U_LIB.S9S_MB_2U(SCH_1):P3V3_E1S_3
    2  GND                B  @S9S_MB_2U_LIB.S9S_MB_2U(SCH_1):GND

Q_CAP  I160  C1503  [Q_CAP_C0402-0.047UF,25V,10%,X7A]
    1  P12V_E1S_0_DVDT      A  @S9S_MB_2U_LIB.S9S_MB_2U(SCH_1):P12V_E1S_0_DVDT
    2  GND                B  @S9S_MB_2U_LIB.S9S_MB_2U(SCH_1):GND

Q_CAP  I161  C1504  [Q_CAP_C0402-0.047UF,25V,10%,X7A]
    1  P12V_E1S_2_DVDT      A  @S9S_MB_2U_LIB.S9S_MB_2U(SCH_1):P12V_E1S_2_DVDT
    2  GND                B  @S9S_MB_2U_LIB.S9S_MB_2U(SCH_1):GND

Q_CAP  I127  C1505  [Q_CAP_0402-0.1UF,25V,10%,X7R,CA]
    1  P12V_FRONT_CPU      A  @S9S_MB_2U_LIB.S9S_MB_2U(SCH_1):P12V_FRONT_CPU
    2  GND                B  @S9S_MB_2U_LIB.S9S_MB_2U(SCH_1):GND

Q_CAP  I164  C1506  [Q_CAP_C0805-10UF,25V,10%,X6S,CA]
    1  P12V_E1S_0         A  @S9S_MB_2U_LIB.S9S_MB_2U(SCH_1):P12V_E1S_0
    2  GND                B  @S9S_MB_2U_LIB.S9S_MB_2U(SCH_1):GND

Q_CAP  I10  C1507  [Q_CAP_0402-27PF  ,50V ,5% ,NPOA]
    1  XTAL_PCH_RTC2_R      A  @S9S_MB_2U_LIB.S9S_MB_2U(SCH_1):XTAL_PCH_RTC2_R
    2  GND                B  @S9S_MB_2U_LIB.S9S_MB_2U(SCH_1):GND

Q_CAP  I17  C1508  [Q_CAP_0402-27PF  ,50V ,5% ,NPOA]
    1  XTAL_PCH_RTC1      A  @S9S_MB_2U_LIB.S9S_MB_2U(SCH_1):XTAL_PCH_RTC1
    2  GND                B  @S9S_MB_2U_LIB.S9S_MB_2U(SCH_1):GND

Q_CAP  I123  C1509  [Q_CAP_C0805-10UF,25V,10%,X6S,CA]
    1  P12V_E1S_2         A  @S9S_MB_2U_LIB.S9S_MB_2U(SCH_1):P12V_E1S_2
    2  GND                B  @S9S_MB_2U_LIB.S9S_MB_2U(SCH_1):GND

Q_CAP  I162  C1510  [Q_CAP_C0402-0.047UF,25V,10%,X7A]
    1  P12V_E1S_1_DVDT      A  @S9S_MB_2U_LIB.S9S_MB_2U(SCH_1):P12V_E1S_1_DVDT
    2  GND                B  @S9S_MB_2U_LIB.S9S_MB_2U(SCH_1):GND

Q_CAP  I163  C1511  [Q_CAP_C0402-0.047UF,25V,10%,X7A]
    1  P12V_E1S_3_DVDT      A  @S9S_MB_2U_LIB.S9S_MB_2U(SCH_1):P12V_E1S_3_DVDT
    2  GND                B  @S9S_MB_2U_LIB.S9S_MB_2U(SCH_1):GND

Q_CAP  I108  C1512  [Q_CAP_0402-0.1UF,25V,10%,X7R,CA]
    1  P12V_FRONT_CPU      A  @S9S_MB_2U_LIB.S9S_MB_2U(SCH_1):P12V_FRONT_CPU
    2  GND                B  @S9S_MB_2U_LIB.S9S_MB_2U(SCH_1):GND

Q_CAP  I144  C1513  [Q_CAP_0402-0.1UF,25V,10%,X7R,CA]
    1  P12V_FRONT_CPU      A  @S9S_MB_2U_LIB.S9S_MB_2U(SCH_1):P12V_FRONT_CPU
    2  GND                B  @S9S_MB_2U_LIB.S9S_MB_2U(SCH_1):GND

Q_CAP  I114  C1514  [Q_CAP_C0805-10UF,25V,10%,X6S,CA]
    1  P12V_E1S_1         A  @S9S_MB_2U_LIB.S9S_MB_2U(SCH_1):P12V_E1S_1
    2  GND                B  @S9S_MB_2U_LIB.S9S_MB_2U(SCH_1):GND

Q_CAP  I140  C1515  [Q_CAP_C0805-10UF,25V,10%,X6S,CA]
    1  P12V_E1S_3         A  @S9S_MB_2U_LIB.S9S_MB_2U(SCH_1):P12V_E1S_3
    2  GND                B  @S9S_MB_2U_LIB.S9S_MB_2U(SCH_1):GND

Q_CAP_DIFFBUS  I302  C1516  [Q_CAP_DIFFBUS_C0201-DIFF BUS_0A]
    2  P5E_CPU1_PE3_TX_DN<15>      2  @S9S_MB_2U_LIB.S9S_MB_2U(SCH_1):P5E_CPU1_PE3_TX_DN<15>
    1  P5E_CPU1_PE3_TX_C_DN<15>      1  @S9S_MB_2U_LIB.S9S_MB_2U(SCH_1):P5E_CPU1_PE3_TX_C_DN<15>

Q_CAP_DIFFBUS  I301  C1517  [Q_CAP_DIFFBUS_C0201-DIFF BUS_0A]
    2  P5E_CPU1_PE3_TX_DP<15>      2  @S9S_MB_2U_LIB.S9S_MB_2U(SCH_1):P5E_CPU1_PE3_TX_DP<15>
    1  P5E_CPU1_PE3_TX_C_DP<15>      1  @S9S_MB_2U_LIB.S9S_MB_2U(SCH_1):P5E_CPU1_PE3_TX_C_DP<15>

Q_CAP_DIFFBUS  I300  C1518  [Q_CAP_DIFFBUS_C0201-DIFF BUS_0A]
    2  P5E_CPU1_PE3_TX_DN<14>      2  @S9S_MB_2U_LIB.S9S_MB_2U(SCH_1):P5E_CPU1_PE3_TX_DN<14>
    1  P5E_CPU1_PE3_TX_C_DN<14>      1  @S9S_MB_2U_LIB.S9S_MB_2U(SCH_1):P5E_CPU1_PE3_TX_C_DN<14>

Q_CAP_DIFFBUS  I299  C1519  [Q_CAP_DIFFBUS_C0201-DIFF BUS_0A]
    2  P5E_CPU1_PE3_TX_DP<14>      2  @S9S_MB_2U_LIB.S9S_MB_2U(SCH_1):P5E_CPU1_PE3_TX_DP<14>
    1  P5E_CPU1_PE3_TX_C_DP<14>      1  @S9S_MB_2U_LIB.S9S_MB_2U(SCH_1):P5E_CPU1_PE3_TX_C_DP<14>

Q_CAP_DIFFBUS  I297  C1520  [Q_CAP_DIFFBUS_C0201-DIFF BUS_0A]
    2  P5E_CPU1_PE3_TX_DN<13>      2  @S9S_MB_2U_LIB.S9S_MB_2U(SCH_1):P5E_CPU1_PE3_TX_DN<13>
    1  P5E_CPU1_PE3_TX_C_DN<13>      1  @S9S_MB_2U_LIB.S9S_MB_2U(SCH_1):P5E_CPU1_PE3_TX_C_DN<13>

Q_CAP_DIFFBUS  I298  C1521  [Q_CAP_DIFFBUS_C0201-DIFF BUS_0A]
    2  P5E_CPU1_PE3_TX_DP<13>      2  @S9S_MB_2U_LIB.S9S_MB_2U(SCH_1):P5E_CPU1_PE3_TX_DP<13>
    1  P5E_CPU1_PE3_TX_C_DP<13>      1  @S9S_MB_2U_LIB.S9S_MB_2U(SCH_1):P5E_CPU1_PE3_TX_C_DP<13>

Q_CAP_DIFFBUS  I286  C1522  [Q_CAP_DIFFBUS_C0201-DIFF BUS_0A]
    2  P5E_CPU1_PE3_TX_DN<12>      2  @S9S_MB_2U_LIB.S9S_MB_2U(SCH_1):P5E_CPU1_PE3_TX_DN<12>
    1  P5E_CPU1_PE3_TX_C_DN<12>      1  @S9S_MB_2U_LIB.S9S_MB_2U(SCH_1):P5E_CPU1_PE3_TX_C_DN<12>

Q_CAP_DIFFBUS  I285  C1523  [Q_CAP_DIFFBUS_C0201-DIFF BUS_0A]
    2  P5E_CPU1_PE3_TX_DP<12>      2  @S9S_MB_2U_LIB.S9S_MB_2U(SCH_1):P5E_CPU1_PE3_TX_DP<12>
    1  P5E_CPU1_PE3_TX_C_DP<12>      1  @S9S_MB_2U_LIB.S9S_MB_2U(SCH_1):P5E_CPU1_PE3_TX_C_DP<12>

Q_CAP_DIFFBUS  I284  C1524  [Q_CAP_DIFFBUS_C0201-DIFF BUS_0A]
    2  P5E_CPU1_PE3_TX_DN<11>      2  @S9S_MB_2U_LIB.S9S_MB_2U(SCH_1):P5E_CPU1_PE3_TX_DN<11>
    1  P5E_CPU1_PE3_TX_C_DN<11>      1  @S9S_MB_2U_LIB.S9S_MB_2U(SCH_1):P5E_CPU1_PE3_TX_C_DN<11>

Q_CAP_DIFFBUS  I283  C1525  [Q_CAP_DIFFBUS_C0201-DIFF BUS_0A]
    2  P5E_CPU1_PE3_TX_DP<11>      2  @S9S_MB_2U_LIB.S9S_MB_2U(SCH_1):P5E_CPU1_PE3_TX_DP<11>
    1  P5E_CPU1_PE3_TX_C_DP<11>      1  @S9S_MB_2U_LIB.S9S_MB_2U(SCH_1):P5E_CPU1_PE3_TX_C_DP<11>

Q_CAP_DIFFBUS  I282  C1526  [Q_CAP_DIFFBUS_C0201-DIFF BUS_0A]
    2  P5E_CPU1_PE3_TX_DN<10>      2  @S9S_MB_2U_LIB.S9S_MB_2U(SCH_1):P5E_CPU1_PE3_TX_DN<10>
    1  P5E_CPU1_PE3_TX_C_DN<10>      1  @S9S_MB_2U_LIB.S9S_MB_2U(SCH_1):P5E_CPU1_PE3_TX_C_DN<10>

Q_CAP_DIFFBUS  I281  C1527  [Q_CAP_DIFFBUS_C0201-DIFF BUS_0A]
    2  P5E_CPU1_PE3_TX_DP<10>      2  @S9S_MB_2U_LIB.S9S_MB_2U(SCH_1):P5E_CPU1_PE3_TX_DP<10>
    1  P5E_CPU1_PE3_TX_C_DP<10>      1  @S9S_MB_2U_LIB.S9S_MB_2U(SCH_1):P5E_CPU1_PE3_TX_C_DP<10>

Q_CAP_DIFFBUS  I280  C1528  [Q_CAP_DIFFBUS_C0201-DIFF BUS_0A]
    2  P5E_CPU1_PE3_TX_DN<9>      2  @S9S_MB_2U_LIB.S9S_MB_2U(SCH_1):P5E_CPU1_PE3_TX_DN<9>
    1  P5E_CPU1_PE3_TX_C_DN<9>      1  @S9S_MB_2U_LIB.S9S_MB_2U(SCH_1):P5E_CPU1_PE3_TX_C_DN<9>

Q_CAP_DIFFBUS  I279  C1529  [Q_CAP_DIFFBUS_C0201-DIFF BUS_0A]
    2  P5E_CPU1_PE3_TX_DP<9>      2  @S9S_MB_2U_LIB.S9S_MB_2U(SCH_1):P5E_CPU1_PE3_TX_DP<9>
    1  P5E_CPU1_PE3_TX_C_DP<9>      1  @S9S_MB_2U_LIB.S9S_MB_2U(SCH_1):P5E_CPU1_PE3_TX_C_DP<9>

Q_CAP_DIFFBUS  I277  C1530  [Q_CAP_DIFFBUS_C0201-DIFF BUS_0A]
    2  P5E_CPU1_PE3_TX_DN<8>      2  @S9S_MB_2U_LIB.S9S_MB_2U(SCH_1):P5E_CPU1_PE3_TX_DN<8>
    1  P5E_CPU1_PE3_TX_C_DN<8>      1  @S9S_MB_2U_LIB.S9S_MB_2U(SCH_1):P5E_CPU1_PE3_TX_C_DN<8>

Q_CAP_DIFFBUS  I278  C1531  [Q_CAP_DIFFBUS_C0201-DIFF BUS_0A]
    2  P5E_CPU1_PE3_TX_DP<8>      2  @S9S_MB_2U_LIB.S9S_MB_2U(SCH_1):P5E_CPU1_PE3_TX_DP<8>
    1  P5E_CPU1_PE3_TX_C_DP<8>      1  @S9S_MB_2U_LIB.S9S_MB_2U(SCH_1):P5E_CPU1_PE3_TX_C_DP<8>

Q_CAP_DIFFBUS  I254  C1532  [Q_CAP_DIFFBUS_C0201-DIFF BUS_0A]
    2  P5E_CPU1_PE3_TX_DN<7>      2  @S9S_MB_2U_LIB.S9S_MB_2U(SCH_1):P5E_CPU1_PE3_TX_DN<7>
    1  P5E_CPU1_PE3_TX_C_DN<7>      1  @S9S_MB_2U_LIB.S9S_MB_2U(SCH_1):P5E_CPU1_PE3_TX_C_DN<7>

Q_CAP_DIFFBUS  I253  C1533  [Q_CAP_DIFFBUS_C0201-DIFF BUS_0A]
    2  P5E_CPU1_PE3_TX_DP<7>      2  @S9S_MB_2U_LIB.S9S_MB_2U(SCH_1):P5E_CPU1_PE3_TX_DP<7>
    1  P5E_CPU1_PE3_TX_C_DP<7>      1  @S9S_MB_2U_LIB.S9S_MB_2U(SCH_1):P5E_CPU1_PE3_TX_C_DP<7>

Q_CAP_DIFFBUS  I251  C1534  [Q_CAP_DIFFBUS_C0201-DIFF BUS_0A]
    2  P5E_CPU1_PE3_TX_DN<6>      2  @S9S_MB_2U_LIB.S9S_MB_2U(SCH_1):P5E_CPU1_PE3_TX_DN<6>
    1  P5E_CPU1_PE3_TX_C_DN<6>      1  @S9S_MB_2U_LIB.S9S_MB_2U(SCH_1):P5E_CPU1_PE3_TX_C_DN<6>

Q_CAP_DIFFBUS  I252  C1535  [Q_CAP_DIFFBUS_C0201-DIFF BUS_0A]
    2  P5E_CPU1_PE3_TX_DP<6>      2  @S9S_MB_2U_LIB.S9S_MB_2U(SCH_1):P5E_CPU1_PE3_TX_DP<6>
    1  P5E_CPU1_PE3_TX_C_DP<6>      1  @S9S_MB_2U_LIB.S9S_MB_2U(SCH_1):P5E_CPU1_PE3_TX_C_DP<6>

Q_CAP_DIFFBUS  I250  C1536  [Q_CAP_DIFFBUS_C0201-DIFF BUS_0A]
    2  P5E_CPU1_PE3_TX_DN<5>      2  @S9S_MB_2U_LIB.S9S_MB_2U(SCH_1):P5E_CPU1_PE3_TX_DN<5>
    1  P5E_CPU1_PE3_TX_C_DN<5>      1  @S9S_MB_2U_LIB.S9S_MB_2U(SCH_1):P5E_CPU1_PE3_TX_C_DN<5>

Q_CAP_DIFFBUS  I249  C1537  [Q_CAP_DIFFBUS_C0201-DIFF BUS_0A]
    2  P5E_CPU1_PE3_TX_DP<5>      2  @S9S_MB_2U_LIB.S9S_MB_2U(SCH_1):P5E_CPU1_PE3_TX_DP<5>
    1  P5E_CPU1_PE3_TX_C_DP<5>      1  @S9S_MB_2U_LIB.S9S_MB_2U(SCH_1):P5E_CPU1_PE3_TX_C_DP<5>

Q_CAP_DIFFBUS  I238  C1538  [Q_CAP_DIFFBUS_C0201-DIFF BUS_0A]
    2  P5E_CPU1_PE3_TX_DN<4>      2  @S9S_MB_2U_LIB.S9S_MB_2U(SCH_1):P5E_CPU1_PE3_TX_DN<4>
    1  P5E_CPU1_PE3_TX_C_DN<4>      1  @S9S_MB_2U_LIB.S9S_MB_2U(SCH_1):P5E_CPU1_PE3_TX_C_DN<4>

Q_CAP_DIFFBUS  I237  C1539  [Q_CAP_DIFFBUS_C0201-DIFF BUS_0A]
    2  P5E_CPU1_PE3_TX_DP<4>      2  @S9S_MB_2U_LIB.S9S_MB_2U(SCH_1):P5E_CPU1_PE3_TX_DP<4>
    1  P5E_CPU1_PE3_TX_C_DP<4>      1  @S9S_MB_2U_LIB.S9S_MB_2U(SCH_1):P5E_CPU1_PE3_TX_C_DP<4>

Q_CAP_DIFFBUS  I236  C1540  [Q_CAP_DIFFBUS_C0201-DIFF BUS_0A]
    2  P5E_CPU1_PE3_TX_DN<3>      2  @S9S_MB_2U_LIB.S9S_MB_2U(SCH_1):P5E_CPU1_PE3_TX_DN<3>
    1  P5E_CPU1_PE3_TX_C_DN<3>      1  @S9S_MB_2U_LIB.S9S_MB_2U(SCH_1):P5E_CPU1_PE3_TX_C_DN<3>

Q_CAP_DIFFBUS  I235  C1541  [Q_CAP_DIFFBUS_C0201-DIFF BUS_0A]
    2  P5E_CPU1_PE3_TX_DP<3>      2  @S9S_MB_2U_LIB.S9S_MB_2U(SCH_1):P5E_CPU1_PE3_TX_DP<3>
    1  P5E_CPU1_PE3_TX_C_DP<3>      1  @S9S_MB_2U_LIB.S9S_MB_2U(SCH_1):P5E_CPU1_PE3_TX_C_DP<3>

Q_CAP_DIFFBUS  I233  C1542  [Q_CAP_DIFFBUS_C0201-DIFF BUS_0A]
    2  P5E_CPU1_PE3_TX_DN<2>      2  @S9S_MB_2U_LIB.S9S_MB_2U(SCH_1):P5E_CPU1_PE3_TX_DN<2>
    1  P5E_CPU1_PE3_TX_C_DN<2>      1  @S9S_MB_2U_LIB.S9S_MB_2U(SCH_1):P5E_CPU1_PE3_TX_C_DN<2>

Q_CAP_DIFFBUS  I234  C1543  [Q_CAP_DIFFBUS_C0201-DIFF BUS_0A]
    2  P5E_CPU1_PE3_TX_DP<2>      2  @S9S_MB_2U_LIB.S9S_MB_2U(SCH_1):P5E_CPU1_PE3_TX_DP<2>
    1  P5E_CPU1_PE3_TX_C_DP<2>      1  @S9S_MB_2U_LIB.S9S_MB_2U(SCH_1):P5E_CPU1_PE3_TX_C_DP<2>

Q_CAP_DIFFBUS  I232  C1544  [Q_CAP_DIFFBUS_C0201-DIFF BUS_0A]
    2  P5E_CPU1_PE3_TX_DN<1>      2  @S9S_MB_2U_LIB.S9S_MB_2U(SCH_1):P5E_CPU1_PE3_TX_DN<1>
    1  P5E_CPU1_PE3_TX_C_DN<1>      1  @S9S_MB_2U_LIB.S9S_MB_2U(SCH_1):P5E_CPU1_PE3_TX_C_DN<1>

Q_CAP_DIFFBUS  I231  C1545  [Q_CAP_DIFFBUS_C0201-DIFF BUS_0A]
    2  P5E_CPU1_PE3_TX_DP<1>      2  @S9S_MB_2U_LIB.S9S_MB_2U(SCH_1):P5E_CPU1_PE3_TX_DP<1>
    1  P5E_CPU1_PE3_TX_C_DP<1>      1  @S9S_MB_2U_LIB.S9S_MB_2U(SCH_1):P5E_CPU1_PE3_TX_C_DP<1>

Q_CAP_DIFFBUS  I230  C1546  [Q_CAP_DIFFBUS_C0201-DIFF BUS_0A]
    2  P5E_CPU1_PE3_TX_DN<0>      2  @S9S_MB_2U_LIB.S9S_MB_2U(SCH_1):P5E_CPU1_PE3_TX_DN<0>
    1  P5E_CPU1_PE3_TX_C_DN<0>      1  @S9S_MB_2U_LIB.S9S_MB_2U(SCH_1):P5E_CPU1_PE3_TX_C_DN<0>

Q_CAP_DIFFBUS  I229  C1547  [Q_CAP_DIFFBUS_C0201-DIFF BUS_0A]
    2  P5E_CPU1_PE3_TX_DP<0>      2  @S9S_MB_2U_LIB.S9S_MB_2U(SCH_1):P5E_CPU1_PE3_TX_DP<0>
    1  P5E_CPU1_PE3_TX_C_DP<0>      1  @S9S_MB_2U_LIB.S9S_MB_2U(SCH_1):P5E_CPU1_PE3_TX_C_DP<0>

Q_CAP_DIFFBUS  I273  C1548  [Q_CAP_DIFFBUS_C0201-DIFF BUS_0A]
    2  P5E_CPU0_PE4_TX_DN<15>      2  @S9S_MB_2U_LIB.S9S_MB_2U(SCH_1):P5E_CPU0_PE4_TX_DN<15>
    1  P5E_CPU0_PE4_TX_C_DN<15>      1  @S9S_MB_2U_LIB.S9S_MB_2U(SCH_1):P5E_CPU0_PE4_TX_C_DN<15>

Q_CAP_DIFFBUS  I274  C1549  [Q_CAP_DIFFBUS_C0201-DIFF BUS_0A]
    2  P5E_CPU0_PE4_TX_DP<15>      2  @S9S_MB_2U_LIB.S9S_MB_2U(SCH_1):P5E_CPU0_PE4_TX_DP<15>
    1  P5E_CPU0_PE4_TX_C_DP<15>      1  @S9S_MB_2U_LIB.S9S_MB_2U(SCH_1):P5E_CPU0_PE4_TX_C_DP<15>

Q_CAP_DIFFBUS  I272  C1550  [Q_CAP_DIFFBUS_C0201-DIFF BUS_0A]
    2  P5E_CPU0_PE4_TX_DN<14>      2  @S9S_MB_2U_LIB.S9S_MB_2U(SCH_1):P5E_CPU0_PE4_TX_DN<14>
    1  P5E_CPU0_PE4_TX_C_DN<14>      1  @S9S_MB_2U_LIB.S9S_MB_2U(SCH_1):P5E_CPU0_PE4_TX_C_DN<14>

Q_CAP_DIFFBUS  I271  C1551  [Q_CAP_DIFFBUS_C0201-DIFF BUS_0A]
    2  P5E_CPU0_PE4_TX_DP<14>      2  @S9S_MB_2U_LIB.S9S_MB_2U(SCH_1):P5E_CPU0_PE4_TX_DP<14>
    1  P5E_CPU0_PE4_TX_C_DP<14>      1  @S9S_MB_2U_LIB.S9S_MB_2U(SCH_1):P5E_CPU0_PE4_TX_C_DP<14>

Q_CAP_DIFFBUS  I270  C1552  [Q_CAP_DIFFBUS_C0201-DIFF BUS_0A]
    2  P5E_CPU0_PE4_TX_DN<13>      2  @S9S_MB_2U_LIB.S9S_MB_2U(SCH_1):P5E_CPU0_PE4_TX_DN<13>
    1  P5E_CPU0_PE4_TX_C_DN<13>      1  @S9S_MB_2U_LIB.S9S_MB_2U(SCH_1):P5E_CPU0_PE4_TX_C_DN<13>

Q_CAP_DIFFBUS  I269  C1553  [Q_CAP_DIFFBUS_C0201-DIFF BUS_0A]
    2  P5E_CPU0_PE4_TX_DP<13>      2  @S9S_MB_2U_LIB.S9S_MB_2U(SCH_1):P5E_CPU0_PE4_TX_DP<13>
    1  P5E_CPU0_PE4_TX_C_DP<13>      1  @S9S_MB_2U_LIB.S9S_MB_2U(SCH_1):P5E_CPU0_PE4_TX_C_DP<13>

Q_CAP_DIFFBUS  I268  C1554  [Q_CAP_DIFFBUS_C0201-DIFF BUS_0A]
    2  P5E_CPU0_PE4_TX_DN<12>      2  @S9S_MB_2U_LIB.S9S_MB_2U(SCH_1):P5E_CPU0_PE4_TX_DN<12>
    1  P5E_CPU0_PE4_TX_C_DN<12>      1  @S9S_MB_2U_LIB.S9S_MB_2U(SCH_1):P5E_CPU0_PE4_TX_C_DN<12>

Q_CAP_DIFFBUS  I267  C1555  [Q_CAP_DIFFBUS_C0201-DIFF BUS_0A]
    2  P5E_CPU0_PE4_TX_DP<12>      2  @S9S_MB_2U_LIB.S9S_MB_2U(SCH_1):P5E_CPU0_PE4_TX_DP<12>
    1  P5E_CPU0_PE4_TX_C_DP<12>      1  @S9S_MB_2U_LIB.S9S_MB_2U(SCH_1):P5E_CPU0_PE4_TX_C_DP<12>

Q_CAP_DIFFBUS  I265  C1556  [Q_CAP_DIFFBUS_C0201-DIFF BUS_0A]
    2  P5E_CPU0_PE4_TX_DN<11>      2  @S9S_MB_2U_LIB.S9S_MB_2U(SCH_1):P5E_CPU0_PE4_TX_DN<11>
    1  P5E_CPU0_PE4_TX_C_DN<11>      1  @S9S_MB_2U_LIB.S9S_MB_2U(SCH_1):P5E_CPU0_PE4_TX_C_DN<11>

Q_CAP_DIFFBUS  I266  C1557  [Q_CAP_DIFFBUS_C0201-DIFF BUS_0A]
    2  P5E_CPU0_PE4_TX_DP<11>      2  @S9S_MB_2U_LIB.S9S_MB_2U(SCH_1):P5E_CPU0_PE4_TX_DP<11>
    1  P5E_CPU0_PE4_TX_C_DP<11>      1  @S9S_MB_2U_LIB.S9S_MB_2U(SCH_1):P5E_CPU0_PE4_TX_C_DP<11>

Q_CAP_DIFFBUS  I264  C1558  [Q_CAP_DIFFBUS_C0201-DIFF BUS_0A]
    2  P5E_CPU0_PE4_TX_DN<10>      2  @S9S_MB_2U_LIB.S9S_MB_2U(SCH_1):P5E_CPU0_PE4_TX_DN<10>
    1  P5E_CPU0_PE4_TX_C_DN<10>      1  @S9S_MB_2U_LIB.S9S_MB_2U(SCH_1):P5E_CPU0_PE4_TX_C_DN<10>

Q_CAP_DIFFBUS  I263  C1559  [Q_CAP_DIFFBUS_C0201-DIFF BUS_0A]
    2  P5E_CPU0_PE4_TX_DP<10>      2  @S9S_MB_2U_LIB.S9S_MB_2U(SCH_1):P5E_CPU0_PE4_TX_DP<10>
    1  P5E_CPU0_PE4_TX_C_DP<10>      1  @S9S_MB_2U_LIB.S9S_MB_2U(SCH_1):P5E_CPU0_PE4_TX_C_DP<10>

Q_CAP_DIFFBUS  I262  C1560  [Q_CAP_DIFFBUS_C0201-DIFF BUS_0A]
    2  P5E_CPU0_PE4_TX_DN<9>      2  @S9S_MB_2U_LIB.S9S_MB_2U(SCH_1):P5E_CPU0_PE4_TX_DN<9>
    1  P5E_CPU0_PE4_TX_C_DN<9>      1  @S9S_MB_2U_LIB.S9S_MB_2U(SCH_1):P5E_CPU0_PE4_TX_C_DN<9>

Q_CAP_DIFFBUS  I261  C1561  [Q_CAP_DIFFBUS_C0201-DIFF BUS_0A]
    2  P5E_CPU0_PE4_TX_DP<9>      2  @S9S_MB_2U_LIB.S9S_MB_2U(SCH_1):P5E_CPU0_PE4_TX_DP<9>
    1  P5E_CPU0_PE4_TX_C_DP<9>      1  @S9S_MB_2U_LIB.S9S_MB_2U(SCH_1):P5E_CPU0_PE4_TX_C_DP<9>

Q_CAP_DIFFBUS  I260  C1562  [Q_CAP_DIFFBUS_C0201-DIFF BUS_0A]
    2  P5E_CPU0_PE4_TX_DN<8>      2  @S9S_MB_2U_LIB.S9S_MB_2U(SCH_1):P5E_CPU0_PE4_TX_DN<8>
    1  P5E_CPU0_PE4_TX_C_DN<8>      1  @S9S_MB_2U_LIB.S9S_MB_2U(SCH_1):P5E_CPU0_PE4_TX_C_DN<8>

Q_CAP_DIFFBUS  I259  C1563  [Q_CAP_DIFFBUS_C0201-DIFF BUS_0A]
    2  P5E_CPU0_PE4_TX_DP<8>      2  @S9S_MB_2U_LIB.S9S_MB_2U(SCH_1):P5E_CPU0_PE4_TX_DP<8>
    1  P5E_CPU0_PE4_TX_C_DP<8>      1  @S9S_MB_2U_LIB.S9S_MB_2U(SCH_1):P5E_CPU0_PE4_TX_C_DP<8>

Q_CAP_DIFFBUS  I242  C1564  [Q_CAP_DIFFBUS_C0201-DIFF BUS_0A]
    2  P5E_CPU0_PE4_TX_DN<7>      2  @S9S_MB_2U_LIB.S9S_MB_2U(SCH_1):P5E_CPU0_PE4_TX_DN<7>
    1  P5E_CPU0_PE4_TX_C_DN<7>      1  @S9S_MB_2U_LIB.S9S_MB_2U(SCH_1):P5E_CPU0_PE4_TX_C_DN<7>

Q_CAP_DIFFBUS  I241  C1565  [Q_CAP_DIFFBUS_C0201-DIFF BUS_0A]
    2  P5E_CPU0_PE4_TX_DP<7>      2  @S9S_MB_2U_LIB.S9S_MB_2U(SCH_1):P5E_CPU0_PE4_TX_DP<7>
    1  P5E_CPU0_PE4_TX_C_DP<7>      1  @S9S_MB_2U_LIB.S9S_MB_2U(SCH_1):P5E_CPU0_PE4_TX_C_DP<7>

Q_CAP_DIFFBUS  I240  C1566  [Q_CAP_DIFFBUS_C0201-DIFF BUS_0A]
    2  P5E_CPU0_PE4_TX_DN<6>      2  @S9S_MB_2U_LIB.S9S_MB_2U(SCH_1):P5E_CPU0_PE4_TX_DN<6>
    1  P5E_CPU0_PE4_TX_C_DN<6>      1  @S9S_MB_2U_LIB.S9S_MB_2U(SCH_1):P5E_CPU0_PE4_TX_C_DN<6>

Q_CAP_DIFFBUS  I239  C1567  [Q_CAP_DIFFBUS_C0201-DIFF BUS_0A]
    2  P5E_CPU0_PE4_TX_DP<6>      2  @S9S_MB_2U_LIB.S9S_MB_2U(SCH_1):P5E_CPU0_PE4_TX_DP<6>
    1  P5E_CPU0_PE4_TX_C_DP<6>      1  @S9S_MB_2U_LIB.S9S_MB_2U(SCH_1):P5E_CPU0_PE4_TX_C_DP<6>

Q_CAP_DIFFBUS  I238  C1568  [Q_CAP_DIFFBUS_C0201-DIFF BUS_0A]
    2  P5E_CPU0_PE4_TX_DN<5>      2  @S9S_MB_2U_LIB.S9S_MB_2U(SCH_1):P5E_CPU0_PE4_TX_DN<5>
    1  P5E_CPU0_PE4_TX_C_DN<5>      1  @S9S_MB_2U_LIB.S9S_MB_2U(SCH_1):P5E_CPU0_PE4_TX_C_DN<5>

Q_CAP_DIFFBUS  I237  C1569  [Q_CAP_DIFFBUS_C0201-DIFF BUS_0A]
    2  P5E_CPU0_PE4_TX_DP<5>      2  @S9S_MB_2U_LIB.S9S_MB_2U(SCH_1):P5E_CPU0_PE4_TX_DP<5>
    1  P5E_CPU0_PE4_TX_C_DP<5>      1  @S9S_MB_2U_LIB.S9S_MB_2U(SCH_1):P5E_CPU0_PE4_TX_C_DP<5>

Q_CAP_DIFFBUS  I235  C1570  [Q_CAP_DIFFBUS_C0201-DIFF BUS_0A]
    2  P5E_CPU0_PE4_TX_DN<4>      2  @S9S_MB_2U_LIB.S9S_MB_2U(SCH_1):P5E_CPU0_PE4_TX_DN<4>
    1  P5E_CPU0_PE4_TX_C_DN<4>      1  @S9S_MB_2U_LIB.S9S_MB_2U(SCH_1):P5E_CPU0_PE4_TX_C_DN<4>

Q_CAP_DIFFBUS  I236  C1571  [Q_CAP_DIFFBUS_C0201-DIFF BUS_0A]
    2  P5E_CPU0_PE4_TX_DP<4>      2  @S9S_MB_2U_LIB.S9S_MB_2U(SCH_1):P5E_CPU0_PE4_TX_DP<4>
    1  P5E_CPU0_PE4_TX_C_DP<4>      1  @S9S_MB_2U_LIB.S9S_MB_2U(SCH_1):P5E_CPU0_PE4_TX_C_DP<4>

Q_CAP_DIFFBUS  I234  C1572  [Q_CAP_DIFFBUS_C0201-DIFF BUS_0A]
    2  P5E_CPU0_PE4_TX_DN<3>      2  @S9S_MB_2U_LIB.S9S_MB_2U(SCH_1):P5E_CPU0_PE4_TX_DN<3>
    1  P5E_CPU0_PE4_TX_C_DN<3>      1  @S9S_MB_2U_LIB.S9S_MB_2U(SCH_1):P5E_CPU0_PE4_TX_C_DN<3>

Q_CAP_DIFFBUS  I233  C1573  [Q_CAP_DIFFBUS_C0201-DIFF BUS_0A]
    2  P5E_CPU0_PE4_TX_DP<3>      2  @S9S_MB_2U_LIB.S9S_MB_2U(SCH_1):P5E_CPU0_PE4_TX_DP<3>
    1  P5E_CPU0_PE4_TX_C_DP<3>      1  @S9S_MB_2U_LIB.S9S_MB_2U(SCH_1):P5E_CPU0_PE4_TX_C_DP<3>

Q_CAP_DIFFBUS  I232  C1574  [Q_CAP_DIFFBUS_C0201-DIFF BUS_0A]
    2  P5E_CPU0_PE4_TX_DN<2>      2  @S9S_MB_2U_LIB.S9S_MB_2U(SCH_1):P5E_CPU0_PE4_TX_DN<2>
    1  P5E_CPU0_PE4_TX_C_DN<2>      1  @S9S_MB_2U_LIB.S9S_MB_2U(SCH_1):P5E_CPU0_PE4_TX_C_DN<2>

Q_CAP_DIFFBUS  I231  C1575  [Q_CAP_DIFFBUS_C0201-DIFF BUS_0A]
    2  P5E_CPU0_PE4_TX_DP<2>      2  @S9S_MB_2U_LIB.S9S_MB_2U(SCH_1):P5E_CPU0_PE4_TX_DP<2>
    1  P5E_CPU0_PE4_TX_C_DP<2>      1  @S9S_MB_2U_LIB.S9S_MB_2U(SCH_1):P5E_CPU0_PE4_TX_C_DP<2>

Q_CAP_DIFFBUS  I312  C1576  [Q_CAP_DIFFBUS_C0201-DIFF BUS_0A]
    2  P5E_CPU0_PE4_TX_DN<1>      2  @S9S_MB_2U_LIB.S9S_MB_2U(SCH_1):P5E_CPU0_PE4_TX_DN<1>
    1  P5E_CPU0_PE4_TX_C_DN<1>      1  @S9S_MB_2U_LIB.S9S_MB_2U(SCH_1):P5E_CPU0_PE4_TX_C_DN<1>

Q_CAP_DIFFBUS  I311  C1577  [Q_CAP_DIFFBUS_C0201-DIFF BUS_0A]
    2  P5E_CPU0_PE4_TX_DP<1>      2  @S9S_MB_2U_LIB.S9S_MB_2U(SCH_1):P5E_CPU0_PE4_TX_DP<1>
    1  P5E_CPU0_PE4_TX_C_DP<1>      1  @S9S_MB_2U_LIB.S9S_MB_2U(SCH_1):P5E_CPU0_PE4_TX_C_DP<1>

Q_CAP_DIFFBUS  I230  C1578  [Q_CAP_DIFFBUS_C0201-DIFF BUS_0A]
    2  P5E_CPU0_PE4_TX_DN<0>      2  @S9S_MB_2U_LIB.S9S_MB_2U(SCH_1):P5E_CPU0_PE4_TX_DN<0>
    1  P5E_CPU0_PE4_TX_C_DN<0>      1  @S9S_MB_2U_LIB.S9S_MB_2U(SCH_1):P5E_CPU0_PE4_TX_C_DN<0>

Q_CAP_DIFFBUS  I229  C1579  [Q_CAP_DIFFBUS_C0201-DIFF BUS_0A]
    2  P5E_CPU0_PE4_TX_DP<0>      2  @S9S_MB_2U_LIB.S9S_MB_2U(SCH_1):P5E_CPU0_PE4_TX_DP<0>
    1  P5E_CPU0_PE4_TX_C_DP<0>      1  @S9S_MB_2U_LIB.S9S_MB_2U(SCH_1):P5E_CPU0_PE4_TX_C_DP<0>

Q_CAP  I120  C1580  [Q_CAP_0402-1NF,50V,10%,X7R,CH2A]
    1  MP5981_0_CLREF      A  @S9S_MB_2U_LIB.S9S_MB_2U(SCH_1):MP5981_0_CLREF
    2  GND                B  @S9S_MB_2U_LIB.S9S_MB_2U(SCH_1):GND

Q_CAP  I124  C1581  [Q_CAP_C0402-1UF,25V,10%,EMPTY,A]
    1  VDD3               A  @S9S_MB_2U_LIB.S9S_MB_2U(SCH_1):VDD3
    2  GND                B  @S9S_MB_2U_LIB.S9S_MB_2U(SCH_1):GND

Q_CAP  I142  C1582  [Q_CAP_C0402-100NF,50V,10%,X7R,A]
    1  MP5981_0_ON_PD      A  @S9S_MB_2U_LIB.S9S_MB_2U(SCH_1):MP5981_0_ON_PD
    2  GND                B  @S9S_MB_2U_LIB.S9S_MB_2U(SCH_1):GND

Q_CAP  I140  C1583  [Q_CAP_C0402-100NF,50V,10%,X7R,A]
    1  MPS5981_SS         A  @S9S_MB_2U_LIB.S9S_MB_2U(SCH_1):MPS5981_SS
    2  GND                B  @S9S_MB_2U_LIB.S9S_MB_2U(SCH_1):GND

Q_CAP  I68  C1584  [Q_CAP_C0402-100NF,50V,10%,X7R,A]
    1  MP5981_1_ON_PD      A  @S9S_MB_2U_LIB.S9S_MB_2U(SCH_1):MP5981_1_ON_PD
    2  GND                B  @S9S_MB_2U_LIB.S9S_MB_2U(SCH_1):GND

Q_CAP  I105  C1585  [Q_CAP_0402-1NF,50V,10%,X7R,CH2A]
    1  MP5981_1_CLREF      A  @S9S_MB_2U_LIB.S9S_MB_2U(SCH_1):MP5981_1_CLREF
    2  GND                B  @S9S_MB_2U_LIB.S9S_MB_2U(SCH_1):GND

Q_CAP  I91  C1586  [Q_CAP_C0402-100NF,50V,10%,X7R,A]
    1  MPS5981_1_SS       A  @S9S_MB_2U_LIB.S9S_MB_2U(SCH_1):MPS5981_1_SS
    2  GND                B  @S9S_MB_2U_LIB.S9S_MB_2U(SCH_1):GND

Q_CAP  I99  C1587  [Q_CAP_C0402-1UF,25V,10%,EMPTY,A]
    1  VDD3               A  @S9S_MB_2U_LIB.S9S_MB_2U(SCH_1):VDD3
    2  GND                B  @S9S_MB_2U_LIB.S9S_MB_2U(SCH_1):GND

Q_CAP  I39  C1588  [Q_CAP_0402-0.1UF,25V,10%,X7R,CA]
    1  P3V3_AUX           A  @S9S_MB_2U_LIB.S9S_MB_2U(SCH_1):P3V3_AUX
    2  GND                B  @S9S_MB_2U_LIB.S9S_MB_2U(SCH_1):GND

Q_CAP  I62  C1589  [Q_CAP_0402-0.1UF,25V,10%,X7R,CA]
    1  P3V3_AUX           A  @S9S_MB_2U_LIB.S9S_MB_2U(SCH_1):P3V3_AUX
    2  GND                B  @S9S_MB_2U_LIB.S9S_MB_2U(SCH_1):GND

Q_CAP  I82  C1590  [Q_CAP_0402-0.1UF,25V,10%,X7R,CA]
    1  P3V3_AUX           A  @S9S_MB_2U_LIB.S9S_MB_2U(SCH_1):P3V3_AUX
    2  GND                B  @S9S_MB_2U_LIB.S9S_MB_2U(SCH_1):GND

Q_CAP  I89  C1591  [Q_CAP_0402-0.1UF,25V,10%,X7R,CA]
    1  P3V3_AUX           A  @S9S_MB_2U_LIB.S9S_MB_2U(SCH_1):P3V3_AUX
    2  GND                B  @S9S_MB_2U_LIB.S9S_MB_2U(SCH_1):GND

Q_CAP  I2   C1592  [Q_CAP_0402-0.1UF,25V,10%,X7R,CA]
    1  P3V3_AUX           A  @S9S_MB_2U_LIB.S9S_MB_2U(SCH_1):P3V3_AUX
    2  GND                B  @S9S_MB_2U_LIB.S9S_MB_2U(SCH_1):GND

Q_CAP  I22  C1593  [Q_CAP_0402-0.1UF,25V,10%,X7R,CA]
    1  P3V3_AUX           A  @S9S_MB_2U_LIB.S9S_MB_2U(SCH_1):P3V3_AUX
    2  GND                B  @S9S_MB_2U_LIB.S9S_MB_2U(SCH_1):GND

Q_CAP  I39  C1594  [Q_CAP_0402-0.1UF,25V,10%,X7R,CA]
    1  P3V3_AUX           A  @S9S_MB_2U_LIB.S9S_MB_2U(SCH_1):P3V3_AUX
    2  GND                B  @S9S_MB_2U_LIB.S9S_MB_2U(SCH_1):GND

Q_CAP  I44  C1595  [Q_CAP_0402-0.1UF,25V,10%,X7R,CA]
    1  P3V3_AUX           A  @S9S_MB_2U_LIB.S9S_MB_2U(SCH_1):P3V3_AUX
    2  GND                B  @S9S_MB_2U_LIB.S9S_MB_2U(SCH_1):GND

Q_CAP  I46  C1596  [Q_CAP_C0402-0.047UF,25V,10%,X7A]
    1  P12V_SCM_DVDT      A  @S9S_MB_2U_LIB.S9S_MB_2U(SCH_1):P12V_SCM_DVDT
    2  GND                B  @S9S_MB_2U_LIB.S9S_MB_2U(SCH_1):GND

Q_CAP  I47  C1597  [Q_CAP_0402-0.1UF,25V,10%,X7R,CA]
    1  P12V_AUX           A  @S9S_MB_2U_LIB.S9S_MB_2U(SCH_1):P12V_AUX
    2  GND                B  @S9S_MB_2U_LIB.S9S_MB_2U(SCH_1):GND

Q_CAP  I48  C1598  [Q_CAP_C0805-10UF,25V,10%,X6S,CA]
    1  P12V_SCM           A  @S9S_MB_2U_LIB.S9S_MB_2U(SCH_1):P12V_SCM
    2  GND                B  @S9S_MB_2U_LIB.S9S_MB_2U(SCH_1):GND

Q_CAP  I41  C1599  [Q_CAP_C0805-22UF,10V,20%,X6S,CA]
    1  P3V3_AUX           A  @S9S_MB_2U_LIB.S9S_MB_2U(SCH_1):P3V3_AUX
    2  GND                B  @S9S_MB_2U_LIB.S9S_MB_2U(SCH_1):GND

Q_CAP  I44  C1600  [Q_CAP_C0805-22UF,10V,20%,X6S,CA]
    1  P3V3_AUX           A  @S9S_MB_2U_LIB.S9S_MB_2U(SCH_1):P3V3_AUX
    2  GND                B  @S9S_MB_2U_LIB.S9S_MB_2U(SCH_1):GND

Q_CAPP  I138  C1601  [Q_CAPP_SMLF-100UF,16V,20%,POSCA]
    1  P12V_FRONT_CPU      A  @S9S_MB_2U_LIB.S9S_MB_2U(SCH_1):P12V_FRONT_CPU
    2  GND                B  @S9S_MB_2U_LIB.S9S_MB_2U(SCH_1):GND

Q_CAP  I139  C1602  [Q_CAP_0402-0.1UF,25V,10%,X7R,CA]
    1  P12V_FRONT_CPU      A  @S9S_MB_2U_LIB.S9S_MB_2U(SCH_1):P12V_FRONT_CPU
    2  GND                B  @S9S_MB_2U_LIB.S9S_MB_2U(SCH_1):GND

Q_CAPP  I140  C1603  [Q_CAPP_SMLF-100UF,16V,20%,POSCA]
    1  P3V3               A  @S9S_MB_2U_LIB.S9S_MB_2U(SCH_1):P3V3
    2  GND                B  @S9S_MB_2U_LIB.S9S_MB_2U(SCH_1):GND

Q_CAP  I141  C1604  [Q_CAP_0402-0.1UF,25V,10%,X7R,CA]
    1  P3V3               A  @S9S_MB_2U_LIB.S9S_MB_2U(SCH_1):P3V3
    2  GND                B  @S9S_MB_2U_LIB.S9S_MB_2U(SCH_1):GND

Q_CAP  I142  C1605  [Q_CAP_C0402-1UF,25V,10%,X6S,CHA]
    1  P3V3_AUX           A  @S9S_MB_2U_LIB.S9S_MB_2U(SCH_1):P3V3_AUX
    2  GND                B  @S9S_MB_2U_LIB.S9S_MB_2U(SCH_1):GND

Q_CAP  I143  C1606  [Q_CAP_0402-0.1UF,25V,10%,X7R,CA]
    1  P3V3_AUX           A  @S9S_MB_2U_LIB.S9S_MB_2U(SCH_1):P3V3_AUX
    2  GND                B  @S9S_MB_2U_LIB.S9S_MB_2U(SCH_1):GND

Q_CAP  I105  C1607  [Q_CAP_0402-0.1UF,25V,10%,X7R,CA]
    1  P3V3_AUX           A  @S9S_MB_2U_LIB.S9S_MB_2U(SCH_1):P3V3_AUX
    2  GND                B  @S9S_MB_2U_LIB.S9S_MB_2U(SCH_1):GND

Q_CAP  I20  C2443  [Q_CAP_C0402-10UF,6.3V,20%,X6S,A]
    1  PVNN_TERM_CPU0      A  @S9S_MB_2U_LIB.S9S_MB_2U(SCH_1):PVNN_TERM_CPU0
    2  GND                B  @S9S_MB_2U_LIB.S9S_MB_2U(SCH_1):GND

Q_CAP  I24  C2444  [Q_CAP_0402-0.1UF,25V,10%,X7R,CA]
    1  PVNN_TERM_CPU0      A  @S9S_MB_2U_LIB.S9S_MB_2U(SCH_1):PVNN_TERM_CPU0
    2  GND                B  @S9S_MB_2U_LIB.S9S_MB_2U(SCH_1):GND

Q_CAP  I11  C2445  [Q_CAP_0402-1000PF,50V,5%,EMPTYA]
    2  GND                B  @S9S_MB_2U_LIB.S9S_MB_2U(SCH_1):GND
    1  FM_PVPP_HBM_CPU1_EN      A  @S9S_MB_2U_LIB.S9S_MB_2U(SCH_1):FM_PVPP_HBM_CPU1_EN

Q_CAP  I39  C2446  [Q_CAP_0402-1000PF,50V,5%,X7R,TA]
    1  PWRGD_PVPP_HBM_CPU1_R      A  @S9S_MB_2U_LIB.S9S_MB_2U(SCH_1):PWRGD_PVPP_HBM_CPU1_R
    2  GND                B  @S9S_MB_2U_LIB.S9S_MB_2U(SCH_1):GND

Q_LED  I239  D0     [Q_LED_SMLF-LED_GREEN,19-213/GVA]
    A  PU_PLD_HEARTBEAT_LVC3      A  @S9S_MB_2U_LIB.S9S_MB_2U(SCH_1):PU_PLD_HEARTBEAT_LVC3
    C  FM_PLD_HEARTBEAT_LVC3_D      C  @S9S_MB_2U_LIB.S9S_MB_2U(SCH_1):FM_PLD_HEARTBEAT_LVC3_D

SCHOTTKY_AC  I370  D4     [SCHOTTKY_AC-SX34F,SMLF,IC,BC00A]
    C  P12V_OCP_SFF       C  @S9S_MB_2U_LIB.S9S_MB_2U(SCH_1):P12V_OCP_SFF
    A  GND                A  @S9S_MB_2U_LIB.S9S_MB_2U(SCH_1):GND

Q_LED  I248  D6     [Q_LED_SMLF-LED_RED,19-217/R6C-A]
    A  LED_CPU_RMCA_CATERR      A  @S9S_MB_2U_LIB.S9S_MB_2U(SCH_1):LED_CPU_RMCA_CATERR
    C  GND                C  @S9S_MB_2U_LIB.S9S_MB_2U(SCH_1):GND

BAT547F  I69  D7     [BAT547F-BAT547F,SMLF,IC,BC0BATA]
    3  P5V                3  @S9S_MB_2U_LIB.S9S_MB_2U(SCH_1):P5V
    1  P3V3               1  @S9S_MB_2U_LIB.S9S_MB_2U(SCH_1):P3V3

DIODE_TVS  I174  D8     [DIODE_TVS-SMF14A,SMLF,IC,BCSMFA]
    C  P12V_FRONT_CPU      C  @S9S_MB_2U_LIB.S9S_MB_2U(SCH_1):P12V_FRONT_CPU
    A  GND                A  @S9S_MB_2U_LIB.S9S_MB_2U(SCH_1):GND

DIODE_TVS  I177  D9     [DIODE_TVS-SMF14A,SMLF,IC,BCSMFA]
    C  P12V_FRONT_CPU      C  @S9S_MB_2U_LIB.S9S_MB_2U(SCH_1):P12V_FRONT_CPU
    A  GND                A  @S9S_MB_2U_LIB.S9S_MB_2U(SCH_1):GND

DIODE_TVS  I181  D10    [DIODE_TVS-SMF14A,SMLF,IC,BCSMFA]
    C  P12V_FRONT_CPU      C  @S9S_MB_2U_LIB.S9S_MB_2U(SCH_1):P12V_FRONT_CPU
    A  GND                A  @S9S_MB_2U_LIB.S9S_MB_2U(SCH_1):GND

DIODE_TVS  I179  D11    [DIODE_TVS-SMF14A,SMLF,IC,BCSMFA]
    C  P12V_FRONT_CPU      C  @S9S_MB_2U_LIB.S9S_MB_2U(SCH_1):P12V_FRONT_CPU
    A  GND                A  @S9S_MB_2U_LIB.S9S_MB_2U(SCH_1):GND

DIODE_TVS  I45  D12    [DIODE_TVS-SMF14A,SMLF,IC,BCSMFA]
    C  P12V_AUX           C  @S9S_MB_2U_LIB.S9S_MB_2U(SCH_1):P12V_AUX
    A  GND                A  @S9S_MB_2U_LIB.S9S_MB_2U(SCH_1):GND

TDR_3P_TH2  I1   DB1    [TDR_3P_TH2-EMPTY,N_A]
    1  T_GND            GND  @S9S_MB_2U_LIB.S9S_MB_2U(SCH_1):T_GND
    3  TDR_SE_40_OHM_TOP    IO2  @S9S_MB_2U_LIB.S9S_MB_2U(SCH_1):TDR_SE_40_OHM_TOP
    2  TDR_SE_40_OHM_TOP    IO1  @S9S_MB_2U_LIB.S9S_MB_2U(SCH_1):TDR_SE_40_OHM_TOP

TDR_3P_TH2  I3   DB2    [TDR_3P_TH2-EMPTY,N_A]
    1  T_GND            GND  @S9S_MB_2U_LIB.S9S_MB_2U(SCH_1):T_GND
    3  TDR_SE_40_OHM_IN1    IO2  @S9S_MB_2U_LIB.S9S_MB_2U(SCH_1):TDR_SE_40_OHM_IN1
    2  TDR_SE_40_OHM_IN1    IO1  @S9S_MB_2U_LIB.S9S_MB_2U(SCH_1):TDR_SE_40_OHM_IN1

TDR_3P_TH2  I5   DB3    [TDR_3P_TH2-EMPTY,N_A]
    1  T_GND            GND  @S9S_MB_2U_LIB.S9S_MB_2U(SCH_1):T_GND
    3  TDR_SE_40_OHM_IN2    IO2  @S9S_MB_2U_LIB.S9S_MB_2U(SCH_1):TDR_SE_40_OHM_IN2
    2  TDR_SE_40_OHM_IN2    IO1  @S9S_MB_2U_LIB.S9S_MB_2U(SCH_1):TDR_SE_40_OHM_IN2

TDR_3P_TH2  I9   DB4    [TDR_3P_TH2-EMPTY,N_A]
    1  T_GND            GND  @S9S_MB_2U_LIB.S9S_MB_2U(SCH_1):T_GND
    3  TDR_SE_40_OHM_IN3    IO2  @S9S_MB_2U_LIB.S9S_MB_2U(SCH_1):TDR_SE_40_OHM_IN3
    2  TDR_SE_40_OHM_IN3    IO1  @S9S_MB_2U_LIB.S9S_MB_2U(SCH_1):TDR_SE_40_OHM_IN3

TDR_3P_TH2  I12  DB5    [TDR_3P_TH2-EMPTY,N_A]
    1  T_GND            GND  @S9S_MB_2U_LIB.S9S_MB_2U(SCH_1):T_GND
    3  TDR_SE_40_OHM_IN4    IO2  @S9S_MB_2U_LIB.S9S_MB_2U(SCH_1):TDR_SE_40_OHM_IN4
    2  TDR_SE_40_OHM_IN4    IO1  @S9S_MB_2U_LIB.S9S_MB_2U(SCH_1):TDR_SE_40_OHM_IN4

TDR_3P_TH2  I7   DB6    [TDR_3P_TH2-EMPTY,N_A]
    1  T_GND            GND  @S9S_MB_2U_LIB.S9S_MB_2U(SCH_1):T_GND
    3  TDR_SE_40_OHM_BOT    IO2  @S9S_MB_2U_LIB.S9S_MB_2U(SCH_1):TDR_SE_40_OHM_BOT
    2  TDR_SE_40_OHM_BOT    IO1  @S9S_MB_2U_LIB.S9S_MB_2U(SCH_1):TDR_SE_40_OHM_BOT

TDR_3P_TH2  I86  DB7    [TDR_3P_TH2-EMPTY,N_A]
    1  T_GND            GND  @S9S_MB_2U_LIB.S9S_MB_2U(SCH_1):T_GND
    3  TDR_SE_50_OHM_TOP    IO2  @S9S_MB_2U_LIB.S9S_MB_2U(SCH_1):TDR_SE_50_OHM_TOP
    2  TDR_SE_50_OHM_TOP    IO1  @S9S_MB_2U_LIB.S9S_MB_2U(SCH_1):TDR_SE_50_OHM_TOP

TDR_3P_TH2  I87  DB8    [TDR_3P_TH2-EMPTY,N_A]
    1  T_GND            GND  @S9S_MB_2U_LIB.S9S_MB_2U(SCH_1):T_GND
    3  TDR_SE_50_OHM_IN1    IO2  @S9S_MB_2U_LIB.S9S_MB_2U(SCH_1):TDR_SE_50_OHM_IN1
    2  TDR_SE_50_OHM_IN1    IO1  @S9S_MB_2U_LIB.S9S_MB_2U(SCH_1):TDR_SE_50_OHM_IN1

TDR_3P_TH2  I88  DB9    [TDR_3P_TH2-EMPTY,N_A]
    1  T_GND            GND  @S9S_MB_2U_LIB.S9S_MB_2U(SCH_1):T_GND
    3  TDR_SE_50_OHM_IN2    IO2  @S9S_MB_2U_LIB.S9S_MB_2U(SCH_1):TDR_SE_50_OHM_IN2
    2  TDR_SE_50_OHM_IN2    IO1  @S9S_MB_2U_LIB.S9S_MB_2U(SCH_1):TDR_SE_50_OHM_IN2

TDR_3P_TH2  I92  DB10   [TDR_3P_TH2-EMPTY,N_A]
    1  T_GND            GND  @S9S_MB_2U_LIB.S9S_MB_2U(SCH_1):T_GND
    3  TDR_SE_50_OHM_IN3    IO2  @S9S_MB_2U_LIB.S9S_MB_2U(SCH_1):TDR_SE_50_OHM_IN3
    2  TDR_SE_50_OHM_IN3    IO1  @S9S_MB_2U_LIB.S9S_MB_2U(SCH_1):TDR_SE_50_OHM_IN3

TDR_3P_TH2  I93  DB11   [TDR_3P_TH2-EMPTY,N_A]
    1  T_GND            GND  @S9S_MB_2U_LIB.S9S_MB_2U(SCH_1):T_GND
    3  TDR_SE_50_OHM_IN4    IO2  @S9S_MB_2U_LIB.S9S_MB_2U(SCH_1):TDR_SE_50_OHM_IN4
    2  TDR_SE_50_OHM_IN4    IO1  @S9S_MB_2U_LIB.S9S_MB_2U(SCH_1):TDR_SE_50_OHM_IN4

TDR_3P_TH2  I85  DB12   [TDR_3P_TH2-EMPTY,N_A]
    1  T_GND            GND  @S9S_MB_2U_LIB.S9S_MB_2U(SCH_1):T_GND
    3  TDR_SE_50_OHM_BOT    IO2  @S9S_MB_2U_LIB.S9S_MB_2U(SCH_1):TDR_SE_50_OHM_BOT
    2  TDR_SE_50_OHM_BOT    IO1  @S9S_MB_2U_LIB.S9S_MB_2U(SCH_1):TDR_SE_50_OHM_BOT

DUMMY_SYMBOL  I15  DM4    [DUMMY_SYMBOL-WEEE,MECH,EMPTY,DA]
    1  NC                 1  NC

DUMMY_SYMBOL  I14  DM7    [DUMMY_SYMBOL-PB-E1_SMALL,MECH,A]
    1  NC                 1  NC

DUMMY_SYMBOL  I18  DM8    [DUMMY_SYMBOL-EFI BIOS LABEL,MEA]
    1  NC                 1  NC

DUMMY_SYMBOL  I17  DM9    [DUMMY_SYMBOL-MECHANIC_SYMBOL,MA]
    1  NC                 1  NC

DUMMY_SYMBOL  I8   DM10   [DUMMY_SYMBOL-PCBA_LABEL_15X5,MA]
    1  NC                 1  NC

DUMMY_SYMBOL  I13  DM13   [DUMMY_SYMBOL-BATTERY_SYMBOL,MEA]
    1  NC                 1  NC

DUMMY_SYMBOL  I6   DM14   [DUMMY_SYMBOL-BARCODE,MECH,EMPTA]
    1  NC                 1  NC

DUMMY_SYMBOL  I5   DM15   [DUMMY_SYMBOL-BARCODE,MECH,EMPTA]
    1  NC                 1  NC

DUMMY_SYMBOL  I1   DM16   [DUMMY_SYMBOL-PCB_VENDOR_LOGO_1A]
    1  NC                 1  NC

HOLE  I12  H1     [HOLE_TH-EMPTY,HOLE1087]
    1  GND                1  @S9S_MB_2U_LIB.S9S_MB_2U(SCH_1):GND

HOLE  I14  H2     [HOLE_TH-EMPTY,HOLE1087]
    1  GND                1  @S9S_MB_2U_LIB.S9S_MB_2U(SCH_1):GND

HOLE  I11  H3     [HOLE_TH-EMPTY,HOLE1087]
    1  GND                1  @S9S_MB_2U_LIB.S9S_MB_2U(SCH_1):GND

HOLE  I13  H4     [HOLE_TH-EMPTY,HOLE1087]
    1  GND                1  @S9S_MB_2U_LIB.S9S_MB_2U(SCH_1):GND

HOLE  I9   H5     [HOLE_TH-EMPTY,HOLE1087]
    1  GND                1  @S9S_MB_2U_LIB.S9S_MB_2U(SCH_1):GND

HOLE  I10  H6     [HOLE_TH-EMPTY,HOLE1087]
    1  GND                1  @S9S_MB_2U_LIB.S9S_MB_2U(SCH_1):GND

HOLE  I7   H7     [HOLE_TH-EMPTY,HOLE1087]
    1  GND                1  @S9S_MB_2U_LIB.S9S_MB_2U(SCH_1):GND

HOLE  I8   H8     [HOLE_TH-EMPTY,HOLE1087]
    1  GND                1  @S9S_MB_2U_LIB.S9S_MB_2U(SCH_1):GND

HOLE  I5   H9     [HOLE_TH-EMPTY,HOLE1087]
    1  GND                1  @S9S_MB_2U_LIB.S9S_MB_2U(SCH_1):GND

HOLE  I6   H10    [HOLE_TH-EMPTY,HOLE1087]
    1  GND                1  @S9S_MB_2U_LIB.S9S_MB_2U(SCH_1):GND

HOLE  I3   H11    [HOLE_TH-EMPTY,HOLE1087]
    1  GND                1  @S9S_MB_2U_LIB.S9S_MB_2U(SCH_1):GND

HOLE  I4   H12    [HOLE_TH-EMPTY,HOLE1087]
    1  GND                1  @S9S_MB_2U_LIB.S9S_MB_2U(SCH_1):GND

HOLE  I2   H13    [HOLE_TH-EMPTY,HOLE1087]
    1  GND                1  @S9S_MB_2U_LIB.S9S_MB_2U(SCH_1):GND

HOLE  I15  H15    [HOLE_TH-EMPTY,HOLE1079]
    1  NC                 1  NC

HOLE  I21  H16    [HOLE_TH-EMPTY,HOLE1079]
    1  NC                 1  NC

HOLE  I16  H17    [HOLE_TH-EMPTY,HOLE1079]
    1  NC                 1  NC

HOLE  I22  H18    [HOLE_TH-EMPTY,HOLE1079]
    1  NC                 1  NC

HOLE  I18  H19    [HOLE_TH-EMPTY,HOLE1079]
    1  NC                 1  NC

HOLE  I26  H20    [HOLE_TH-EMPTY,HOLE1079]
    1  NC                 1  NC

HOLE  I17  H21    [HOLE_TH-EMPTY,HOLE1079]
    1  NC                 1  NC

HOLE  I25  H22    [HOLE_TH-EMPTY,HOLE1079]
    1  NC                 1  NC

HOLE  I19  H23    [HOLE_TH-EMPTY,HOLE1079]
    1  NC                 1  NC

HOLE  I24  H24    [HOLE_TH-EMPTY,HOLE1079]
    1  NC                 1  NC

HOLE  I20  H25    [HOLE_TH-EMPTY,HOLE1079]
    1  NC                 1  NC

HOLE  I23  H26    [HOLE_TH-EMPTY,HOLE1079]
    1  NC                 1  NC

HOLE  I27  H27    [HOLE_TH-EMPTY,DUMMY50]
    1  NC                 1  NC

HOLE  I28  H28    [HOLE_TH-EMPTY,DUMMY50]
    1  NC                 1  NC

HOLE  I30  H29    [HOLE_TH-EMPTY,DUMMY50]
    1  NC                 1  NC

HOLE  I29  H30    [HOLE_TH-EMPTY,DUMMY50]
    1  NC                 1  NC

HOLE  I31  H31    [HOLE_TH-EMPTY,HOLE1214]
    1  GND                1  @S9S_MB_2U_LIB.S9S_MB_2U(SCH_1):GND

HOLE  I32  H32    [HOLE_TH-EMPTY,HOLE1214]
    1  GND                1  @S9S_MB_2U_LIB.S9S_MB_2U(SCH_1):GND

HOLE  I33  H33    [HOLE_TH-EMPTY,HOLE491]
    1  NC                 1  NC

HOLE  I34  H34    [HOLE_TH-EMPTY,HOLE491]
    1  NC                 1  NC

HOLE  I35  H35    [HOLE_TH-EMPTY,HOLE1098]
    1  GND                1  @S9S_MB_2U_LIB.S9S_MB_2U(SCH_1):GND

HOLE  I37  H36    [HOLE_TH-EMPTY,TMP-Q_HOLE78]
    1  NC                 1  NC

HOLE  I36  H37    [HOLE_TH-EMPTY,HOLE1098]
    1  GND                1  @S9S_MB_2U_LIB.S9S_MB_2U(SCH_1):GND

HOLE  I38  H38    [HOLE_TH-EMPTY,TMP-Q_HOLE78]
    1  NC                 1  NC

HOLE  I41  H39    [HOLE_TH-EMPTY,HOLE1222]
    1  GND                1  @S9S_MB_2U_LIB.S9S_MB_2U(SCH_1):GND

HOLE  I43  H40    [HOLE_TH-EMPTY,HOLE1222]
    1  GND                1  @S9S_MB_2U_LIB.S9S_MB_2U(SCH_1):GND

HOLE  I45  H41    [HOLE_TH-EMPTY,HOLE1068]
    1  NC                 1  NC

HOLE  I46  H42    [HOLE_TH-EMPTY,HOLE1068]
    1  NC                 1  NC

HOLE  I47  H43    [HOLE_TH-EMPTY,HOLE1068]
    1  NC                 1  NC

HOLE  I49  H44    [HOLE_TH-EMPTY,HOLE1212]
    1  GND                1  @S9S_MB_2U_LIB.S9S_MB_2U(SCH_1):GND

HOLE  I48  H45    [HOLE_TH-EMPTY,HOLE1212]
    1  GND                1  @S9S_MB_2U_LIB.S9S_MB_2U(SCH_1):GND

HOLE  I52  H47    [HOLE_TH-EMPTY,HOLE1212]
    1  GND                1  @S9S_MB_2U_LIB.S9S_MB_2U(SCH_1):GND

HOLE  I53  H49    [HOLE_TH-EMPTY,HOLE1212]
    1  GND                1  @S9S_MB_2U_LIB.S9S_MB_2U(SCH_1):GND

HOLE  I58  H54    [HOLE_TH-EMPTY,HOLE1087]
    1  GND                1  @S9S_MB_2U_LIB.S9S_MB_2U(SCH_1):GND

HOLE  I59  H55    [HOLE_TH-EMPTY,HOLE1087]
    1  GND                1  @S9S_MB_2U_LIB.S9S_MB_2U(SCH_1):GND

SCONN288_ADR50001P013C01  I200  J1     [SCONN288_ADR50001P013C01-SCONNA]
  146  P12V_S3_AUX_CPU0_NVDIMM  VIN_BULK2  @S9S_MB_2U_LIB.S9S_MB_2U(SCH_1):P12V_S3_AUX_CPU0_NVDIMM
  145  P12V_S3_AUX_CPU0_NVDIMM  VIN_BULK1  @S9S_MB_2U_LIB.S9S_MB_2U(SCH_1):P12V_S3_AUX_CPU0_NVDIMM
    1  P12V_S3_AUX_CPU0_NVDIMM  VIN_BULK0  @S9S_MB_2U_LIB.S9S_MB_2U(SCH_1):P12V_S3_AUX_CPU0_NVDIMM
  288  GND            VSS126  @S9S_MB_2U_LIB.S9S_MB_2U(SCH_1):GND
  286  GND            VSS125  @S9S_MB_2U_LIB.S9S_MB_2U(SCH_1):GND
  284  GND            VSS124  @S9S_MB_2U_LIB.S9S_MB_2U(SCH_1):GND
  281  GND            VSS123  @S9S_MB_2U_LIB.S9S_MB_2U(SCH_1):GND
  279  GND            VSS122  @S9S_MB_2U_LIB.S9S_MB_2U(SCH_1):GND
  277  GND            VSS121  @S9S_MB_2U_LIB.S9S_MB_2U(SCH_1):GND
  275  GND            VSS120  @S9S_MB_2U_LIB.S9S_MB_2U(SCH_1):GND
  273  GND            VSS119  @S9S_MB_2U_LIB.S9S_MB_2U(SCH_1):GND
  270  GND            VSS118  @S9S_MB_2U_LIB.S9S_MB_2U(SCH_1):GND
  268  GND            VSS117  @S9S_MB_2U_LIB.S9S_MB_2U(SCH_1):GND
  266  GND            VSS116  @S9S_MB_2U_LIB.S9S_MB_2U(SCH_1):GND
  264  GND            VSS115  @S9S_MB_2U_LIB.S9S_MB_2U(SCH_1):GND
  262  GND            VSS114  @S9S_MB_2U_LIB.S9S_MB_2U(SCH_1):GND
  259  GND            VSS113  @S9S_MB_2U_LIB.S9S_MB_2U(SCH_1):GND
  257  GND            VSS112  @S9S_MB_2U_LIB.S9S_MB_2U(SCH_1):GND
  255  GND            VSS111  @S9S_MB_2U_LIB.S9S_MB_2U(SCH_1):GND
  253  GND            VSS110  @S9S_MB_2U_LIB.S9S_MB_2U(SCH_1):GND
  251  GND            VSS109  @S9S_MB_2U_LIB.S9S_MB_2U(SCH_1):GND
  248  GND            VSS108  @S9S_MB_2U_LIB.S9S_MB_2U(SCH_1):GND
  246  GND            VSS107  @S9S_MB_2U_LIB.S9S_MB_2U(SCH_1):GND
  244  GND            VSS106  @S9S_MB_2U_LIB.S9S_MB_2U(SCH_1):GND
  242  GND            VSS105  @S9S_MB_2U_LIB.S9S_MB_2U(SCH_1):GND
  240  GND            VSS104  @S9S_MB_2U_LIB.S9S_MB_2U(SCH_1):GND
  237  GND            VSS103  @S9S_MB_2U_LIB.S9S_MB_2U(SCH_1):GND
  235  GND            VSS102  @S9S_MB_2U_LIB.S9S_MB_2U(SCH_1):GND
  233  GND            VSS101  @S9S_MB_2U_LIB.S9S_MB_2U(SCH_1):GND
  230  GND            VSS100  @S9S_MB_2U_LIB.S9S_MB_2U(SCH_1):GND
  228  GND            VSS99  @S9S_MB_2U_LIB.S9S_MB_2U(SCH_1):GND
  226  GND            VSS98  @S9S_MB_2U_LIB.S9S_MB_2U(SCH_1):GND
  224  GND            VSS97  @S9S_MB_2U_LIB.S9S_MB_2U(SCH_1):GND
  222  GND            VSS96  @S9S_MB_2U_LIB.S9S_MB_2U(SCH_1):GND
  219  GND            VSS95  @S9S_MB_2U_LIB.S9S_MB_2U(SCH_1):GND
  216  GND            VSS94  @S9S_MB_2U_LIB.S9S_MB_2U(SCH_1):GND
  214  GND            VSS93  @S9S_MB_2U_LIB.S9S_MB_2U(SCH_1):GND
  212  GND            VSS92  @S9S_MB_2U_LIB.S9S_MB_2U(SCH_1):GND
  210  GND            VSS91  @S9S_MB_2U_LIB.S9S_MB_2U(SCH_1):GND
  208  GND            VSS90  @S9S_MB_2U_LIB.S9S_MB_2U(SCH_1):GND
  206  GND            VSS89  @S9S_MB_2U_LIB.S9S_MB_2U(SCH_1):GND
  204  GND            VSS88  @S9S_MB_2U_LIB.S9S_MB_2U(SCH_1):GND
  202  GND            VSS87  @S9S_MB_2U_LIB.S9S_MB_2U(SCH_1):GND
  199  GND            VSS86  @S9S_MB_2U_LIB.S9S_MB_2U(SCH_1):GND
  197  GND            VSS85  @S9S_MB_2U_LIB.S9S_MB_2U(SCH_1):GND
  195  GND            VSS84  @S9S_MB_2U_LIB.S9S_MB_2U(SCH_1):GND
  193  GND            VSS83  @S9S_MB_2U_LIB.S9S_MB_2U(SCH_1):GND
  191  GND            VSS82  @S9S_MB_2U_LIB.S9S_MB_2U(SCH_1):GND
  188  GND            VSS81  @S9S_MB_2U_LIB.S9S_MB_2U(SCH_1):GND
  186  GND            VSS80  @S9S_MB_2U_LIB.S9S_MB_2U(SCH_1):GND
  184  GND            VSS79  @S9S_MB_2U_LIB.S9S_MB_2U(SCH_1):GND
  182  GND            VSS78  @S9S_MB_2U_LIB.S9S_MB_2U(SCH_1):GND
  180  GND            VSS77  @S9S_MB_2U_LIB.S9S_MB_2U(SCH_1):GND
  177  GND            VSS76  @S9S_MB_2U_LIB.S9S_MB_2U(SCH_1):GND
  175  GND            VSS75  @S9S_MB_2U_LIB.S9S_MB_2U(SCH_1):GND
  173  GND            VSS74  @S9S_MB_2U_LIB.S9S_MB_2U(SCH_1):GND
  171  GND            VSS73  @S9S_MB_2U_LIB.S9S_MB_2U(SCH_1):GND
  169  GND            VSS72  @S9S_MB_2U_LIB.S9S_MB_2U(SCH_1):GND
  166  GND            VSS71  @S9S_MB_2U_LIB.S9S_MB_2U(SCH_1):GND
  164  GND            VSS70  @S9S_MB_2U_LIB.S9S_MB_2U(SCH_1):GND
  162  GND            VSS69  @S9S_MB_2U_LIB.S9S_MB_2U(SCH_1):GND
  160  GND            VSS68  @S9S_MB_2U_LIB.S9S_MB_2U(SCH_1):GND
  158  GND            VSS67  @S9S_MB_2U_LIB.S9S_MB_2U(SCH_1):GND
  155  GND            VSS66  @S9S_MB_2U_LIB.S9S_MB_2U(SCH_1):GND
  153  GND            VSS65  @S9S_MB_2U_LIB.S9S_MB_2U(SCH_1):GND
  151  GND            VSS64  @S9S_MB_2U_LIB.S9S_MB_2U(SCH_1):GND
  143  GND            VSS63  @S9S_MB_2U_LIB.S9S_MB_2U(SCH_1):GND
  141  GND            VSS62  @S9S_MB_2U_LIB.S9S_MB_2U(SCH_1):GND
  139  GND            VSS61  @S9S_MB_2U_LIB.S9S_MB_2U(SCH_1):GND
  136  GND            VSS60  @S9S_MB_2U_LIB.S9S_MB_2U(SCH_1):GND
  134  GND            VSS59  @S9S_MB_2U_LIB.S9S_MB_2U(SCH_1):GND
  132  GND            VSS58  @S9S_MB_2U_LIB.S9S_MB_2U(SCH_1):GND
  130  GND            VSS57  @S9S_MB_2U_LIB.S9S_MB_2U(SCH_1):GND
  128  GND            VSS56  @S9S_MB_2U_LIB.S9S_MB_2U(SCH_1):GND
  125  GND            VSS55  @S9S_MB_2U_LIB.S9S_MB_2U(SCH_1):GND
  123  GND            VSS54  @S9S_MB_2U_LIB.S9S_MB_2U(SCH_1):GND
  121  GND            VSS53  @S9S_MB_2U_LIB.S9S_MB_2U(SCH_1):GND
  119  GND            VSS52  @S9S_MB_2U_LIB.S9S_MB_2U(SCH_1):GND
  117  GND            VSS51  @S9S_MB_2U_LIB.S9S_MB_2U(SCH_1):GND
  114  GND            VSS50  @S9S_MB_2U_LIB.S9S_MB_2U(SCH_1):GND
  112  GND            VSS49  @S9S_MB_2U_LIB.S9S_MB_2U(SCH_1):GND
  110  GND            VSS48  @S9S_MB_2U_LIB.S9S_MB_2U(SCH_1):GND
  108  GND            VSS47  @S9S_MB_2U_LIB.S9S_MB_2U(SCH_1):GND
  106  GND            VSS46  @S9S_MB_2U_LIB.S9S_MB_2U(SCH_1):GND
  103  GND            VSS45  @S9S_MB_2U_LIB.S9S_MB_2U(SCH_1):GND
  101  GND            VSS44  @S9S_MB_2U_LIB.S9S_MB_2U(SCH_1):GND
   99  GND            VSS43  @S9S_MB_2U_LIB.S9S_MB_2U(SCH_1):GND
   97  GND            VSS42  @S9S_MB_2U_LIB.S9S_MB_2U(SCH_1):GND
   95  GND            VSS41  @S9S_MB_2U_LIB.S9S_MB_2U(SCH_1):GND
   92  GND            VSS40  @S9S_MB_2U_LIB.S9S_MB_2U(SCH_1):GND
   90  GND            VSS39  @S9S_MB_2U_LIB.S9S_MB_2U(SCH_1):GND
   88  GND            VSS38  @S9S_MB_2U_LIB.S9S_MB_2U(SCH_1):GND
   85  GND            VSS37  @S9S_MB_2U_LIB.S9S_MB_2U(SCH_1):GND
   83  GND            VSS36  @S9S_MB_2U_LIB.S9S_MB_2U(SCH_1):GND
   81  GND            VSS35  @S9S_MB_2U_LIB.S9S_MB_2U(SCH_1):GND
   79  GND            VSS34  @S9S_MB_2U_LIB.S9S_MB_2U(SCH_1):GND
   77  GND            VSS33  @S9S_MB_2U_LIB.S9S_MB_2U(SCH_1):GND
   75  GND            VSS32  @S9S_MB_2U_LIB.S9S_MB_2U(SCH_1):GND
   73  GND            VSS31  @S9S_MB_2U_LIB.S9S_MB_2U(SCH_1):GND
   71  GND            VSS30  @S9S_MB_2U_LIB.S9S_MB_2U(SCH_1):GND
   69  GND            VSS29  @S9S_MB_2U_LIB.S9S_MB_2U(SCH_1):GND
   67  GND            VSS28  @S9S_MB_2U_LIB.S9S_MB_2U(SCH_1):GND
   65  GND            VSS27  @S9S_MB_2U_LIB.S9S_MB_2U(SCH_1):GND
   63  GND            VSS26  @S9S_MB_2U_LIB.S9S_MB_2U(SCH_1):GND
   61  GND            VSS25  @S9S_MB_2U_LIB.S9S_MB_2U(SCH_1):GND
   59  GND            VSS24  @S9S_MB_2U_LIB.S9S_MB_2U(SCH_1):GND
   57  GND            VSS23  @S9S_MB_2U_LIB.S9S_MB_2U(SCH_1):GND
   54  GND            VSS22  @S9S_MB_2U_LIB.S9S_MB_2U(SCH_1):GND
   52  GND            VSS21  @S9S_MB_2U_LIB.S9S_MB_2U(SCH_1):GND
   50  GND            VSS20  @S9S_MB_2U_LIB.S9S_MB_2U(SCH_1):GND
   48  GND            VSS19  @S9S_MB_2U_LIB.S9S_MB_2U(SCH_1):GND
   46  GND            VSS18  @S9S_MB_2U_LIB.S9S_MB_2U(SCH_1):GND
   43  GND            VSS17  @S9S_MB_2U_LIB.S9S_MB_2U(SCH_1):GND
   41  GND            VSS16  @S9S_MB_2U_LIB.S9S_MB_2U(SCH_1):GND
   39  GND            VSS15  @S9S_MB_2U_LIB.S9S_MB_2U(SCH_1):GND
   37  GND            VSS14  @S9S_MB_2U_LIB.S9S_MB_2U(SCH_1):GND
   35  GND            VSS13  @S9S_MB_2U_LIB.S9S_MB_2U(SCH_1):GND
   32  GND            VSS12  @S9S_MB_2U_LIB.S9S_MB_2U(SCH_1):GND
   30  GND            VSS11  @S9S_MB_2U_LIB.S9S_MB_2U(SCH_1):GND
   28  GND            VSS10  @S9S_MB_2U_LIB.S9S_MB_2U(SCH_1):GND
   26  GND             VSS9  @S9S_MB_2U_LIB.S9S_MB_2U(SCH_1):GND
   24  GND             VSS8  @S9S_MB_2U_LIB.S9S_MB_2U(SCH_1):GND
   21  GND             VSS7  @S9S_MB_2U_LIB.S9S_MB_2U(SCH_1):GND
   19  GND             VSS6  @S9S_MB_2U_LIB.S9S_MB_2U(SCH_1):GND
   17  GND             VSS5  @S9S_MB_2U_LIB.S9S_MB_2U(SCH_1):GND
   15  GND             VSS4  @S9S_MB_2U_LIB.S9S_MB_2U(SCH_1):GND
   13  GND             VSS3  @S9S_MB_2U_LIB.S9S_MB_2U(SCH_1):GND
   10  GND             VSS2  @S9S_MB_2U_LIB.S9S_MB_2U(SCH_1):GND
    8  GND             VSS1  @S9S_MB_2U_LIB.S9S_MB_2U(SCH_1):GND
    6  GND             VSS0  @S9S_MB_2U_LIB.S9S_MB_2U(SCH_1):GND
   G3  GND               G3  @S9S_MB_2U_LIB.S9S_MB_2U(SCH_1):GND
   G2  GND               G2  @S9S_MB_2U_LIB.S9S_MB_2U(SCH_1):GND
   G1  GND               G1  @S9S_MB_2U_LIB.S9S_MB_2U(SCH_1):GND

SCONN288_ADR50001P013C01  I199  J1     [SCONN288_ADR50001P013C01-SCONNA]
   93  M_A_CPU0_SB_DQS_DP<9>  DQS9_B_P  @S9S_MB_2U_LIB.S9S_MB_2U(SCH_1):M_A_CPU0_SB_DQS_DP<9>
  283  M_A_CPU0_SB_DQS_DP<8>  DQS8_B_P  @S9S_MB_2U_LIB.S9S_MB_2U(SCH_1):M_A_CPU0_SB_DQS_DP<8>
  272  M_A_CPU0_SB_DQS_DP<7>  DQS7_B_P  @S9S_MB_2U_LIB.S9S_MB_2U(SCH_1):M_A_CPU0_SB_DQS_DP<7>
  261  M_A_CPU0_SB_DQS_DP<6>  DQS6_B_P  @S9S_MB_2U_LIB.S9S_MB_2U(SCH_1):M_A_CPU0_SB_DQS_DP<6>
  250  M_A_CPU0_SB_DQS_DP<5>  DQS5_B_P  @S9S_MB_2U_LIB.S9S_MB_2U(SCH_1):M_A_CPU0_SB_DQS_DP<5>
  239  M_A_CPU0_SB_DQS_DP<4>  DQS4_B_P  @S9S_MB_2U_LIB.S9S_MB_2U(SCH_1):M_A_CPU0_SB_DQS_DP<4>
  137  M_A_CPU0_SB_DQS_DP<3>  DQS3_B_P  @S9S_MB_2U_LIB.S9S_MB_2U(SCH_1):M_A_CPU0_SB_DQS_DP<3>
  126  M_A_CPU0_SB_DQS_DP<2>  DQS2_B_P  @S9S_MB_2U_LIB.S9S_MB_2U(SCH_1):M_A_CPU0_SB_DQS_DP<2>
  115  M_A_CPU0_SB_DQS_DP<1>  DQS1_B_P  @S9S_MB_2U_LIB.S9S_MB_2U(SCH_1):M_A_CPU0_SB_DQS_DP<1>
  104  M_A_CPU0_SB_DQS_DP<0>  DQS0_B_P  @S9S_MB_2U_LIB.S9S_MB_2U(SCH_1):M_A_CPU0_SB_DQS_DP<0>
   94  M_A_CPU0_SB_DQS_DN<9>  DQS9_B_N  @S9S_MB_2U_LIB.S9S_MB_2U(SCH_1):M_A_CPU0_SB_DQS_DN<9>
  282  M_A_CPU0_SB_DQS_DN<8>  DQS8_B_N  @S9S_MB_2U_LIB.S9S_MB_2U(SCH_1):M_A_CPU0_SB_DQS_DN<8>
  271  M_A_CPU0_SB_DQS_DN<7>  DQS7_B_N  @S9S_MB_2U_LIB.S9S_MB_2U(SCH_1):M_A_CPU0_SB_DQS_DN<7>
  260  M_A_CPU0_SB_DQS_DN<6>  DQS6_B_N  @S9S_MB_2U_LIB.S9S_MB_2U(SCH_1):M_A_CPU0_SB_DQS_DN<6>
  249  M_A_CPU0_SB_DQS_DN<5>  DQS5_B_N  @S9S_MB_2U_LIB.S9S_MB_2U(SCH_1):M_A_CPU0_SB_DQS_DN<5>
  238  M_A_CPU0_SB_DQS_DN<4>  DQS4_B_N  @S9S_MB_2U_LIB.S9S_MB_2U(SCH_1):M_A_CPU0_SB_DQS_DN<4>
  138  M_A_CPU0_SB_DQS_DN<3>  DQS3_B_N  @S9S_MB_2U_LIB.S9S_MB_2U(SCH_1):M_A_CPU0_SB_DQS_DN<3>
  127  M_A_CPU0_SB_DQS_DN<2>  DQS2_B_N  @S9S_MB_2U_LIB.S9S_MB_2U(SCH_1):M_A_CPU0_SB_DQS_DN<2>
  116  M_A_CPU0_SB_DQS_DN<1>  DQS1_B_N  @S9S_MB_2U_LIB.S9S_MB_2U(SCH_1):M_A_CPU0_SB_DQS_DN<1>
  105  M_A_CPU0_SB_DQS_DN<0>  DQS0_B_N  @S9S_MB_2U_LIB.S9S_MB_2U(SCH_1):M_A_CPU0_SB_DQS_DN<0>
  201  M_A_CPU0_SA_DQS_DP<9>  DQS9_A_P  @S9S_MB_2U_LIB.S9S_MB_2U(SCH_1):M_A_CPU0_SA_DQS_DP<9>
  190  M_A_CPU0_SA_DQS_DP<8>  DQS8_A_P  @S9S_MB_2U_LIB.S9S_MB_2U(SCH_1):M_A_CPU0_SA_DQS_DP<8>
  179  M_A_CPU0_SA_DQS_DP<7>  DQS7_A_P  @S9S_MB_2U_LIB.S9S_MB_2U(SCH_1):M_A_CPU0_SA_DQS_DP<7>
  168  M_A_CPU0_SA_DQS_DP<6>  DQS6_A_P  @S9S_MB_2U_LIB.S9S_MB_2U(SCH_1):M_A_CPU0_SA_DQS_DP<6>
  157  M_A_CPU0_SA_DQS_DP<5>  DQS5_A_P  @S9S_MB_2U_LIB.S9S_MB_2U(SCH_1):M_A_CPU0_SA_DQS_DP<5>
   55  M_A_CPU0_SA_DQS_DP<4>  DQS4_A_P  @S9S_MB_2U_LIB.S9S_MB_2U(SCH_1):M_A_CPU0_SA_DQS_DP<4>
   44  M_A_CPU0_SA_DQS_DP<3>  DQS3_A_P  @S9S_MB_2U_LIB.S9S_MB_2U(SCH_1):M_A_CPU0_SA_DQS_DP<3>
   33  M_A_CPU0_SA_DQS_DP<2>  DQS2_A_P  @S9S_MB_2U_LIB.S9S_MB_2U(SCH_1):M_A_CPU0_SA_DQS_DP<2>
   22  M_A_CPU0_SA_DQS_DP<1>  DQS1_A_P  @S9S_MB_2U_LIB.S9S_MB_2U(SCH_1):M_A_CPU0_SA_DQS_DP<1>
   11  M_A_CPU0_SA_DQS_DP<0>  DQS0_A_P  @S9S_MB_2U_LIB.S9S_MB_2U(SCH_1):M_A_CPU0_SA_DQS_DP<0>
  200  M_A_CPU0_SA_DQS_DN<9>  DQS9_A_N  @S9S_MB_2U_LIB.S9S_MB_2U(SCH_1):M_A_CPU0_SA_DQS_DN<9>
  189  M_A_CPU0_SA_DQS_DN<8>  DQS8_A_N  @S9S_MB_2U_LIB.S9S_MB_2U(SCH_1):M_A_CPU0_SA_DQS_DN<8>
  178  M_A_CPU0_SA_DQS_DN<7>  DQS7_A_N  @S9S_MB_2U_LIB.S9S_MB_2U(SCH_1):M_A_CPU0_SA_DQS_DN<7>
  167  M_A_CPU0_SA_DQS_DN<6>  DQS6_A_N  @S9S_MB_2U_LIB.S9S_MB_2U(SCH_1):M_A_CPU0_SA_DQS_DN<6>
  156  M_A_CPU0_SA_DQS_DN<5>  DQS5_A_N  @S9S_MB_2U_LIB.S9S_MB_2U(SCH_1):M_A_CPU0_SA_DQS_DN<5>
   56  M_A_CPU0_SA_DQS_DN<4>  DQS4_A_N  @S9S_MB_2U_LIB.S9S_MB_2U(SCH_1):M_A_CPU0_SA_DQS_DN<4>
   45  M_A_CPU0_SA_DQS_DN<3>  DQS3_A_N  @S9S_MB_2U_LIB.S9S_MB_2U(SCH_1):M_A_CPU0_SA_DQS_DN<3>
   34  M_A_CPU0_SA_DQS_DN<2>  DQS2_A_N  @S9S_MB_2U_LIB.S9S_MB_2U(SCH_1):M_A_CPU0_SA_DQS_DN<2>
   23  M_A_CPU0_SA_DQS_DN<1>  DQS1_A_N  @S9S_MB_2U_LIB.S9S_MB_2U(SCH_1):M_A_CPU0_SA_DQS_DN<1>
   12  M_A_CPU0_SA_DQS_DN<0>  DQS0_A_N  @S9S_MB_2U_LIB.S9S_MB_2U(SCH_1):M_A_CPU0_SA_DQS_DN<0>

SCONN288_ADR50001P013C01  I198  J1     [SCONN288_ADR50001P013C01-SCONNA]
  232  NC              RFU6  NC
  231  NC              RFU5  NC
  220  NC              RFU4  NC
  150  NC              RFU3  NC
  149  NC              RFU2  NC
  144  NC              RFU1  NC
    2  NC              RFU0  NC
  207  RST_M_AB_CPU0_FPGA_N  RESET_N  @S9S_MB_2U_LIB.S9S_MB_2U(SCH_1):RST_M_AB_CPU0_FPGA_N
  147  PWRGD_CHA_CPU0_DIMM1  PWR_GOOD||FAIL_N  @S9S_MB_2U_LIB.S9S_MB_2U(SCH_1):PWRGD_CHA_CPU0_DIMM1
  148  PD_CHA_CPU0_DIMM1_SAA    HAS  @S9S_MB_2U_LIB.S9S_MB_2U(SCH_1):PD_CHA_CPU0_DIMM1_SAA
    3  P3V3_AUX       VIN_MGMT  @S9S_MB_2U_LIB.S9S_MB_2U(SCH_1):P3V3_AUX
   87  M_A_CPU0_SB_RSP<0>  LBS||RSP_N_B  @S9S_MB_2U_LIB.S9S_MB_2U(SCH_1):M_A_CPU0_SB_RSP<0>
  227  M_A_CPU0_SB_PAR  PAR_B  @S9S_MB_2U_LIB.S9S_MB_2U(SCH_1):M_A_CPU0_SB_PAR
  113  M_A_CPU0_SB_DQ<9>  DQ_B9  @S9S_MB_2U_LIB.S9S_MB_2U(SCH_1):M_A_CPU0_SB_DQ<9>
  111  M_A_CPU0_SB_DQ<8>  DQ_B8  @S9S_MB_2U_LIB.S9S_MB_2U(SCH_1):M_A_CPU0_SB_DQ<8>
  254  M_A_CPU0_SB_DQ<7>  DQ_B7  @S9S_MB_2U_LIB.S9S_MB_2U(SCH_1):M_A_CPU0_SB_DQ<7>
  252  M_A_CPU0_SB_DQ<6>  DQ_B6  @S9S_MB_2U_LIB.S9S_MB_2U(SCH_1):M_A_CPU0_SB_DQ<6>
  109  M_A_CPU0_SB_DQ<5>  DQ_B5  @S9S_MB_2U_LIB.S9S_MB_2U(SCH_1):M_A_CPU0_SB_DQ<5>
  107  M_A_CPU0_SB_DQ<4>  DQ_B4  @S9S_MB_2U_LIB.S9S_MB_2U(SCH_1):M_A_CPU0_SB_DQ<4>
  247  M_A_CPU0_SB_DQ<3>  DQ_B3  @S9S_MB_2U_LIB.S9S_MB_2U(SCH_1):M_A_CPU0_SB_DQ<3>
  287  M_A_CPU0_SB_DQ<31>  DQ_B31  @S9S_MB_2U_LIB.S9S_MB_2U(SCH_1):M_A_CPU0_SB_DQ<31>
  285  M_A_CPU0_SB_DQ<30>  DQ_B30  @S9S_MB_2U_LIB.S9S_MB_2U(SCH_1):M_A_CPU0_SB_DQ<30>
  245  M_A_CPU0_SB_DQ<2>  DQ_B2  @S9S_MB_2U_LIB.S9S_MB_2U(SCH_1):M_A_CPU0_SB_DQ<2>
  142  M_A_CPU0_SB_DQ<29>  DQ_B29  @S9S_MB_2U_LIB.S9S_MB_2U(SCH_1):M_A_CPU0_SB_DQ<29>
  140  M_A_CPU0_SB_DQ<28>  DQ_B28  @S9S_MB_2U_LIB.S9S_MB_2U(SCH_1):M_A_CPU0_SB_DQ<28>
  280  M_A_CPU0_SB_DQ<27>  DQ_B27  @S9S_MB_2U_LIB.S9S_MB_2U(SCH_1):M_A_CPU0_SB_DQ<27>
  278  M_A_CPU0_SB_DQ<26>  DQ_B26  @S9S_MB_2U_LIB.S9S_MB_2U(SCH_1):M_A_CPU0_SB_DQ<26>
  135  M_A_CPU0_SB_DQ<25>  DQ_B25  @S9S_MB_2U_LIB.S9S_MB_2U(SCH_1):M_A_CPU0_SB_DQ<25>
  133  M_A_CPU0_SB_DQ<24>  DQ_B24  @S9S_MB_2U_LIB.S9S_MB_2U(SCH_1):M_A_CPU0_SB_DQ<24>
  276  M_A_CPU0_SB_DQ<23>  DQ_B23  @S9S_MB_2U_LIB.S9S_MB_2U(SCH_1):M_A_CPU0_SB_DQ<23>
  274  M_A_CPU0_SB_DQ<22>  DQ_B22  @S9S_MB_2U_LIB.S9S_MB_2U(SCH_1):M_A_CPU0_SB_DQ<22>
  131  M_A_CPU0_SB_DQ<21>  DQ_B21  @S9S_MB_2U_LIB.S9S_MB_2U(SCH_1):M_A_CPU0_SB_DQ<21>
  129  M_A_CPU0_SB_DQ<20>  DQ_B20  @S9S_MB_2U_LIB.S9S_MB_2U(SCH_1):M_A_CPU0_SB_DQ<20>
  102  M_A_CPU0_SB_DQ<1>  DQ_B1  @S9S_MB_2U_LIB.S9S_MB_2U(SCH_1):M_A_CPU0_SB_DQ<1>
  269  M_A_CPU0_SB_DQ<19>  DQ_B19  @S9S_MB_2U_LIB.S9S_MB_2U(SCH_1):M_A_CPU0_SB_DQ<19>
  267  M_A_CPU0_SB_DQ<18>  DQ_B18  @S9S_MB_2U_LIB.S9S_MB_2U(SCH_1):M_A_CPU0_SB_DQ<18>
  124  M_A_CPU0_SB_DQ<17>  DQ_B17  @S9S_MB_2U_LIB.S9S_MB_2U(SCH_1):M_A_CPU0_SB_DQ<17>
  122  M_A_CPU0_SB_DQ<16>  DQ_B16  @S9S_MB_2U_LIB.S9S_MB_2U(SCH_1):M_A_CPU0_SB_DQ<16>
  265  M_A_CPU0_SB_DQ<15>  DQ_B15  @S9S_MB_2U_LIB.S9S_MB_2U(SCH_1):M_A_CPU0_SB_DQ<15>
  263  M_A_CPU0_SB_DQ<14>  DQ_B14  @S9S_MB_2U_LIB.S9S_MB_2U(SCH_1):M_A_CPU0_SB_DQ<14>
  120  M_A_CPU0_SB_DQ<13>  DQ_B13  @S9S_MB_2U_LIB.S9S_MB_2U(SCH_1):M_A_CPU0_SB_DQ<13>
  118  M_A_CPU0_SB_DQ<12>  DQ_B12  @S9S_MB_2U_LIB.S9S_MB_2U(SCH_1):M_A_CPU0_SB_DQ<12>
  258  M_A_CPU0_SB_DQ<11>  DQ_B11  @S9S_MB_2U_LIB.S9S_MB_2U(SCH_1):M_A_CPU0_SB_DQ<11>
  256  M_A_CPU0_SB_DQ<10>  DQ_B10  @S9S_MB_2U_LIB.S9S_MB_2U(SCH_1):M_A_CPU0_SB_DQ<10>
  100  M_A_CPU0_SB_DQ<0>  DQ_B0  @S9S_MB_2U_LIB.S9S_MB_2U(SCH_1):M_A_CPU0_SB_DQ<0>
  229  M_A_CPU0_SB_CS_N<1>  CS1_N_B  @S9S_MB_2U_LIB.S9S_MB_2U(SCH_1):M_A_CPU0_SB_CS_N<1>
   84  M_A_CPU0_SB_CS_N<0>  CS0_N_B  @S9S_MB_2U_LIB.S9S_MB_2U(SCH_1):M_A_CPU0_SB_CS_N<0>
  236  M_A_CPU0_SB_CB<7>  CB_B7  @S9S_MB_2U_LIB.S9S_MB_2U(SCH_1):M_A_CPU0_SB_CB<7>
  234  M_A_CPU0_SB_CB<6>  CB_B6  @S9S_MB_2U_LIB.S9S_MB_2U(SCH_1):M_A_CPU0_SB_CB<6>
   91  M_A_CPU0_SB_CB<5>  CB_B5  @S9S_MB_2U_LIB.S9S_MB_2U(SCH_1):M_A_CPU0_SB_CB<5>
   89  M_A_CPU0_SB_CB<4>  CB_B4  @S9S_MB_2U_LIB.S9S_MB_2U(SCH_1):M_A_CPU0_SB_CB<4>
  243  M_A_CPU0_SB_CB<3>  CB_B3  @S9S_MB_2U_LIB.S9S_MB_2U(SCH_1):M_A_CPU0_SB_CB<3>
  241  M_A_CPU0_SB_CB<2>  CB_B2  @S9S_MB_2U_LIB.S9S_MB_2U(SCH_1):M_A_CPU0_SB_CB<2>
   98  M_A_CPU0_SB_CB<1>  CB_B1  @S9S_MB_2U_LIB.S9S_MB_2U(SCH_1):M_A_CPU0_SB_CB<1>
   96  M_A_CPU0_SB_CB<0>  CB_B0  @S9S_MB_2U_LIB.S9S_MB_2U(SCH_1):M_A_CPU0_SB_CB<0>
   82  M_A_CPU0_SB_CA<6>  CA6_B  @S9S_MB_2U_LIB.S9S_MB_2U(SCH_1):M_A_CPU0_SB_CA<6>
  225  M_A_CPU0_SB_CA<5>  CA5_B  @S9S_MB_2U_LIB.S9S_MB_2U(SCH_1):M_A_CPU0_SB_CA<5>
   80  M_A_CPU0_SB_CA<4>  CA4_B  @S9S_MB_2U_LIB.S9S_MB_2U(SCH_1):M_A_CPU0_SB_CA<4>
  223  M_A_CPU0_SB_CA<3>  CA3_B  @S9S_MB_2U_LIB.S9S_MB_2U(SCH_1):M_A_CPU0_SB_CA<3>
   78  M_A_CPU0_SB_CA<2>  CA2_B  @S9S_MB_2U_LIB.S9S_MB_2U(SCH_1):M_A_CPU0_SB_CA<2>
  221  M_A_CPU0_SB_CA<1>  CA1_B  @S9S_MB_2U_LIB.S9S_MB_2U(SCH_1):M_A_CPU0_SB_CA<1>
   76  M_A_CPU0_SB_CA<0>  CA0_B  @S9S_MB_2U_LIB.S9S_MB_2U(SCH_1):M_A_CPU0_SB_CA<0>
   86  M_A_CPU0_SA_RSP<0>  LBD||RSP_N_A  @S9S_MB_2U_LIB.S9S_MB_2U(SCH_1):M_A_CPU0_SA_RSP<0>
   74  M_A_CPU0_SA_PAR  PAR_A  @S9S_MB_2U_LIB.S9S_MB_2U(SCH_1):M_A_CPU0_SA_PAR
   20  M_A_CPU0_SA_DQ<9>  DQ_A9  @S9S_MB_2U_LIB.S9S_MB_2U(SCH_1):M_A_CPU0_SA_DQ<9>
   18  M_A_CPU0_SA_DQ<8>  DQ_A8  @S9S_MB_2U_LIB.S9S_MB_2U(SCH_1):M_A_CPU0_SA_DQ<8>
  161  M_A_CPU0_SA_DQ<7>  DQ_A7  @S9S_MB_2U_LIB.S9S_MB_2U(SCH_1):M_A_CPU0_SA_DQ<7>
  159  M_A_CPU0_SA_DQ<6>  DQ_A6  @S9S_MB_2U_LIB.S9S_MB_2U(SCH_1):M_A_CPU0_SA_DQ<6>
   16  M_A_CPU0_SA_DQ<5>  DQ_A5  @S9S_MB_2U_LIB.S9S_MB_2U(SCH_1):M_A_CPU0_SA_DQ<5>
   14  M_A_CPU0_SA_DQ<4>  DQ_A4  @S9S_MB_2U_LIB.S9S_MB_2U(SCH_1):M_A_CPU0_SA_DQ<4>
  154  M_A_CPU0_SA_DQ<3>  DQ_A3  @S9S_MB_2U_LIB.S9S_MB_2U(SCH_1):M_A_CPU0_SA_DQ<3>
  194  M_A_CPU0_SA_DQ<31>  DQ_A31  @S9S_MB_2U_LIB.S9S_MB_2U(SCH_1):M_A_CPU0_SA_DQ<31>
  192  M_A_CPU0_SA_DQ<30>  DQ_A30  @S9S_MB_2U_LIB.S9S_MB_2U(SCH_1):M_A_CPU0_SA_DQ<30>
  152  M_A_CPU0_SA_DQ<2>  DQ_A2  @S9S_MB_2U_LIB.S9S_MB_2U(SCH_1):M_A_CPU0_SA_DQ<2>
   49  M_A_CPU0_SA_DQ<29>  DQ_A29  @S9S_MB_2U_LIB.S9S_MB_2U(SCH_1):M_A_CPU0_SA_DQ<29>
   47  M_A_CPU0_SA_DQ<28>  DQ_A28  @S9S_MB_2U_LIB.S9S_MB_2U(SCH_1):M_A_CPU0_SA_DQ<28>
  187  M_A_CPU0_SA_DQ<27>  DQ_A27  @S9S_MB_2U_LIB.S9S_MB_2U(SCH_1):M_A_CPU0_SA_DQ<27>
  185  M_A_CPU0_SA_DQ<26>  DQ_A26  @S9S_MB_2U_LIB.S9S_MB_2U(SCH_1):M_A_CPU0_SA_DQ<26>
   42  M_A_CPU0_SA_DQ<25>  DQ_A25  @S9S_MB_2U_LIB.S9S_MB_2U(SCH_1):M_A_CPU0_SA_DQ<25>
   40  M_A_CPU0_SA_DQ<24>  DQ_A24  @S9S_MB_2U_LIB.S9S_MB_2U(SCH_1):M_A_CPU0_SA_DQ<24>
  183  M_A_CPU0_SA_DQ<23>  DQ_A23  @S9S_MB_2U_LIB.S9S_MB_2U(SCH_1):M_A_CPU0_SA_DQ<23>
  181  M_A_CPU0_SA_DQ<22>  DQ_A22  @S9S_MB_2U_LIB.S9S_MB_2U(SCH_1):M_A_CPU0_SA_DQ<22>
   38  M_A_CPU0_SA_DQ<21>  DQ_A21  @S9S_MB_2U_LIB.S9S_MB_2U(SCH_1):M_A_CPU0_SA_DQ<21>
   36  M_A_CPU0_SA_DQ<20>  DQ_A20  @S9S_MB_2U_LIB.S9S_MB_2U(SCH_1):M_A_CPU0_SA_DQ<20>
    9  M_A_CPU0_SA_DQ<1>  DQ_A1  @S9S_MB_2U_LIB.S9S_MB_2U(SCH_1):M_A_CPU0_SA_DQ<1>
  176  M_A_CPU0_SA_DQ<19>  DQ_A19  @S9S_MB_2U_LIB.S9S_MB_2U(SCH_1):M_A_CPU0_SA_DQ<19>
  174  M_A_CPU0_SA_DQ<18>  DQ_A18  @S9S_MB_2U_LIB.S9S_MB_2U(SCH_1):M_A_CPU0_SA_DQ<18>
   31  M_A_CPU0_SA_DQ<17>  DQ_A17  @S9S_MB_2U_LIB.S9S_MB_2U(SCH_1):M_A_CPU0_SA_DQ<17>
   29  M_A_CPU0_SA_DQ<16>  DQ_A16  @S9S_MB_2U_LIB.S9S_MB_2U(SCH_1):M_A_CPU0_SA_DQ<16>
  172  M_A_CPU0_SA_DQ<15>  DQ_A15  @S9S_MB_2U_LIB.S9S_MB_2U(SCH_1):M_A_CPU0_SA_DQ<15>
  170  M_A_CPU0_SA_DQ<14>  DQ_A14  @S9S_MB_2U_LIB.S9S_MB_2U(SCH_1):M_A_CPU0_SA_DQ<14>
   27  M_A_CPU0_SA_DQ<13>  DQ_A13  @S9S_MB_2U_LIB.S9S_MB_2U(SCH_1):M_A_CPU0_SA_DQ<13>
   25  M_A_CPU0_SA_DQ<12>  DQ_A12  @S9S_MB_2U_LIB.S9S_MB_2U(SCH_1):M_A_CPU0_SA_DQ<12>
  165  M_A_CPU0_SA_DQ<11>  DQ_A11  @S9S_MB_2U_LIB.S9S_MB_2U(SCH_1):M_A_CPU0_SA_DQ<11>
  163  M_A_CPU0_SA_DQ<10>  DQ_A10  @S9S_MB_2U_LIB.S9S_MB_2U(SCH_1):M_A_CPU0_SA_DQ<10>
    7  M_A_CPU0_SA_DQ<0>  DQ_A0  @S9S_MB_2U_LIB.S9S_MB_2U(SCH_1):M_A_CPU0_SA_DQ<0>
  209  M_A_CPU0_SA_CS_N<1>  CS1_N_A  @S9S_MB_2U_LIB.S9S_MB_2U(SCH_1):M_A_CPU0_SA_CS_N<1>
   64  M_A_CPU0_SA_CS_N<0>  CS0_N_A  @S9S_MB_2U_LIB.S9S_MB_2U(SCH_1):M_A_CPU0_SA_CS_N<0>
  205  M_A_CPU0_SA_CB<7>  CB_A7  @S9S_MB_2U_LIB.S9S_MB_2U(SCH_1):M_A_CPU0_SA_CB<7>
  203  M_A_CPU0_SA_CB<6>  CB_A6  @S9S_MB_2U_LIB.S9S_MB_2U(SCH_1):M_A_CPU0_SA_CB<6>
   60  M_A_CPU0_SA_CB<5>  CB_A5  @S9S_MB_2U_LIB.S9S_MB_2U(SCH_1):M_A_CPU0_SA_CB<5>
   58  M_A_CPU0_SA_CB<4>  CB_A4  @S9S_MB_2U_LIB.S9S_MB_2U(SCH_1):M_A_CPU0_SA_CB<4>
  198  M_A_CPU0_SA_CB<3>  CB_A3  @S9S_MB_2U_LIB.S9S_MB_2U(SCH_1):M_A_CPU0_SA_CB<3>
  196  M_A_CPU0_SA_CB<2>  CB_A2  @S9S_MB_2U_LIB.S9S_MB_2U(SCH_1):M_A_CPU0_SA_CB<2>
   53  M_A_CPU0_SA_CB<1>  CB_A1  @S9S_MB_2U_LIB.S9S_MB_2U(SCH_1):M_A_CPU0_SA_CB<1>
   51  M_A_CPU0_SA_CB<0>  CB_A0  @S9S_MB_2U_LIB.S9S_MB_2U(SCH_1):M_A_CPU0_SA_CB<0>
   72  M_A_CPU0_SA_CA<6>  CA6_A  @S9S_MB_2U_LIB.S9S_MB_2U(SCH_1):M_A_CPU0_SA_CA<6>
  215  M_A_CPU0_SA_CA<5>  CA5_A  @S9S_MB_2U_LIB.S9S_MB_2U(SCH_1):M_A_CPU0_SA_CA<5>
   70  M_A_CPU0_SA_CA<4>  CA4_A  @S9S_MB_2U_LIB.S9S_MB_2U(SCH_1):M_A_CPU0_SA_CA<4>
  213  M_A_CPU0_SA_CA<3>  CA3_A  @S9S_MB_2U_LIB.S9S_MB_2U(SCH_1):M_A_CPU0_SA_CA<3>
   68  M_A_CPU0_SA_CA<2>  CA2_A  @S9S_MB_2U_LIB.S9S_MB_2U(SCH_1):M_A_CPU0_SA_CA<2>
  211  M_A_CPU0_SA_CA<1>  CA1_A  @S9S_MB_2U_LIB.S9S_MB_2U(SCH_1):M_A_CPU0_SA_CA<1>
   66  M_A_CPU0_SA_CA<0>  CA0_A  @S9S_MB_2U_LIB.S9S_MB_2U(SCH_1):M_A_CPU0_SA_CA<0>
  217  M_A_CPU0_CLK_DP<0>   CK_P  @S9S_MB_2U_LIB.S9S_MB_2U(SCH_1):M_A_CPU0_CLK_DP<0>
  218  M_A_CPU0_CLK_DN<0>   CK_N  @S9S_MB_2U_LIB.S9S_MB_2U(SCH_1):M_A_CPU0_CLK_DN<0>
   62  M_A_CPU0_ALERT_N  ALERT_N  @S9S_MB_2U_LIB.S9S_MB_2U(SCH_1):M_A_CPU0_ALERT_N
    5  I3C_SPD_DDRABCD_CPU0_LVC1_SDA   HSDA  @S9S_MB_2U_LIB.S9S_MB_2U(SCH_1):I3C_SPD_DDRABCD_CPU0_LVC1_SDA
    4  I3C_SPD_DDRABCD_CPU0_LVC1_SCL   HSCL  @S9S_MB_2U_LIB.S9S_MB_2U(SCH_1):I3C_SPD_DDRABCD_CPU0_LVC1_SCL

SCONN288_ADR50001P003C01  I179  J2     [SCONN288_ADR50001P003C01-SCONNA]
  146  P12V_S3_AUX_CPU0_NVDIMM  VIN_BULK2  @S9S_MB_2U_LIB.S9S_MB_2U(SCH_1):P12V_S3_AUX_CPU0_NVDIMM
  145  P12V_S3_AUX_CPU0_NVDIMM  VIN_BULK1  @S9S_MB_2U_LIB.S9S_MB_2U(SCH_1):P12V_S3_AUX_CPU0_NVDIMM
    1  P12V_S3_AUX_CPU0_NVDIMM  VIN_BULK0  @S9S_MB_2U_LIB.S9S_MB_2U(SCH_1):P12V_S3_AUX_CPU0_NVDIMM
  288  GND            VSS126  @S9S_MB_2U_LIB.S9S_MB_2U(SCH_1):GND
  286  GND            VSS125  @S9S_MB_2U_LIB.S9S_MB_2U(SCH_1):GND
  284  GND            VSS124  @S9S_MB_2U_LIB.S9S_MB_2U(SCH_1):GND
  281  GND            VSS123  @S9S_MB_2U_LIB.S9S_MB_2U(SCH_1):GND
  279  GND            VSS122  @S9S_MB_2U_LIB.S9S_MB_2U(SCH_1):GND
  277  GND            VSS121  @S9S_MB_2U_LIB.S9S_MB_2U(SCH_1):GND
  275  GND            VSS120  @S9S_MB_2U_LIB.S9S_MB_2U(SCH_1):GND
  273  GND            VSS119  @S9S_MB_2U_LIB.S9S_MB_2U(SCH_1):GND
  270  GND            VSS118  @S9S_MB_2U_LIB.S9S_MB_2U(SCH_1):GND
  268  GND            VSS117  @S9S_MB_2U_LIB.S9S_MB_2U(SCH_1):GND
  266  GND            VSS116  @S9S_MB_2U_LIB.S9S_MB_2U(SCH_1):GND
  264  GND            VSS115  @S9S_MB_2U_LIB.S9S_MB_2U(SCH_1):GND
  262  GND            VSS114  @S9S_MB_2U_LIB.S9S_MB_2U(SCH_1):GND
  259  GND            VSS113  @S9S_MB_2U_LIB.S9S_MB_2U(SCH_1):GND
  257  GND            VSS112  @S9S_MB_2U_LIB.S9S_MB_2U(SCH_1):GND
  255  GND            VSS111  @S9S_MB_2U_LIB.S9S_MB_2U(SCH_1):GND
  253  GND            VSS110  @S9S_MB_2U_LIB.S9S_MB_2U(SCH_1):GND
  251  GND            VSS109  @S9S_MB_2U_LIB.S9S_MB_2U(SCH_1):GND
  248  GND            VSS108  @S9S_MB_2U_LIB.S9S_MB_2U(SCH_1):GND
  246  GND            VSS107  @S9S_MB_2U_LIB.S9S_MB_2U(SCH_1):GND
  244  GND            VSS106  @S9S_MB_2U_LIB.S9S_MB_2U(SCH_1):GND
  242  GND            VSS105  @S9S_MB_2U_LIB.S9S_MB_2U(SCH_1):GND
  240  GND            VSS104  @S9S_MB_2U_LIB.S9S_MB_2U(SCH_1):GND
  237  GND            VSS103  @S9S_MB_2U_LIB.S9S_MB_2U(SCH_1):GND
  235  GND            VSS102  @S9S_MB_2U_LIB.S9S_MB_2U(SCH_1):GND
  233  GND            VSS101  @S9S_MB_2U_LIB.S9S_MB_2U(SCH_1):GND
  230  GND            VSS100  @S9S_MB_2U_LIB.S9S_MB_2U(SCH_1):GND
  228  GND            VSS99  @S9S_MB_2U_LIB.S9S_MB_2U(SCH_1):GND
  226  GND            VSS98  @S9S_MB_2U_LIB.S9S_MB_2U(SCH_1):GND
  224  GND            VSS97  @S9S_MB_2U_LIB.S9S_MB_2U(SCH_1):GND
  222  GND            VSS96  @S9S_MB_2U_LIB.S9S_MB_2U(SCH_1):GND
  219  GND            VSS95  @S9S_MB_2U_LIB.S9S_MB_2U(SCH_1):GND
  216  GND            VSS94  @S9S_MB_2U_LIB.S9S_MB_2U(SCH_1):GND
  214  GND            VSS93  @S9S_MB_2U_LIB.S9S_MB_2U(SCH_1):GND
  212  GND            VSS92  @S9S_MB_2U_LIB.S9S_MB_2U(SCH_1):GND
  210  GND            VSS91  @S9S_MB_2U_LIB.S9S_MB_2U(SCH_1):GND
  208  GND            VSS90  @S9S_MB_2U_LIB.S9S_MB_2U(SCH_1):GND
  206  GND            VSS89  @S9S_MB_2U_LIB.S9S_MB_2U(SCH_1):GND
  204  GND            VSS88  @S9S_MB_2U_LIB.S9S_MB_2U(SCH_1):GND
  202  GND            VSS87  @S9S_MB_2U_LIB.S9S_MB_2U(SCH_1):GND
  199  GND            VSS86  @S9S_MB_2U_LIB.S9S_MB_2U(SCH_1):GND
  197  GND            VSS85  @S9S_MB_2U_LIB.S9S_MB_2U(SCH_1):GND
  195  GND            VSS84  @S9S_MB_2U_LIB.S9S_MB_2U(SCH_1):GND
  193  GND            VSS83  @S9S_MB_2U_LIB.S9S_MB_2U(SCH_1):GND
  191  GND            VSS82  @S9S_MB_2U_LIB.S9S_MB_2U(SCH_1):GND
  188  GND            VSS81  @S9S_MB_2U_LIB.S9S_MB_2U(SCH_1):GND
  186  GND            VSS80  @S9S_MB_2U_LIB.S9S_MB_2U(SCH_1):GND
  184  GND            VSS79  @S9S_MB_2U_LIB.S9S_MB_2U(SCH_1):GND
  182  GND            VSS78  @S9S_MB_2U_LIB.S9S_MB_2U(SCH_1):GND
  180  GND            VSS77  @S9S_MB_2U_LIB.S9S_MB_2U(SCH_1):GND
  177  GND            VSS76  @S9S_MB_2U_LIB.S9S_MB_2U(SCH_1):GND
  175  GND            VSS75  @S9S_MB_2U_LIB.S9S_MB_2U(SCH_1):GND
  173  GND            VSS74  @S9S_MB_2U_LIB.S9S_MB_2U(SCH_1):GND
  171  GND            VSS73  @S9S_MB_2U_LIB.S9S_MB_2U(SCH_1):GND
  169  GND            VSS72  @S9S_MB_2U_LIB.S9S_MB_2U(SCH_1):GND
  166  GND            VSS71  @S9S_MB_2U_LIB.S9S_MB_2U(SCH_1):GND
  164  GND            VSS70  @S9S_MB_2U_LIB.S9S_MB_2U(SCH_1):GND
  162  GND            VSS69  @S9S_MB_2U_LIB.S9S_MB_2U(SCH_1):GND
  160  GND            VSS68  @S9S_MB_2U_LIB.S9S_MB_2U(SCH_1):GND
  158  GND            VSS67  @S9S_MB_2U_LIB.S9S_MB_2U(SCH_1):GND
  155  GND            VSS66  @S9S_MB_2U_LIB.S9S_MB_2U(SCH_1):GND
  153  GND            VSS65  @S9S_MB_2U_LIB.S9S_MB_2U(SCH_1):GND
  151  GND            VSS64  @S9S_MB_2U_LIB.S9S_MB_2U(SCH_1):GND
  143  GND            VSS63  @S9S_MB_2U_LIB.S9S_MB_2U(SCH_1):GND
  141  GND            VSS62  @S9S_MB_2U_LIB.S9S_MB_2U(SCH_1):GND
  139  GND            VSS61  @S9S_MB_2U_LIB.S9S_MB_2U(SCH_1):GND
  136  GND            VSS60  @S9S_MB_2U_LIB.S9S_MB_2U(SCH_1):GND
  134  GND            VSS59  @S9S_MB_2U_LIB.S9S_MB_2U(SCH_1):GND
  132  GND            VSS58  @S9S_MB_2U_LIB.S9S_MB_2U(SCH_1):GND
  130  GND            VSS57  @S9S_MB_2U_LIB.S9S_MB_2U(SCH_1):GND
  128  GND            VSS56  @S9S_MB_2U_LIB.S9S_MB_2U(SCH_1):GND
  125  GND            VSS55  @S9S_MB_2U_LIB.S9S_MB_2U(SCH_1):GND
  123  GND            VSS54  @S9S_MB_2U_LIB.S9S_MB_2U(SCH_1):GND
  121  GND            VSS53  @S9S_MB_2U_LIB.S9S_MB_2U(SCH_1):GND
  119  GND            VSS52  @S9S_MB_2U_LIB.S9S_MB_2U(SCH_1):GND
  117  GND            VSS51  @S9S_MB_2U_LIB.S9S_MB_2U(SCH_1):GND
  114  GND            VSS50  @S9S_MB_2U_LIB.S9S_MB_2U(SCH_1):GND
  112  GND            VSS49  @S9S_MB_2U_LIB.S9S_MB_2U(SCH_1):GND
  110  GND            VSS48  @S9S_MB_2U_LIB.S9S_MB_2U(SCH_1):GND
  108  GND            VSS47  @S9S_MB_2U_LIB.S9S_MB_2U(SCH_1):GND
  106  GND            VSS46  @S9S_MB_2U_LIB.S9S_MB_2U(SCH_1):GND
  103  GND            VSS45  @S9S_MB_2U_LIB.S9S_MB_2U(SCH_1):GND
  101  GND            VSS44  @S9S_MB_2U_LIB.S9S_MB_2U(SCH_1):GND
   99  GND            VSS43  @S9S_MB_2U_LIB.S9S_MB_2U(SCH_1):GND
   97  GND            VSS42  @S9S_MB_2U_LIB.S9S_MB_2U(SCH_1):GND
   95  GND            VSS41  @S9S_MB_2U_LIB.S9S_MB_2U(SCH_1):GND
   92  GND            VSS40  @S9S_MB_2U_LIB.S9S_MB_2U(SCH_1):GND
   90  GND            VSS39  @S9S_MB_2U_LIB.S9S_MB_2U(SCH_1):GND
   88  GND            VSS38  @S9S_MB_2U_LIB.S9S_MB_2U(SCH_1):GND
   85  GND            VSS37  @S9S_MB_2U_LIB.S9S_MB_2U(SCH_1):GND
   83  GND            VSS36  @S9S_MB_2U_LIB.S9S_MB_2U(SCH_1):GND
   81  GND            VSS35  @S9S_MB_2U_LIB.S9S_MB_2U(SCH_1):GND
   79  GND            VSS34  @S9S_MB_2U_LIB.S9S_MB_2U(SCH_1):GND
   77  GND            VSS33  @S9S_MB_2U_LIB.S9S_MB_2U(SCH_1):GND
   75  GND            VSS32  @S9S_MB_2U_LIB.S9S_MB_2U(SCH_1):GND
   73  GND            VSS31  @S9S_MB_2U_LIB.S9S_MB_2U(SCH_1):GND
   71  GND            VSS30  @S9S_MB_2U_LIB.S9S_MB_2U(SCH_1):GND
   69  GND            VSS29  @S9S_MB_2U_LIB.S9S_MB_2U(SCH_1):GND
   67  GND            VSS28  @S9S_MB_2U_LIB.S9S_MB_2U(SCH_1):GND
   65  GND            VSS27  @S9S_MB_2U_LIB.S9S_MB_2U(SCH_1):GND
   63  GND            VSS26  @S9S_MB_2U_LIB.S9S_MB_2U(SCH_1):GND
   61  GND            VSS25  @S9S_MB_2U_LIB.S9S_MB_2U(SCH_1):GND
   59  GND            VSS24  @S9S_MB_2U_LIB.S9S_MB_2U(SCH_1):GND
   57  GND            VSS23  @S9S_MB_2U_LIB.S9S_MB_2U(SCH_1):GND
   54  GND            VSS22  @S9S_MB_2U_LIB.S9S_MB_2U(SCH_1):GND
   52  GND            VSS21  @S9S_MB_2U_LIB.S9S_MB_2U(SCH_1):GND
   50  GND            VSS20  @S9S_MB_2U_LIB.S9S_MB_2U(SCH_1):GND
   48  GND            VSS19  @S9S_MB_2U_LIB.S9S_MB_2U(SCH_1):GND
   46  GND            VSS18  @S9S_MB_2U_LIB.S9S_MB_2U(SCH_1):GND
   43  GND            VSS17  @S9S_MB_2U_LIB.S9S_MB_2U(SCH_1):GND
   41  GND            VSS16  @S9S_MB_2U_LIB.S9S_MB_2U(SCH_1):GND
   39  GND            VSS15  @S9S_MB_2U_LIB.S9S_MB_2U(SCH_1):GND
   37  GND            VSS14  @S9S_MB_2U_LIB.S9S_MB_2U(SCH_1):GND
   35  GND            VSS13  @S9S_MB_2U_LIB.S9S_MB_2U(SCH_1):GND
   32  GND            VSS12  @S9S_MB_2U_LIB.S9S_MB_2U(SCH_1):GND
   30  GND            VSS11  @S9S_MB_2U_LIB.S9S_MB_2U(SCH_1):GND
   28  GND            VSS10  @S9S_MB_2U_LIB.S9S_MB_2U(SCH_1):GND
   26  GND             VSS9  @S9S_MB_2U_LIB.S9S_MB_2U(SCH_1):GND
   24  GND             VSS8  @S9S_MB_2U_LIB.S9S_MB_2U(SCH_1):GND
   21  GND             VSS7  @S9S_MB_2U_LIB.S9S_MB_2U(SCH_1):GND
   19  GND             VSS6  @S9S_MB_2U_LIB.S9S_MB_2U(SCH_1):GND
   17  GND             VSS5  @S9S_MB_2U_LIB.S9S_MB_2U(SCH_1):GND
   15  GND             VSS4  @S9S_MB_2U_LIB.S9S_MB_2U(SCH_1):GND
   13  GND             VSS3  @S9S_MB_2U_LIB.S9S_MB_2U(SCH_1):GND
   10  GND             VSS2  @S9S_MB_2U_LIB.S9S_MB_2U(SCH_1):GND
    8  GND             VSS1  @S9S_MB_2U_LIB.S9S_MB_2U(SCH_1):GND
    6  GND             VSS0  @S9S_MB_2U_LIB.S9S_MB_2U(SCH_1):GND
   G3  GND               G3  @S9S_MB_2U_LIB.S9S_MB_2U(SCH_1):GND
   G2  GND               G2  @S9S_MB_2U_LIB.S9S_MB_2U(SCH_1):GND
   G1  GND               G1  @S9S_MB_2U_LIB.S9S_MB_2U(SCH_1):GND

SCONN288_ADR50001P003C01  I178  J2     [SCONN288_ADR50001P003C01-SCONNA]
   93  M_A_CPU0_SB_DQS_DP<9>  DQS9_B_P  @S9S_MB_2U_LIB.S9S_MB_2U(SCH_1):M_A_CPU0_SB_DQS_DP<9>
  283  M_A_CPU0_SB_DQS_DP<8>  DQS8_B_P  @S9S_MB_2U_LIB.S9S_MB_2U(SCH_1):M_A_CPU0_SB_DQS_DP<8>
  272  M_A_CPU0_SB_DQS_DP<7>  DQS7_B_P  @S9S_MB_2U_LIB.S9S_MB_2U(SCH_1):M_A_CPU0_SB_DQS_DP<7>
  261  M_A_CPU0_SB_DQS_DP<6>  DQS6_B_P  @S9S_MB_2U_LIB.S9S_MB_2U(SCH_1):M_A_CPU0_SB_DQS_DP<6>
  250  M_A_CPU0_SB_DQS_DP<5>  DQS5_B_P  @S9S_MB_2U_LIB.S9S_MB_2U(SCH_1):M_A_CPU0_SB_DQS_DP<5>
  239  M_A_CPU0_SB_DQS_DP<4>  DQS4_B_P  @S9S_MB_2U_LIB.S9S_MB_2U(SCH_1):M_A_CPU0_SB_DQS_DP<4>
  137  M_A_CPU0_SB_DQS_DP<3>  DQS3_B_P  @S9S_MB_2U_LIB.S9S_MB_2U(SCH_1):M_A_CPU0_SB_DQS_DP<3>
  126  M_A_CPU0_SB_DQS_DP<2>  DQS2_B_P  @S9S_MB_2U_LIB.S9S_MB_2U(SCH_1):M_A_CPU0_SB_DQS_DP<2>
  115  M_A_CPU0_SB_DQS_DP<1>  DQS1_B_P  @S9S_MB_2U_LIB.S9S_MB_2U(SCH_1):M_A_CPU0_SB_DQS_DP<1>
  104  M_A_CPU0_SB_DQS_DP<0>  DQS0_B_P  @S9S_MB_2U_LIB.S9S_MB_2U(SCH_1):M_A_CPU0_SB_DQS_DP<0>
   94  M_A_CPU0_SB_DQS_DN<9>  DQS9_B_N  @S9S_MB_2U_LIB.S9S_MB_2U(SCH_1):M_A_CPU0_SB_DQS_DN<9>
  282  M_A_CPU0_SB_DQS_DN<8>  DQS8_B_N  @S9S_MB_2U_LIB.S9S_MB_2U(SCH_1):M_A_CPU0_SB_DQS_DN<8>
  271  M_A_CPU0_SB_DQS_DN<7>  DQS7_B_N  @S9S_MB_2U_LIB.S9S_MB_2U(SCH_1):M_A_CPU0_SB_DQS_DN<7>
  260  M_A_CPU0_SB_DQS_DN<6>  DQS6_B_N  @S9S_MB_2U_LIB.S9S_MB_2U(SCH_1):M_A_CPU0_SB_DQS_DN<6>
  249  M_A_CPU0_SB_DQS_DN<5>  DQS5_B_N  @S9S_MB_2U_LIB.S9S_MB_2U(SCH_1):M_A_CPU0_SB_DQS_DN<5>
  238  M_A_CPU0_SB_DQS_DN<4>  DQS4_B_N  @S9S_MB_2U_LIB.S9S_MB_2U(SCH_1):M_A_CPU0_SB_DQS_DN<4>
  138  M_A_CPU0_SB_DQS_DN<3>  DQS3_B_N  @S9S_MB_2U_LIB.S9S_MB_2U(SCH_1):M_A_CPU0_SB_DQS_DN<3>
  127  M_A_CPU0_SB_DQS_DN<2>  DQS2_B_N  @S9S_MB_2U_LIB.S9S_MB_2U(SCH_1):M_A_CPU0_SB_DQS_DN<2>
  116  M_A_CPU0_SB_DQS_DN<1>  DQS1_B_N  @S9S_MB_2U_LIB.S9S_MB_2U(SCH_1):M_A_CPU0_SB_DQS_DN<1>
  105  M_A_CPU0_SB_DQS_DN<0>  DQS0_B_N  @S9S_MB_2U_LIB.S9S_MB_2U(SCH_1):M_A_CPU0_SB_DQS_DN<0>
  201  M_A_CPU0_SA_DQS_DP<9>  DQS9_A_P  @S9S_MB_2U_LIB.S9S_MB_2U(SCH_1):M_A_CPU0_SA_DQS_DP<9>
  190  M_A_CPU0_SA_DQS_DP<8>  DQS8_A_P  @S9S_MB_2U_LIB.S9S_MB_2U(SCH_1):M_A_CPU0_SA_DQS_DP<8>
  179  M_A_CPU0_SA_DQS_DP<7>  DQS7_A_P  @S9S_MB_2U_LIB.S9S_MB_2U(SCH_1):M_A_CPU0_SA_DQS_DP<7>
  168  M_A_CPU0_SA_DQS_DP<6>  DQS6_A_P  @S9S_MB_2U_LIB.S9S_MB_2U(SCH_1):M_A_CPU0_SA_DQS_DP<6>
  157  M_A_CPU0_SA_DQS_DP<5>  DQS5_A_P  @S9S_MB_2U_LIB.S9S_MB_2U(SCH_1):M_A_CPU0_SA_DQS_DP<5>
   55  M_A_CPU0_SA_DQS_DP<4>  DQS4_A_P  @S9S_MB_2U_LIB.S9S_MB_2U(SCH_1):M_A_CPU0_SA_DQS_DP<4>
   44  M_A_CPU0_SA_DQS_DP<3>  DQS3_A_P  @S9S_MB_2U_LIB.S9S_MB_2U(SCH_1):M_A_CPU0_SA_DQS_DP<3>
   33  M_A_CPU0_SA_DQS_DP<2>  DQS2_A_P  @S9S_MB_2U_LIB.S9S_MB_2U(SCH_1):M_A_CPU0_SA_DQS_DP<2>
   22  M_A_CPU0_SA_DQS_DP<1>  DQS1_A_P  @S9S_MB_2U_LIB.S9S_MB_2U(SCH_1):M_A_CPU0_SA_DQS_DP<1>
   11  M_A_CPU0_SA_DQS_DP<0>  DQS0_A_P  @S9S_MB_2U_LIB.S9S_MB_2U(SCH_1):M_A_CPU0_SA_DQS_DP<0>
  200  M_A_CPU0_SA_DQS_DN<9>  DQS9_A_N  @S9S_MB_2U_LIB.S9S_MB_2U(SCH_1):M_A_CPU0_SA_DQS_DN<9>
  189  M_A_CPU0_SA_DQS_DN<8>  DQS8_A_N  @S9S_MB_2U_LIB.S9S_MB_2U(SCH_1):M_A_CPU0_SA_DQS_DN<8>
  178  M_A_CPU0_SA_DQS_DN<7>  DQS7_A_N  @S9S_MB_2U_LIB.S9S_MB_2U(SCH_1):M_A_CPU0_SA_DQS_DN<7>
  167  M_A_CPU0_SA_DQS_DN<6>  DQS6_A_N  @S9S_MB_2U_LIB.S9S_MB_2U(SCH_1):M_A_CPU0_SA_DQS_DN<6>
  156  M_A_CPU0_SA_DQS_DN<5>  DQS5_A_N  @S9S_MB_2U_LIB.S9S_MB_2U(SCH_1):M_A_CPU0_SA_DQS_DN<5>
   56  M_A_CPU0_SA_DQS_DN<4>  DQS4_A_N  @S9S_MB_2U_LIB.S9S_MB_2U(SCH_1):M_A_CPU0_SA_DQS_DN<4>
   45  M_A_CPU0_SA_DQS_DN<3>  DQS3_A_N  @S9S_MB_2U_LIB.S9S_MB_2U(SCH_1):M_A_CPU0_SA_DQS_DN<3>
   34  M_A_CPU0_SA_DQS_DN<2>  DQS2_A_N  @S9S_MB_2U_LIB.S9S_MB_2U(SCH_1):M_A_CPU0_SA_DQS_DN<2>
   23  M_A_CPU0_SA_DQS_DN<1>  DQS1_A_N  @S9S_MB_2U_LIB.S9S_MB_2U(SCH_1):M_A_CPU0_SA_DQS_DN<1>
   12  M_A_CPU0_SA_DQS_DN<0>  DQS0_A_N  @S9S_MB_2U_LIB.S9S_MB_2U(SCH_1):M_A_CPU0_SA_DQS_DN<0>

SCONN288_ADR50001P003C01  I177  J2     [SCONN288_ADR50001P003C01-SCONNA]
  232  NC              RFU6  NC
  231  NC              RFU5  NC
  220  NC              RFU4  NC
  150  NC              RFU3  NC
  149  NC              RFU2  NC
  144  NC              RFU1  NC
    2  NC              RFU0  NC
  207  RST_M_AB_CPU0_FPGA_N  RESET_N  @S9S_MB_2U_LIB.S9S_MB_2U(SCH_1):RST_M_AB_CPU0_FPGA_N
  147  PWRGD_CHA_CPU0_DIMM2  PWR_GOOD||FAIL_N  @S9S_MB_2U_LIB.S9S_MB_2U(SCH_1):PWRGD_CHA_CPU0_DIMM2
  148  PD_CHA_CPU0_DIMM2_SAA    HAS  @S9S_MB_2U_LIB.S9S_MB_2U(SCH_1):PD_CHA_CPU0_DIMM2_SAA
    3  P3V3_AUX       VIN_MGMT  @S9S_MB_2U_LIB.S9S_MB_2U(SCH_1):P3V3_AUX
   87  M_A_CPU0_SB_RSP<1>  LBS||RSP_N_B  @S9S_MB_2U_LIB.S9S_MB_2U(SCH_1):M_A_CPU0_SB_RSP<1>
  227  M_A_CPU0_SB_PAR  PAR_B  @S9S_MB_2U_LIB.S9S_MB_2U(SCH_1):M_A_CPU0_SB_PAR
  113  M_A_CPU0_SB_DQ<9>  DQ_B9  @S9S_MB_2U_LIB.S9S_MB_2U(SCH_1):M_A_CPU0_SB_DQ<9>
  111  M_A_CPU0_SB_DQ<8>  DQ_B8  @S9S_MB_2U_LIB.S9S_MB_2U(SCH_1):M_A_CPU0_SB_DQ<8>
  254  M_A_CPU0_SB_DQ<7>  DQ_B7  @S9S_MB_2U_LIB.S9S_MB_2U(SCH_1):M_A_CPU0_SB_DQ<7>
  252  M_A_CPU0_SB_DQ<6>  DQ_B6  @S9S_MB_2U_LIB.S9S_MB_2U(SCH_1):M_A_CPU0_SB_DQ<6>
  109  M_A_CPU0_SB_DQ<5>  DQ_B5  @S9S_MB_2U_LIB.S9S_MB_2U(SCH_1):M_A_CPU0_SB_DQ<5>
  107  M_A_CPU0_SB_DQ<4>  DQ_B4  @S9S_MB_2U_LIB.S9S_MB_2U(SCH_1):M_A_CPU0_SB_DQ<4>
  247  M_A_CPU0_SB_DQ<3>  DQ_B3  @S9S_MB_2U_LIB.S9S_MB_2U(SCH_1):M_A_CPU0_SB_DQ<3>
  287  M_A_CPU0_SB_DQ<31>  DQ_B31  @S9S_MB_2U_LIB.S9S_MB_2U(SCH_1):M_A_CPU0_SB_DQ<31>
  285  M_A_CPU0_SB_DQ<30>  DQ_B30  @S9S_MB_2U_LIB.S9S_MB_2U(SCH_1):M_A_CPU0_SB_DQ<30>
  245  M_A_CPU0_SB_DQ<2>  DQ_B2  @S9S_MB_2U_LIB.S9S_MB_2U(SCH_1):M_A_CPU0_SB_DQ<2>
  142  M_A_CPU0_SB_DQ<29>  DQ_B29  @S9S_MB_2U_LIB.S9S_MB_2U(SCH_1):M_A_CPU0_SB_DQ<29>
  140  M_A_CPU0_SB_DQ<28>  DQ_B28  @S9S_MB_2U_LIB.S9S_MB_2U(SCH_1):M_A_CPU0_SB_DQ<28>
  280  M_A_CPU0_SB_DQ<27>  DQ_B27  @S9S_MB_2U_LIB.S9S_MB_2U(SCH_1):M_A_CPU0_SB_DQ<27>
  278  M_A_CPU0_SB_DQ<26>  DQ_B26  @S9S_MB_2U_LIB.S9S_MB_2U(SCH_1):M_A_CPU0_SB_DQ<26>
  135  M_A_CPU0_SB_DQ<25>  DQ_B25  @S9S_MB_2U_LIB.S9S_MB_2U(SCH_1):M_A_CPU0_SB_DQ<25>
  133  M_A_CPU0_SB_DQ<24>  DQ_B24  @S9S_MB_2U_LIB.S9S_MB_2U(SCH_1):M_A_CPU0_SB_DQ<24>
  276  M_A_CPU0_SB_DQ<23>  DQ_B23  @S9S_MB_2U_LIB.S9S_MB_2U(SCH_1):M_A_CPU0_SB_DQ<23>
  274  M_A_CPU0_SB_DQ<22>  DQ_B22  @S9S_MB_2U_LIB.S9S_MB_2U(SCH_1):M_A_CPU0_SB_DQ<22>
  131  M_A_CPU0_SB_DQ<21>  DQ_B21  @S9S_MB_2U_LIB.S9S_MB_2U(SCH_1):M_A_CPU0_SB_DQ<21>
  129  M_A_CPU0_SB_DQ<20>  DQ_B20  @S9S_MB_2U_LIB.S9S_MB_2U(SCH_1):M_A_CPU0_SB_DQ<20>
  102  M_A_CPU0_SB_DQ<1>  DQ_B1  @S9S_MB_2U_LIB.S9S_MB_2U(SCH_1):M_A_CPU0_SB_DQ<1>
  269  M_A_CPU0_SB_DQ<19>  DQ_B19  @S9S_MB_2U_LIB.S9S_MB_2U(SCH_1):M_A_CPU0_SB_DQ<19>
  267  M_A_CPU0_SB_DQ<18>  DQ_B18  @S9S_MB_2U_LIB.S9S_MB_2U(SCH_1):M_A_CPU0_SB_DQ<18>
  124  M_A_CPU0_SB_DQ<17>  DQ_B17  @S9S_MB_2U_LIB.S9S_MB_2U(SCH_1):M_A_CPU0_SB_DQ<17>
  122  M_A_CPU0_SB_DQ<16>  DQ_B16  @S9S_MB_2U_LIB.S9S_MB_2U(SCH_1):M_A_CPU0_SB_DQ<16>
  265  M_A_CPU0_SB_DQ<15>  DQ_B15  @S9S_MB_2U_LIB.S9S_MB_2U(SCH_1):M_A_CPU0_SB_DQ<15>
  263  M_A_CPU0_SB_DQ<14>  DQ_B14  @S9S_MB_2U_LIB.S9S_MB_2U(SCH_1):M_A_CPU0_SB_DQ<14>
  120  M_A_CPU0_SB_DQ<13>  DQ_B13  @S9S_MB_2U_LIB.S9S_MB_2U(SCH_1):M_A_CPU0_SB_DQ<13>
  118  M_A_CPU0_SB_DQ<12>  DQ_B12  @S9S_MB_2U_LIB.S9S_MB_2U(SCH_1):M_A_CPU0_SB_DQ<12>
  258  M_A_CPU0_SB_DQ<11>  DQ_B11  @S9S_MB_2U_LIB.S9S_MB_2U(SCH_1):M_A_CPU0_SB_DQ<11>
  256  M_A_CPU0_SB_DQ<10>  DQ_B10  @S9S_MB_2U_LIB.S9S_MB_2U(SCH_1):M_A_CPU0_SB_DQ<10>
  100  M_A_CPU0_SB_DQ<0>  DQ_B0  @S9S_MB_2U_LIB.S9S_MB_2U(SCH_1):M_A_CPU0_SB_DQ<0>
  229  M_A_CPU0_SB_CS_N<3>  CS1_N_B  @S9S_MB_2U_LIB.S9S_MB_2U(SCH_1):M_A_CPU0_SB_CS_N<3>
   84  M_A_CPU0_SB_CS_N<2>  CS0_N_B  @S9S_MB_2U_LIB.S9S_MB_2U(SCH_1):M_A_CPU0_SB_CS_N<2>
  236  M_A_CPU0_SB_CB<7>  CB_B7  @S9S_MB_2U_LIB.S9S_MB_2U(SCH_1):M_A_CPU0_SB_CB<7>
  234  M_A_CPU0_SB_CB<6>  CB_B6  @S9S_MB_2U_LIB.S9S_MB_2U(SCH_1):M_A_CPU0_SB_CB<6>
   91  M_A_CPU0_SB_CB<5>  CB_B5  @S9S_MB_2U_LIB.S9S_MB_2U(SCH_1):M_A_CPU0_SB_CB<5>
   89  M_A_CPU0_SB_CB<4>  CB_B4  @S9S_MB_2U_LIB.S9S_MB_2U(SCH_1):M_A_CPU0_SB_CB<4>
  243  M_A_CPU0_SB_CB<3>  CB_B3  @S9S_MB_2U_LIB.S9S_MB_2U(SCH_1):M_A_CPU0_SB_CB<3>
  241  M_A_CPU0_SB_CB<2>  CB_B2  @S9S_MB_2U_LIB.S9S_MB_2U(SCH_1):M_A_CPU0_SB_CB<2>
   98  M_A_CPU0_SB_CB<1>  CB_B1  @S9S_MB_2U_LIB.S9S_MB_2U(SCH_1):M_A_CPU0_SB_CB<1>
   96  M_A_CPU0_SB_CB<0>  CB_B0  @S9S_MB_2U_LIB.S9S_MB_2U(SCH_1):M_A_CPU0_SB_CB<0>
   82  M_A_CPU0_SB_CA<6>  CA6_B  @S9S_MB_2U_LIB.S9S_MB_2U(SCH_1):M_A_CPU0_SB_CA<6>
  225  M_A_CPU0_SB_CA<5>  CA5_B  @S9S_MB_2U_LIB.S9S_MB_2U(SCH_1):M_A_CPU0_SB_CA<5>
   80  M_A_CPU0_SB_CA<4>  CA4_B  @S9S_MB_2U_LIB.S9S_MB_2U(SCH_1):M_A_CPU0_SB_CA<4>
  223  M_A_CPU0_SB_CA<3>  CA3_B  @S9S_MB_2U_LIB.S9S_MB_2U(SCH_1):M_A_CPU0_SB_CA<3>
   78  M_A_CPU0_SB_CA<2>  CA2_B  @S9S_MB_2U_LIB.S9S_MB_2U(SCH_1):M_A_CPU0_SB_CA<2>
  221  M_A_CPU0_SB_CA<1>  CA1_B  @S9S_MB_2U_LIB.S9S_MB_2U(SCH_1):M_A_CPU0_SB_CA<1>
   76  M_A_CPU0_SB_CA<0>  CA0_B  @S9S_MB_2U_LIB.S9S_MB_2U(SCH_1):M_A_CPU0_SB_CA<0>
   86  M_A_CPU0_SA_RSP<1>  LBD||RSP_N_A  @S9S_MB_2U_LIB.S9S_MB_2U(SCH_1):M_A_CPU0_SA_RSP<1>
   74  M_A_CPU0_SA_PAR  PAR_A  @S9S_MB_2U_LIB.S9S_MB_2U(SCH_1):M_A_CPU0_SA_PAR
   20  M_A_CPU0_SA_DQ<9>  DQ_A9  @S9S_MB_2U_LIB.S9S_MB_2U(SCH_1):M_A_CPU0_SA_DQ<9>
   18  M_A_CPU0_SA_DQ<8>  DQ_A8  @S9S_MB_2U_LIB.S9S_MB_2U(SCH_1):M_A_CPU0_SA_DQ<8>
  161  M_A_CPU0_SA_DQ<7>  DQ_A7  @S9S_MB_2U_LIB.S9S_MB_2U(SCH_1):M_A_CPU0_SA_DQ<7>
  159  M_A_CPU0_SA_DQ<6>  DQ_A6  @S9S_MB_2U_LIB.S9S_MB_2U(SCH_1):M_A_CPU0_SA_DQ<6>
   16  M_A_CPU0_SA_DQ<5>  DQ_A5  @S9S_MB_2U_LIB.S9S_MB_2U(SCH_1):M_A_CPU0_SA_DQ<5>
   14  M_A_CPU0_SA_DQ<4>  DQ_A4  @S9S_MB_2U_LIB.S9S_MB_2U(SCH_1):M_A_CPU0_SA_DQ<4>
  154  M_A_CPU0_SA_DQ<3>  DQ_A3  @S9S_MB_2U_LIB.S9S_MB_2U(SCH_1):M_A_CPU0_SA_DQ<3>
  194  M_A_CPU0_SA_DQ<31>  DQ_A31  @S9S_MB_2U_LIB.S9S_MB_2U(SCH_1):M_A_CPU0_SA_DQ<31>
  192  M_A_CPU0_SA_DQ<30>  DQ_A30  @S9S_MB_2U_LIB.S9S_MB_2U(SCH_1):M_A_CPU0_SA_DQ<30>
  152  M_A_CPU0_SA_DQ<2>  DQ_A2  @S9S_MB_2U_LIB.S9S_MB_2U(SCH_1):M_A_CPU0_SA_DQ<2>
   49  M_A_CPU0_SA_DQ<29>  DQ_A29  @S9S_MB_2U_LIB.S9S_MB_2U(SCH_1):M_A_CPU0_SA_DQ<29>
   47  M_A_CPU0_SA_DQ<28>  DQ_A28  @S9S_MB_2U_LIB.S9S_MB_2U(SCH_1):M_A_CPU0_SA_DQ<28>
  187  M_A_CPU0_SA_DQ<27>  DQ_A27  @S9S_MB_2U_LIB.S9S_MB_2U(SCH_1):M_A_CPU0_SA_DQ<27>
  185  M_A_CPU0_SA_DQ<26>  DQ_A26  @S9S_MB_2U_LIB.S9S_MB_2U(SCH_1):M_A_CPU0_SA_DQ<26>
   42  M_A_CPU0_SA_DQ<25>  DQ_A25  @S9S_MB_2U_LIB.S9S_MB_2U(SCH_1):M_A_CPU0_SA_DQ<25>
   40  M_A_CPU0_SA_DQ<24>  DQ_A24  @S9S_MB_2U_LIB.S9S_MB_2U(SCH_1):M_A_CPU0_SA_DQ<24>
  183  M_A_CPU0_SA_DQ<23>  DQ_A23  @S9S_MB_2U_LIB.S9S_MB_2U(SCH_1):M_A_CPU0_SA_DQ<23>
  181  M_A_CPU0_SA_DQ<22>  DQ_A22  @S9S_MB_2U_LIB.S9S_MB_2U(SCH_1):M_A_CPU0_SA_DQ<22>
   38  M_A_CPU0_SA_DQ<21>  DQ_A21  @S9S_MB_2U_LIB.S9S_MB_2U(SCH_1):M_A_CPU0_SA_DQ<21>
   36  M_A_CPU0_SA_DQ<20>  DQ_A20  @S9S_MB_2U_LIB.S9S_MB_2U(SCH_1):M_A_CPU0_SA_DQ<20>
    9  M_A_CPU0_SA_DQ<1>  DQ_A1  @S9S_MB_2U_LIB.S9S_MB_2U(SCH_1):M_A_CPU0_SA_DQ<1>
  176  M_A_CPU0_SA_DQ<19>  DQ_A19  @S9S_MB_2U_LIB.S9S_MB_2U(SCH_1):M_A_CPU0_SA_DQ<19>
  174  M_A_CPU0_SA_DQ<18>  DQ_A18  @S9S_MB_2U_LIB.S9S_MB_2U(SCH_1):M_A_CPU0_SA_DQ<18>
   31  M_A_CPU0_SA_DQ<17>  DQ_A17  @S9S_MB_2U_LIB.S9S_MB_2U(SCH_1):M_A_CPU0_SA_DQ<17>
   29  M_A_CPU0_SA_DQ<16>  DQ_A16  @S9S_MB_2U_LIB.S9S_MB_2U(SCH_1):M_A_CPU0_SA_DQ<16>
  172  M_A_CPU0_SA_DQ<15>  DQ_A15  @S9S_MB_2U_LIB.S9S_MB_2U(SCH_1):M_A_CPU0_SA_DQ<15>
  170  M_A_CPU0_SA_DQ<14>  DQ_A14  @S9S_MB_2U_LIB.S9S_MB_2U(SCH_1):M_A_CPU0_SA_DQ<14>
   27  M_A_CPU0_SA_DQ<13>  DQ_A13  @S9S_MB_2U_LIB.S9S_MB_2U(SCH_1):M_A_CPU0_SA_DQ<13>
   25  M_A_CPU0_SA_DQ<12>  DQ_A12  @S9S_MB_2U_LIB.S9S_MB_2U(SCH_1):M_A_CPU0_SA_DQ<12>
  165  M_A_CPU0_SA_DQ<11>  DQ_A11  @S9S_MB_2U_LIB.S9S_MB_2U(SCH_1):M_A_CPU0_SA_DQ<11>
  163  M_A_CPU0_SA_DQ<10>  DQ_A10  @S9S_MB_2U_LIB.S9S_MB_2U(SCH_1):M_A_CPU0_SA_DQ<10>
    7  M_A_CPU0_SA_DQ<0>  DQ_A0  @S9S_MB_2U_LIB.S9S_MB_2U(SCH_1):M_A_CPU0_SA_DQ<0>
  209  M_A_CPU0_SA_CS_N<3>  CS1_N_A  @S9S_MB_2U_LIB.S9S_MB_2U(SCH_1):M_A_CPU0_SA_CS_N<3>
   64  M_A_CPU0_SA_CS_N<2>  CS0_N_A  @S9S_MB_2U_LIB.S9S_MB_2U(SCH_1):M_A_CPU0_SA_CS_N<2>
  205  M_A_CPU0_SA_CB<7>  CB_A7  @S9S_MB_2U_LIB.S9S_MB_2U(SCH_1):M_A_CPU0_SA_CB<7>
  203  M_A_CPU0_SA_CB<6>  CB_A6  @S9S_MB_2U_LIB.S9S_MB_2U(SCH_1):M_A_CPU0_SA_CB<6>
   60  M_A_CPU0_SA_CB<5>  CB_A5  @S9S_MB_2U_LIB.S9S_MB_2U(SCH_1):M_A_CPU0_SA_CB<5>
   58  M_A_CPU0_SA_CB<4>  CB_A4  @S9S_MB_2U_LIB.S9S_MB_2U(SCH_1):M_A_CPU0_SA_CB<4>
  198  M_A_CPU0_SA_CB<3>  CB_A3  @S9S_MB_2U_LIB.S9S_MB_2U(SCH_1):M_A_CPU0_SA_CB<3>
  196  M_A_CPU0_SA_CB<2>  CB_A2  @S9S_MB_2U_LIB.S9S_MB_2U(SCH_1):M_A_CPU0_SA_CB<2>
   53  M_A_CPU0_SA_CB<1>  CB_A1  @S9S_MB_2U_LIB.S9S_MB_2U(SCH_1):M_A_CPU0_SA_CB<1>
   51  M_A_CPU0_SA_CB<0>  CB_A0  @S9S_MB_2U_LIB.S9S_MB_2U(SCH_1):M_A_CPU0_SA_CB<0>
   72  M_A_CPU0_SA_CA<6>  CA6_A  @S9S_MB_2U_LIB.S9S_MB_2U(SCH_1):M_A_CPU0_SA_CA<6>
  215  M_A_CPU0_SA_CA<5>  CA5_A  @S9S_MB_2U_LIB.S9S_MB_2U(SCH_1):M_A_CPU0_SA_CA<5>
   70  M_A_CPU0_SA_CA<4>  CA4_A  @S9S_MB_2U_LIB.S9S_MB_2U(SCH_1):M_A_CPU0_SA_CA<4>
  213  M_A_CPU0_SA_CA<3>  CA3_A  @S9S_MB_2U_LIB.S9S_MB_2U(SCH_1):M_A_CPU0_SA_CA<3>
   68  M_A_CPU0_SA_CA<2>  CA2_A  @S9S_MB_2U_LIB.S9S_MB_2U(SCH_1):M_A_CPU0_SA_CA<2>
  211  M_A_CPU0_SA_CA<1>  CA1_A  @S9S_MB_2U_LIB.S9S_MB_2U(SCH_1):M_A_CPU0_SA_CA<1>
   66  M_A_CPU0_SA_CA<0>  CA0_A  @S9S_MB_2U_LIB.S9S_MB_2U(SCH_1):M_A_CPU0_SA_CA<0>
  217  M_A_CPU0_CLK_DP<1>   CK_P  @S9S_MB_2U_LIB.S9S_MB_2U(SCH_1):M_A_CPU0_CLK_DP<1>
  218  M_A_CPU0_CLK_DN<1>   CK_N  @S9S_MB_2U_LIB.S9S_MB_2U(SCH_1):M_A_CPU0_CLK_DN<1>
   62  M_A_CPU0_ALERT_N  ALERT_N  @S9S_MB_2U_LIB.S9S_MB_2U(SCH_1):M_A_CPU0_ALERT_N
    5  I3C_SPD_DDRABCD_CPU0_LVC1_SDA   HSDA  @S9S_MB_2U_LIB.S9S_MB_2U(SCH_1):I3C_SPD_DDRABCD_CPU0_LVC1_SDA
    4  I3C_SPD_DDRABCD_CPU0_LVC1_SCL   HSCL  @S9S_MB_2U_LIB.S9S_MB_2U(SCH_1):I3C_SPD_DDRABCD_CPU0_LVC1_SCL

SCONN288_ADR50001P013C01  I146  J3     [SCONN288_ADR50001P013C01-SCONNA]
  146  P12V_S3_AUX_CPU0_NVDIMM  VIN_BULK2  @S9S_MB_2U_LIB.S9S_MB_2U(SCH_1):P12V_S3_AUX_CPU0_NVDIMM
  145  P12V_S3_AUX_CPU0_NVDIMM  VIN_BULK1  @S9S_MB_2U_LIB.S9S_MB_2U(SCH_1):P12V_S3_AUX_CPU0_NVDIMM
    1  P12V_S3_AUX_CPU0_NVDIMM  VIN_BULK0  @S9S_MB_2U_LIB.S9S_MB_2U(SCH_1):P12V_S3_AUX_CPU0_NVDIMM
  288  GND            VSS126  @S9S_MB_2U_LIB.S9S_MB_2U(SCH_1):GND
  286  GND            VSS125  @S9S_MB_2U_LIB.S9S_MB_2U(SCH_1):GND
  284  GND            VSS124  @S9S_MB_2U_LIB.S9S_MB_2U(SCH_1):GND
  281  GND            VSS123  @S9S_MB_2U_LIB.S9S_MB_2U(SCH_1):GND
  279  GND            VSS122  @S9S_MB_2U_LIB.S9S_MB_2U(SCH_1):GND
  277  GND            VSS121  @S9S_MB_2U_LIB.S9S_MB_2U(SCH_1):GND
  275  GND            VSS120  @S9S_MB_2U_LIB.S9S_MB_2U(SCH_1):GND
  273  GND            VSS119  @S9S_MB_2U_LIB.S9S_MB_2U(SCH_1):GND
  270  GND            VSS118  @S9S_MB_2U_LIB.S9S_MB_2U(SCH_1):GND
  268  GND            VSS117  @S9S_MB_2U_LIB.S9S_MB_2U(SCH_1):GND
  266  GND            VSS116  @S9S_MB_2U_LIB.S9S_MB_2U(SCH_1):GND
  264  GND            VSS115  @S9S_MB_2U_LIB.S9S_MB_2U(SCH_1):GND
  262  GND            VSS114  @S9S_MB_2U_LIB.S9S_MB_2U(SCH_1):GND
  259  GND            VSS113  @S9S_MB_2U_LIB.S9S_MB_2U(SCH_1):GND
  257  GND            VSS112  @S9S_MB_2U_LIB.S9S_MB_2U(SCH_1):GND
  255  GND            VSS111  @S9S_MB_2U_LIB.S9S_MB_2U(SCH_1):GND
  253  GND            VSS110  @S9S_MB_2U_LIB.S9S_MB_2U(SCH_1):GND
  251  GND            VSS109  @S9S_MB_2U_LIB.S9S_MB_2U(SCH_1):GND
  248  GND            VSS108  @S9S_MB_2U_LIB.S9S_MB_2U(SCH_1):GND
  246  GND            VSS107  @S9S_MB_2U_LIB.S9S_MB_2U(SCH_1):GND
  244  GND            VSS106  @S9S_MB_2U_LIB.S9S_MB_2U(SCH_1):GND
  242  GND            VSS105  @S9S_MB_2U_LIB.S9S_MB_2U(SCH_1):GND
  240  GND            VSS104  @S9S_MB_2U_LIB.S9S_MB_2U(SCH_1):GND
  237  GND            VSS103  @S9S_MB_2U_LIB.S9S_MB_2U(SCH_1):GND
  235  GND            VSS102  @S9S_MB_2U_LIB.S9S_MB_2U(SCH_1):GND
  233  GND            VSS101  @S9S_MB_2U_LIB.S9S_MB_2U(SCH_1):GND
  230  GND            VSS100  @S9S_MB_2U_LIB.S9S_MB_2U(SCH_1):GND
  228  GND            VSS99  @S9S_MB_2U_LIB.S9S_MB_2U(SCH_1):GND
  226  GND            VSS98  @S9S_MB_2U_LIB.S9S_MB_2U(SCH_1):GND
  224  GND            VSS97  @S9S_MB_2U_LIB.S9S_MB_2U(SCH_1):GND
  222  GND            VSS96  @S9S_MB_2U_LIB.S9S_MB_2U(SCH_1):GND
  219  GND            VSS95  @S9S_MB_2U_LIB.S9S_MB_2U(SCH_1):GND
  216  GND            VSS94  @S9S_MB_2U_LIB.S9S_MB_2U(SCH_1):GND
  214  GND            VSS93  @S9S_MB_2U_LIB.S9S_MB_2U(SCH_1):GND
  212  GND            VSS92  @S9S_MB_2U_LIB.S9S_MB_2U(SCH_1):GND
  210  GND            VSS91  @S9S_MB_2U_LIB.S9S_MB_2U(SCH_1):GND
  208  GND            VSS90  @S9S_MB_2U_LIB.S9S_MB_2U(SCH_1):GND
  206  GND            VSS89  @S9S_MB_2U_LIB.S9S_MB_2U(SCH_1):GND
  204  GND            VSS88  @S9S_MB_2U_LIB.S9S_MB_2U(SCH_1):GND
  202  GND            VSS87  @S9S_MB_2U_LIB.S9S_MB_2U(SCH_1):GND
  199  GND            VSS86  @S9S_MB_2U_LIB.S9S_MB_2U(SCH_1):GND
  197  GND            VSS85  @S9S_MB_2U_LIB.S9S_MB_2U(SCH_1):GND
  195  GND            VSS84  @S9S_MB_2U_LIB.S9S_MB_2U(SCH_1):GND
  193  GND            VSS83  @S9S_MB_2U_LIB.S9S_MB_2U(SCH_1):GND
  191  GND            VSS82  @S9S_MB_2U_LIB.S9S_MB_2U(SCH_1):GND
  188  GND            VSS81  @S9S_MB_2U_LIB.S9S_MB_2U(SCH_1):GND
  186  GND            VSS80  @S9S_MB_2U_LIB.S9S_MB_2U(SCH_1):GND
  184  GND            VSS79  @S9S_MB_2U_LIB.S9S_MB_2U(SCH_1):GND
  182  GND            VSS78  @S9S_MB_2U_LIB.S9S_MB_2U(SCH_1):GND
  180  GND            VSS77  @S9S_MB_2U_LIB.S9S_MB_2U(SCH_1):GND
  177  GND            VSS76  @S9S_MB_2U_LIB.S9S_MB_2U(SCH_1):GND
  175  GND            VSS75  @S9S_MB_2U_LIB.S9S_MB_2U(SCH_1):GND
  173  GND            VSS74  @S9S_MB_2U_LIB.S9S_MB_2U(SCH_1):GND
  171  GND            VSS73  @S9S_MB_2U_LIB.S9S_MB_2U(SCH_1):GND
  169  GND            VSS72  @S9S_MB_2U_LIB.S9S_MB_2U(SCH_1):GND
  166  GND            VSS71  @S9S_MB_2U_LIB.S9S_MB_2U(SCH_1):GND
  164  GND            VSS70  @S9S_MB_2U_LIB.S9S_MB_2U(SCH_1):GND
  162  GND            VSS69  @S9S_MB_2U_LIB.S9S_MB_2U(SCH_1):GND
  160  GND            VSS68  @S9S_MB_2U_LIB.S9S_MB_2U(SCH_1):GND
  158  GND            VSS67  @S9S_MB_2U_LIB.S9S_MB_2U(SCH_1):GND
  155  GND            VSS66  @S9S_MB_2U_LIB.S9S_MB_2U(SCH_1):GND
  153  GND            VSS65  @S9S_MB_2U_LIB.S9S_MB_2U(SCH_1):GND
  151  GND            VSS64  @S9S_MB_2U_LIB.S9S_MB_2U(SCH_1):GND
  143  GND            VSS63  @S9S_MB_2U_LIB.S9S_MB_2U(SCH_1):GND
  141  GND            VSS62  @S9S_MB_2U_LIB.S9S_MB_2U(SCH_1):GND
  139  GND            VSS61  @S9S_MB_2U_LIB.S9S_MB_2U(SCH_1):GND
  136  GND            VSS60  @S9S_MB_2U_LIB.S9S_MB_2U(SCH_1):GND
  134  GND            VSS59  @S9S_MB_2U_LIB.S9S_MB_2U(SCH_1):GND
  132  GND            VSS58  @S9S_MB_2U_LIB.S9S_MB_2U(SCH_1):GND
  130  GND            VSS57  @S9S_MB_2U_LIB.S9S_MB_2U(SCH_1):GND
  128  GND            VSS56  @S9S_MB_2U_LIB.S9S_MB_2U(SCH_1):GND
  125  GND            VSS55  @S9S_MB_2U_LIB.S9S_MB_2U(SCH_1):GND
  123  GND            VSS54  @S9S_MB_2U_LIB.S9S_MB_2U(SCH_1):GND
  121  GND            VSS53  @S9S_MB_2U_LIB.S9S_MB_2U(SCH_1):GND
  119  GND            VSS52  @S9S_MB_2U_LIB.S9S_MB_2U(SCH_1):GND
  117  GND            VSS51  @S9S_MB_2U_LIB.S9S_MB_2U(SCH_1):GND
  114  GND            VSS50  @S9S_MB_2U_LIB.S9S_MB_2U(SCH_1):GND
  112  GND            VSS49  @S9S_MB_2U_LIB.S9S_MB_2U(SCH_1):GND
  110  GND            VSS48  @S9S_MB_2U_LIB.S9S_MB_2U(SCH_1):GND
  108  GND            VSS47  @S9S_MB_2U_LIB.S9S_MB_2U(SCH_1):GND
  106  GND            VSS46  @S9S_MB_2U_LIB.S9S_MB_2U(SCH_1):GND
  103  GND            VSS45  @S9S_MB_2U_LIB.S9S_MB_2U(SCH_1):GND
  101  GND            VSS44  @S9S_MB_2U_LIB.S9S_MB_2U(SCH_1):GND
   99  GND            VSS43  @S9S_MB_2U_LIB.S9S_MB_2U(SCH_1):GND
   97  GND            VSS42  @S9S_MB_2U_LIB.S9S_MB_2U(SCH_1):GND
   95  GND            VSS41  @S9S_MB_2U_LIB.S9S_MB_2U(SCH_1):GND
   92  GND            VSS40  @S9S_MB_2U_LIB.S9S_MB_2U(SCH_1):GND
   90  GND            VSS39  @S9S_MB_2U_LIB.S9S_MB_2U(SCH_1):GND
   88  GND            VSS38  @S9S_MB_2U_LIB.S9S_MB_2U(SCH_1):GND
   85  GND            VSS37  @S9S_MB_2U_LIB.S9S_MB_2U(SCH_1):GND
   83  GND            VSS36  @S9S_MB_2U_LIB.S9S_MB_2U(SCH_1):GND
   81  GND            VSS35  @S9S_MB_2U_LIB.S9S_MB_2U(SCH_1):GND
   79  GND            VSS34  @S9S_MB_2U_LIB.S9S_MB_2U(SCH_1):GND
   77  GND            VSS33  @S9S_MB_2U_LIB.S9S_MB_2U(SCH_1):GND
   75  GND            VSS32  @S9S_MB_2U_LIB.S9S_MB_2U(SCH_1):GND
   73  GND            VSS31  @S9S_MB_2U_LIB.S9S_MB_2U(SCH_1):GND
   71  GND            VSS30  @S9S_MB_2U_LIB.S9S_MB_2U(SCH_1):GND
   69  GND            VSS29  @S9S_MB_2U_LIB.S9S_MB_2U(SCH_1):GND
   67  GND            VSS28  @S9S_MB_2U_LIB.S9S_MB_2U(SCH_1):GND
   65  GND            VSS27  @S9S_MB_2U_LIB.S9S_MB_2U(SCH_1):GND
   63  GND            VSS26  @S9S_MB_2U_LIB.S9S_MB_2U(SCH_1):GND
   61  GND            VSS25  @S9S_MB_2U_LIB.S9S_MB_2U(SCH_1):GND
   59  GND            VSS24  @S9S_MB_2U_LIB.S9S_MB_2U(SCH_1):GND
   57  GND            VSS23  @S9S_MB_2U_LIB.S9S_MB_2U(SCH_1):GND
   54  GND            VSS22  @S9S_MB_2U_LIB.S9S_MB_2U(SCH_1):GND
   52  GND            VSS21  @S9S_MB_2U_LIB.S9S_MB_2U(SCH_1):GND
   50  GND            VSS20  @S9S_MB_2U_LIB.S9S_MB_2U(SCH_1):GND
   48  GND            VSS19  @S9S_MB_2U_LIB.S9S_MB_2U(SCH_1):GND
   46  GND            VSS18  @S9S_MB_2U_LIB.S9S_MB_2U(SCH_1):GND
   43  GND            VSS17  @S9S_MB_2U_LIB.S9S_MB_2U(SCH_1):GND
   41  GND            VSS16  @S9S_MB_2U_LIB.S9S_MB_2U(SCH_1):GND
   39  GND            VSS15  @S9S_MB_2U_LIB.S9S_MB_2U(SCH_1):GND
   37  GND            VSS14  @S9S_MB_2U_LIB.S9S_MB_2U(SCH_1):GND
   35  GND            VSS13  @S9S_MB_2U_LIB.S9S_MB_2U(SCH_1):GND
   32  GND            VSS12  @S9S_MB_2U_LIB.S9S_MB_2U(SCH_1):GND
   30  GND            VSS11  @S9S_MB_2U_LIB.S9S_MB_2U(SCH_1):GND
   28  GND            VSS10  @S9S_MB_2U_LIB.S9S_MB_2U(SCH_1):GND
   26  GND             VSS9  @S9S_MB_2U_LIB.S9S_MB_2U(SCH_1):GND
   24  GND             VSS8  @S9S_MB_2U_LIB.S9S_MB_2U(SCH_1):GND
   21  GND             VSS7  @S9S_MB_2U_LIB.S9S_MB_2U(SCH_1):GND
   19  GND             VSS6  @S9S_MB_2U_LIB.S9S_MB_2U(SCH_1):GND
   17  GND             VSS5  @S9S_MB_2U_LIB.S9S_MB_2U(SCH_1):GND
   15  GND             VSS4  @S9S_MB_2U_LIB.S9S_MB_2U(SCH_1):GND
   13  GND             VSS3  @S9S_MB_2U_LIB.S9S_MB_2U(SCH_1):GND
   10  GND             VSS2  @S9S_MB_2U_LIB.S9S_MB_2U(SCH_1):GND
    8  GND             VSS1  @S9S_MB_2U_LIB.S9S_MB_2U(SCH_1):GND
    6  GND             VSS0  @S9S_MB_2U_LIB.S9S_MB_2U(SCH_1):GND
   G3  GND               G3  @S9S_MB_2U_LIB.S9S_MB_2U(SCH_1):GND
   G2  GND               G2  @S9S_MB_2U_LIB.S9S_MB_2U(SCH_1):GND
   G1  GND               G1  @S9S_MB_2U_LIB.S9S_MB_2U(SCH_1):GND

SCONN288_ADR50001P013C01  I125  J3     [SCONN288_ADR50001P013C01-SCONNA]
   93  M_B_CPU0_SB_DQS_DP<9>  DQS9_B_P  @S9S_MB_2U_LIB.S9S_MB_2U(SCH_1):M_B_CPU0_SB_DQS_DP<9>
  283  M_B_CPU0_SB_DQS_DP<8>  DQS8_B_P  @S9S_MB_2U_LIB.S9S_MB_2U(SCH_1):M_B_CPU0_SB_DQS_DP<8>
  272  M_B_CPU0_SB_DQS_DP<7>  DQS7_B_P  @S9S_MB_2U_LIB.S9S_MB_2U(SCH_1):M_B_CPU0_SB_DQS_DP<7>
  261  M_B_CPU0_SB_DQS_DP<6>  DQS6_B_P  @S9S_MB_2U_LIB.S9S_MB_2U(SCH_1):M_B_CPU0_SB_DQS_DP<6>
  250  M_B_CPU0_SB_DQS_DP<5>  DQS5_B_P  @S9S_MB_2U_LIB.S9S_MB_2U(SCH_1):M_B_CPU0_SB_DQS_DP<5>
  239  M_B_CPU0_SB_DQS_DP<4>  DQS4_B_P  @S9S_MB_2U_LIB.S9S_MB_2U(SCH_1):M_B_CPU0_SB_DQS_DP<4>
  137  M_B_CPU0_SB_DQS_DP<3>  DQS3_B_P  @S9S_MB_2U_LIB.S9S_MB_2U(SCH_1):M_B_CPU0_SB_DQS_DP<3>
  126  M_B_CPU0_SB_DQS_DP<2>  DQS2_B_P  @S9S_MB_2U_LIB.S9S_MB_2U(SCH_1):M_B_CPU0_SB_DQS_DP<2>
  115  M_B_CPU0_SB_DQS_DP<1>  DQS1_B_P  @S9S_MB_2U_LIB.S9S_MB_2U(SCH_1):M_B_CPU0_SB_DQS_DP<1>
  104  M_B_CPU0_SB_DQS_DP<0>  DQS0_B_P  @S9S_MB_2U_LIB.S9S_MB_2U(SCH_1):M_B_CPU0_SB_DQS_DP<0>
   94  M_B_CPU0_SB_DQS_DN<9>  DQS9_B_N  @S9S_MB_2U_LIB.S9S_MB_2U(SCH_1):M_B_CPU0_SB_DQS_DN<9>
  282  M_B_CPU0_SB_DQS_DN<8>  DQS8_B_N  @S9S_MB_2U_LIB.S9S_MB_2U(SCH_1):M_B_CPU0_SB_DQS_DN<8>
  271  M_B_CPU0_SB_DQS_DN<7>  DQS7_B_N  @S9S_MB_2U_LIB.S9S_MB_2U(SCH_1):M_B_CPU0_SB_DQS_DN<7>
  260  M_B_CPU0_SB_DQS_DN<6>  DQS6_B_N  @S9S_MB_2U_LIB.S9S_MB_2U(SCH_1):M_B_CPU0_SB_DQS_DN<6>
  249  M_B_CPU0_SB_DQS_DN<5>  DQS5_B_N  @S9S_MB_2U_LIB.S9S_MB_2U(SCH_1):M_B_CPU0_SB_DQS_DN<5>
  238  M_B_CPU0_SB_DQS_DN<4>  DQS4_B_N  @S9S_MB_2U_LIB.S9S_MB_2U(SCH_1):M_B_CPU0_SB_DQS_DN<4>
  138  M_B_CPU0_SB_DQS_DN<3>  DQS3_B_N  @S9S_MB_2U_LIB.S9S_MB_2U(SCH_1):M_B_CPU0_SB_DQS_DN<3>
  127  M_B_CPU0_SB_DQS_DN<2>  DQS2_B_N  @S9S_MB_2U_LIB.S9S_MB_2U(SCH_1):M_B_CPU0_SB_DQS_DN<2>
  116  M_B_CPU0_SB_DQS_DN<1>  DQS1_B_N  @S9S_MB_2U_LIB.S9S_MB_2U(SCH_1):M_B_CPU0_SB_DQS_DN<1>
  105  M_B_CPU0_SB_DQS_DN<0>  DQS0_B_N  @S9S_MB_2U_LIB.S9S_MB_2U(SCH_1):M_B_CPU0_SB_DQS_DN<0>
  201  M_B_CPU0_SA_DQS_DP<9>  DQS9_A_P  @S9S_MB_2U_LIB.S9S_MB_2U(SCH_1):M_B_CPU0_SA_DQS_DP<9>
  190  M_B_CPU0_SA_DQS_DP<8>  DQS8_A_P  @S9S_MB_2U_LIB.S9S_MB_2U(SCH_1):M_B_CPU0_SA_DQS_DP<8>
  179  M_B_CPU0_SA_DQS_DP<7>  DQS7_A_P  @S9S_MB_2U_LIB.S9S_MB_2U(SCH_1):M_B_CPU0_SA_DQS_DP<7>
  168  M_B_CPU0_SA_DQS_DP<6>  DQS6_A_P  @S9S_MB_2U_LIB.S9S_MB_2U(SCH_1):M_B_CPU0_SA_DQS_DP<6>
  157  M_B_CPU0_SA_DQS_DP<5>  DQS5_A_P  @S9S_MB_2U_LIB.S9S_MB_2U(SCH_1):M_B_CPU0_SA_DQS_DP<5>
   55  M_B_CPU0_SA_DQS_DP<4>  DQS4_A_P  @S9S_MB_2U_LIB.S9S_MB_2U(SCH_1):M_B_CPU0_SA_DQS_DP<4>
   44  M_B_CPU0_SA_DQS_DP<3>  DQS3_A_P  @S9S_MB_2U_LIB.S9S_MB_2U(SCH_1):M_B_CPU0_SA_DQS_DP<3>
   33  M_B_CPU0_SA_DQS_DP<2>  DQS2_A_P  @S9S_MB_2U_LIB.S9S_MB_2U(SCH_1):M_B_CPU0_SA_DQS_DP<2>
   22  M_B_CPU0_SA_DQS_DP<1>  DQS1_A_P  @S9S_MB_2U_LIB.S9S_MB_2U(SCH_1):M_B_CPU0_SA_DQS_DP<1>
   11  M_B_CPU0_SA_DQS_DP<0>  DQS0_A_P  @S9S_MB_2U_LIB.S9S_MB_2U(SCH_1):M_B_CPU0_SA_DQS_DP<0>
  200  M_B_CPU0_SA_DQS_DN<9>  DQS9_A_N  @S9S_MB_2U_LIB.S9S_MB_2U(SCH_1):M_B_CPU0_SA_DQS_DN<9>
  189  M_B_CPU0_SA_DQS_DN<8>  DQS8_A_N  @S9S_MB_2U_LIB.S9S_MB_2U(SCH_1):M_B_CPU0_SA_DQS_DN<8>
  178  M_B_CPU0_SA_DQS_DN<7>  DQS7_A_N  @S9S_MB_2U_LIB.S9S_MB_2U(SCH_1):M_B_CPU0_SA_DQS_DN<7>
  167  M_B_CPU0_SA_DQS_DN<6>  DQS6_A_N  @S9S_MB_2U_LIB.S9S_MB_2U(SCH_1):M_B_CPU0_SA_DQS_DN<6>
  156  M_B_CPU0_SA_DQS_DN<5>  DQS5_A_N  @S9S_MB_2U_LIB.S9S_MB_2U(SCH_1):M_B_CPU0_SA_DQS_DN<5>
   56  M_B_CPU0_SA_DQS_DN<4>  DQS4_A_N  @S9S_MB_2U_LIB.S9S_MB_2U(SCH_1):M_B_CPU0_SA_DQS_DN<4>
   45  M_B_CPU0_SA_DQS_DN<3>  DQS3_A_N  @S9S_MB_2U_LIB.S9S_MB_2U(SCH_1):M_B_CPU0_SA_DQS_DN<3>
   34  M_B_CPU0_SA_DQS_DN<2>  DQS2_A_N  @S9S_MB_2U_LIB.S9S_MB_2U(SCH_1):M_B_CPU0_SA_DQS_DN<2>
   23  M_B_CPU0_SA_DQS_DN<1>  DQS1_A_N  @S9S_MB_2U_LIB.S9S_MB_2U(SCH_1):M_B_CPU0_SA_DQS_DN<1>
   12  M_B_CPU0_SA_DQS_DN<0>  DQS0_A_N  @S9S_MB_2U_LIB.S9S_MB_2U(SCH_1):M_B_CPU0_SA_DQS_DN<0>

SCONN288_ADR50001P013C01  I11  J3     [SCONN288_ADR50001P013C01-SCONNA]
  232  NC              RFU6  NC
  231  NC              RFU5  NC
  220  NC              RFU4  NC
  150  NC              RFU3  NC
  149  NC              RFU2  NC
  144  NC              RFU1  NC
    2  NC              RFU0  NC
  207  RST_M_AB_CPU0_FPGA_N  RESET_N  @S9S_MB_2U_LIB.S9S_MB_2U(SCH_1):RST_M_AB_CPU0_FPGA_N
  147  PWRGD_CHB_CPU0_DIMM1  PWR_GOOD||FAIL_N  @S9S_MB_2U_LIB.S9S_MB_2U(SCH_1):PWRGD_CHB_CPU0_DIMM1
  148  PD_CHB_CPU0_DIMM1_SAA    HAS  @S9S_MB_2U_LIB.S9S_MB_2U(SCH_1):PD_CHB_CPU0_DIMM1_SAA
    3  P3V3_AUX       VIN_MGMT  @S9S_MB_2U_LIB.S9S_MB_2U(SCH_1):P3V3_AUX
   87  M_B_CPU0_SB_RSP<0>  LBS||RSP_N_B  @S9S_MB_2U_LIB.S9S_MB_2U(SCH_1):M_B_CPU0_SB_RSP<0>
  227  M_B_CPU0_SB_PAR  PAR_B  @S9S_MB_2U_LIB.S9S_MB_2U(SCH_1):M_B_CPU0_SB_PAR
  113  M_B_CPU0_SB_DQ<9>  DQ_B9  @S9S_MB_2U_LIB.S9S_MB_2U(SCH_1):M_B_CPU0_SB_DQ<9>
  111  M_B_CPU0_SB_DQ<8>  DQ_B8  @S9S_MB_2U_LIB.S9S_MB_2U(SCH_1):M_B_CPU0_SB_DQ<8>
  254  M_B_CPU0_SB_DQ<7>  DQ_B7  @S9S_MB_2U_LIB.S9S_MB_2U(SCH_1):M_B_CPU0_SB_DQ<7>
  252  M_B_CPU0_SB_DQ<6>  DQ_B6  @S9S_MB_2U_LIB.S9S_MB_2U(SCH_1):M_B_CPU0_SB_DQ<6>
  109  M_B_CPU0_SB_DQ<5>  DQ_B5  @S9S_MB_2U_LIB.S9S_MB_2U(SCH_1):M_B_CPU0_SB_DQ<5>
  107  M_B_CPU0_SB_DQ<4>  DQ_B4  @S9S_MB_2U_LIB.S9S_MB_2U(SCH_1):M_B_CPU0_SB_DQ<4>
  247  M_B_CPU0_SB_DQ<3>  DQ_B3  @S9S_MB_2U_LIB.S9S_MB_2U(SCH_1):M_B_CPU0_SB_DQ<3>
  287  M_B_CPU0_SB_DQ<31>  DQ_B31  @S9S_MB_2U_LIB.S9S_MB_2U(SCH_1):M_B_CPU0_SB_DQ<31>
  285  M_B_CPU0_SB_DQ<30>  DQ_B30  @S9S_MB_2U_LIB.S9S_MB_2U(SCH_1):M_B_CPU0_SB_DQ<30>
  245  M_B_CPU0_SB_DQ<2>  DQ_B2  @S9S_MB_2U_LIB.S9S_MB_2U(SCH_1):M_B_CPU0_SB_DQ<2>
  142  M_B_CPU0_SB_DQ<29>  DQ_B29  @S9S_MB_2U_LIB.S9S_MB_2U(SCH_1):M_B_CPU0_SB_DQ<29>
  140  M_B_CPU0_SB_DQ<28>  DQ_B28  @S9S_MB_2U_LIB.S9S_MB_2U(SCH_1):M_B_CPU0_SB_DQ<28>
  280  M_B_CPU0_SB_DQ<27>  DQ_B27  @S9S_MB_2U_LIB.S9S_MB_2U(SCH_1):M_B_CPU0_SB_DQ<27>
  278  M_B_CPU0_SB_DQ<26>  DQ_B26  @S9S_MB_2U_LIB.S9S_MB_2U(SCH_1):M_B_CPU0_SB_DQ<26>
  135  M_B_CPU0_SB_DQ<25>  DQ_B25  @S9S_MB_2U_LIB.S9S_MB_2U(SCH_1):M_B_CPU0_SB_DQ<25>
  133  M_B_CPU0_SB_DQ<24>  DQ_B24  @S9S_MB_2U_LIB.S9S_MB_2U(SCH_1):M_B_CPU0_SB_DQ<24>
  276  M_B_CPU0_SB_DQ<23>  DQ_B23  @S9S_MB_2U_LIB.S9S_MB_2U(SCH_1):M_B_CPU0_SB_DQ<23>
  274  M_B_CPU0_SB_DQ<22>  DQ_B22  @S9S_MB_2U_LIB.S9S_MB_2U(SCH_1):M_B_CPU0_SB_DQ<22>
  131  M_B_CPU0_SB_DQ<21>  DQ_B21  @S9S_MB_2U_LIB.S9S_MB_2U(SCH_1):M_B_CPU0_SB_DQ<21>
  129  M_B_CPU0_SB_DQ<20>  DQ_B20  @S9S_MB_2U_LIB.S9S_MB_2U(SCH_1):M_B_CPU0_SB_DQ<20>
  102  M_B_CPU0_SB_DQ<1>  DQ_B1  @S9S_MB_2U_LIB.S9S_MB_2U(SCH_1):M_B_CPU0_SB_DQ<1>
  269  M_B_CPU0_SB_DQ<19>  DQ_B19  @S9S_MB_2U_LIB.S9S_MB_2U(SCH_1):M_B_CPU0_SB_DQ<19>
  267  M_B_CPU0_SB_DQ<18>  DQ_B18  @S9S_MB_2U_LIB.S9S_MB_2U(SCH_1):M_B_CPU0_SB_DQ<18>
  124  M_B_CPU0_SB_DQ<17>  DQ_B17  @S9S_MB_2U_LIB.S9S_MB_2U(SCH_1):M_B_CPU0_SB_DQ<17>
  122  M_B_CPU0_SB_DQ<16>  DQ_B16  @S9S_MB_2U_LIB.S9S_MB_2U(SCH_1):M_B_CPU0_SB_DQ<16>
  265  M_B_CPU0_SB_DQ<15>  DQ_B15  @S9S_MB_2U_LIB.S9S_MB_2U(SCH_1):M_B_CPU0_SB_DQ<15>
  263  M_B_CPU0_SB_DQ<14>  DQ_B14  @S9S_MB_2U_LIB.S9S_MB_2U(SCH_1):M_B_CPU0_SB_DQ<14>
  120  M_B_CPU0_SB_DQ<13>  DQ_B13  @S9S_MB_2U_LIB.S9S_MB_2U(SCH_1):M_B_CPU0_SB_DQ<13>
  118  M_B_CPU0_SB_DQ<12>  DQ_B12  @S9S_MB_2U_LIB.S9S_MB_2U(SCH_1):M_B_CPU0_SB_DQ<12>
  258  M_B_CPU0_SB_DQ<11>  DQ_B11  @S9S_MB_2U_LIB.S9S_MB_2U(SCH_1):M_B_CPU0_SB_DQ<11>
  256  M_B_CPU0_SB_DQ<10>  DQ_B10  @S9S_MB_2U_LIB.S9S_MB_2U(SCH_1):M_B_CPU0_SB_DQ<10>
  100  M_B_CPU0_SB_DQ<0>  DQ_B0  @S9S_MB_2U_LIB.S9S_MB_2U(SCH_1):M_B_CPU0_SB_DQ<0>
  229  M_B_CPU0_SB_CS_N<1>  CS1_N_B  @S9S_MB_2U_LIB.S9S_MB_2U(SCH_1):M_B_CPU0_SB_CS_N<1>
   84  M_B_CPU0_SB_CS_N<0>  CS0_N_B  @S9S_MB_2U_LIB.S9S_MB_2U(SCH_1):M_B_CPU0_SB_CS_N<0>
  236  M_B_CPU0_SB_CB<7>  CB_B7  @S9S_MB_2U_LIB.S9S_MB_2U(SCH_1):M_B_CPU0_SB_CB<7>
  234  M_B_CPU0_SB_CB<6>  CB_B6  @S9S_MB_2U_LIB.S9S_MB_2U(SCH_1):M_B_CPU0_SB_CB<6>
   91  M_B_CPU0_SB_CB<5>  CB_B5  @S9S_MB_2U_LIB.S9S_MB_2U(SCH_1):M_B_CPU0_SB_CB<5>
   89  M_B_CPU0_SB_CB<4>  CB_B4  @S9S_MB_2U_LIB.S9S_MB_2U(SCH_1):M_B_CPU0_SB_CB<4>
  243  M_B_CPU0_SB_CB<3>  CB_B3  @S9S_MB_2U_LIB.S9S_MB_2U(SCH_1):M_B_CPU0_SB_CB<3>
  241  M_B_CPU0_SB_CB<2>  CB_B2  @S9S_MB_2U_LIB.S9S_MB_2U(SCH_1):M_B_CPU0_SB_CB<2>
   98  M_B_CPU0_SB_CB<1>  CB_B1  @S9S_MB_2U_LIB.S9S_MB_2U(SCH_1):M_B_CPU0_SB_CB<1>
   96  M_B_CPU0_SB_CB<0>  CB_B0  @S9S_MB_2U_LIB.S9S_MB_2U(SCH_1):M_B_CPU0_SB_CB<0>
   82  M_B_CPU0_SB_CA<6>  CA6_B  @S9S_MB_2U_LIB.S9S_MB_2U(SCH_1):M_B_CPU0_SB_CA<6>
  225  M_B_CPU0_SB_CA<5>  CA5_B  @S9S_MB_2U_LIB.S9S_MB_2U(SCH_1):M_B_CPU0_SB_CA<5>
   80  M_B_CPU0_SB_CA<4>  CA4_B  @S9S_MB_2U_LIB.S9S_MB_2U(SCH_1):M_B_CPU0_SB_CA<4>
  223  M_B_CPU0_SB_CA<3>  CA3_B  @S9S_MB_2U_LIB.S9S_MB_2U(SCH_1):M_B_CPU0_SB_CA<3>
   78  M_B_CPU0_SB_CA<2>  CA2_B  @S9S_MB_2U_LIB.S9S_MB_2U(SCH_1):M_B_CPU0_SB_CA<2>
  221  M_B_CPU0_SB_CA<1>  CA1_B  @S9S_MB_2U_LIB.S9S_MB_2U(SCH_1):M_B_CPU0_SB_CA<1>
   76  M_B_CPU0_SB_CA<0>  CA0_B  @S9S_MB_2U_LIB.S9S_MB_2U(SCH_1):M_B_CPU0_SB_CA<0>
   86  M_B_CPU0_SA_RSP<0>  LBD||RSP_N_A  @S9S_MB_2U_LIB.S9S_MB_2U(SCH_1):M_B_CPU0_SA_RSP<0>
   74  M_B_CPU0_SA_PAR  PAR_A  @S9S_MB_2U_LIB.S9S_MB_2U(SCH_1):M_B_CPU0_SA_PAR
   20  M_B_CPU0_SA_DQ<9>  DQ_A9  @S9S_MB_2U_LIB.S9S_MB_2U(SCH_1):M_B_CPU0_SA_DQ<9>
   18  M_B_CPU0_SA_DQ<8>  DQ_A8  @S9S_MB_2U_LIB.S9S_MB_2U(SCH_1):M_B_CPU0_SA_DQ<8>
  161  M_B_CPU0_SA_DQ<7>  DQ_A7  @S9S_MB_2U_LIB.S9S_MB_2U(SCH_1):M_B_CPU0_SA_DQ<7>
  159  M_B_CPU0_SA_DQ<6>  DQ_A6  @S9S_MB_2U_LIB.S9S_MB_2U(SCH_1):M_B_CPU0_SA_DQ<6>
   16  M_B_CPU0_SA_DQ<5>  DQ_A5  @S9S_MB_2U_LIB.S9S_MB_2U(SCH_1):M_B_CPU0_SA_DQ<5>
   14  M_B_CPU0_SA_DQ<4>  DQ_A4  @S9S_MB_2U_LIB.S9S_MB_2U(SCH_1):M_B_CPU0_SA_DQ<4>
  154  M_B_CPU0_SA_DQ<3>  DQ_A3  @S9S_MB_2U_LIB.S9S_MB_2U(SCH_1):M_B_CPU0_SA_DQ<3>
  194  M_B_CPU0_SA_DQ<31>  DQ_A31  @S9S_MB_2U_LIB.S9S_MB_2U(SCH_1):M_B_CPU0_SA_DQ<31>
  192  M_B_CPU0_SA_DQ<30>  DQ_A30  @S9S_MB_2U_LIB.S9S_MB_2U(SCH_1):M_B_CPU0_SA_DQ<30>
  152  M_B_CPU0_SA_DQ<2>  DQ_A2  @S9S_MB_2U_LIB.S9S_MB_2U(SCH_1):M_B_CPU0_SA_DQ<2>
   49  M_B_CPU0_SA_DQ<29>  DQ_A29  @S9S_MB_2U_LIB.S9S_MB_2U(SCH_1):M_B_CPU0_SA_DQ<29>
   47  M_B_CPU0_SA_DQ<28>  DQ_A28  @S9S_MB_2U_LIB.S9S_MB_2U(SCH_1):M_B_CPU0_SA_DQ<28>
  187  M_B_CPU0_SA_DQ<27>  DQ_A27  @S9S_MB_2U_LIB.S9S_MB_2U(SCH_1):M_B_CPU0_SA_DQ<27>
  185  M_B_CPU0_SA_DQ<26>  DQ_A26  @S9S_MB_2U_LIB.S9S_MB_2U(SCH_1):M_B_CPU0_SA_DQ<26>
   42  M_B_CPU0_SA_DQ<25>  DQ_A25  @S9S_MB_2U_LIB.S9S_MB_2U(SCH_1):M_B_CPU0_SA_DQ<25>
   40  M_B_CPU0_SA_DQ<24>  DQ_A24  @S9S_MB_2U_LIB.S9S_MB_2U(SCH_1):M_B_CPU0_SA_DQ<24>
  183  M_B_CPU0_SA_DQ<23>  DQ_A23  @S9S_MB_2U_LIB.S9S_MB_2U(SCH_1):M_B_CPU0_SA_DQ<23>
  181  M_B_CPU0_SA_DQ<22>  DQ_A22  @S9S_MB_2U_LIB.S9S_MB_2U(SCH_1):M_B_CPU0_SA_DQ<22>
   38  M_B_CPU0_SA_DQ<21>  DQ_A21  @S9S_MB_2U_LIB.S9S_MB_2U(SCH_1):M_B_CPU0_SA_DQ<21>
   36  M_B_CPU0_SA_DQ<20>  DQ_A20  @S9S_MB_2U_LIB.S9S_MB_2U(SCH_1):M_B_CPU0_SA_DQ<20>
    9  M_B_CPU0_SA_DQ<1>  DQ_A1  @S9S_MB_2U_LIB.S9S_MB_2U(SCH_1):M_B_CPU0_SA_DQ<1>
  176  M_B_CPU0_SA_DQ<19>  DQ_A19  @S9S_MB_2U_LIB.S9S_MB_2U(SCH_1):M_B_CPU0_SA_DQ<19>
  174  M_B_CPU0_SA_DQ<18>  DQ_A18  @S9S_MB_2U_LIB.S9S_MB_2U(SCH_1):M_B_CPU0_SA_DQ<18>
   31  M_B_CPU0_SA_DQ<17>  DQ_A17  @S9S_MB_2U_LIB.S9S_MB_2U(SCH_1):M_B_CPU0_SA_DQ<17>
   29  M_B_CPU0_SA_DQ<16>  DQ_A16  @S9S_MB_2U_LIB.S9S_MB_2U(SCH_1):M_B_CPU0_SA_DQ<16>
  172  M_B_CPU0_SA_DQ<15>  DQ_A15  @S9S_MB_2U_LIB.S9S_MB_2U(SCH_1):M_B_CPU0_SA_DQ<15>
  170  M_B_CPU0_SA_DQ<14>  DQ_A14  @S9S_MB_2U_LIB.S9S_MB_2U(SCH_1):M_B_CPU0_SA_DQ<14>
   27  M_B_CPU0_SA_DQ<13>  DQ_A13  @S9S_MB_2U_LIB.S9S_MB_2U(SCH_1):M_B_CPU0_SA_DQ<13>
   25  M_B_CPU0_SA_DQ<12>  DQ_A12  @S9S_MB_2U_LIB.S9S_MB_2U(SCH_1):M_B_CPU0_SA_DQ<12>
  165  M_B_CPU0_SA_DQ<11>  DQ_A11  @S9S_MB_2U_LIB.S9S_MB_2U(SCH_1):M_B_CPU0_SA_DQ<11>
  163  M_B_CPU0_SA_DQ<10>  DQ_A10  @S9S_MB_2U_LIB.S9S_MB_2U(SCH_1):M_B_CPU0_SA_DQ<10>
    7  M_B_CPU0_SA_DQ<0>  DQ_A0  @S9S_MB_2U_LIB.S9S_MB_2U(SCH_1):M_B_CPU0_SA_DQ<0>
  209  M_B_CPU0_SA_CS_N<1>  CS1_N_A  @S9S_MB_2U_LIB.S9S_MB_2U(SCH_1):M_B_CPU0_SA_CS_N<1>
   64  M_B_CPU0_SA_CS_N<0>  CS0_N_A  @S9S_MB_2U_LIB.S9S_MB_2U(SCH_1):M_B_CPU0_SA_CS_N<0>
  205  M_B_CPU0_SA_CB<7>  CB_A7  @S9S_MB_2U_LIB.S9S_MB_2U(SCH_1):M_B_CPU0_SA_CB<7>
  203  M_B_CPU0_SA_CB<6>  CB_A6  @S9S_MB_2U_LIB.S9S_MB_2U(SCH_1):M_B_CPU0_SA_CB<6>
   60  M_B_CPU0_SA_CB<5>  CB_A5  @S9S_MB_2U_LIB.S9S_MB_2U(SCH_1):M_B_CPU0_SA_CB<5>
   58  M_B_CPU0_SA_CB<4>  CB_A4  @S9S_MB_2U_LIB.S9S_MB_2U(SCH_1):M_B_CPU0_SA_CB<4>
  198  M_B_CPU0_SA_CB<3>  CB_A3  @S9S_MB_2U_LIB.S9S_MB_2U(SCH_1):M_B_CPU0_SA_CB<3>
  196  M_B_CPU0_SA_CB<2>  CB_A2  @S9S_MB_2U_LIB.S9S_MB_2U(SCH_1):M_B_CPU0_SA_CB<2>
   53  M_B_CPU0_SA_CB<1>  CB_A1  @S9S_MB_2U_LIB.S9S_MB_2U(SCH_1):M_B_CPU0_SA_CB<1>
   51  M_B_CPU0_SA_CB<0>  CB_A0  @S9S_MB_2U_LIB.S9S_MB_2U(SCH_1):M_B_CPU0_SA_CB<0>
   72  M_B_CPU0_SA_CA<6>  CA6_A  @S9S_MB_2U_LIB.S9S_MB_2U(SCH_1):M_B_CPU0_SA_CA<6>
  215  M_B_CPU0_SA_CA<5>  CA5_A  @S9S_MB_2U_LIB.S9S_MB_2U(SCH_1):M_B_CPU0_SA_CA<5>
   70  M_B_CPU0_SA_CA<4>  CA4_A  @S9S_MB_2U_LIB.S9S_MB_2U(SCH_1):M_B_CPU0_SA_CA<4>
  213  M_B_CPU0_SA_CA<3>  CA3_A  @S9S_MB_2U_LIB.S9S_MB_2U(SCH_1):M_B_CPU0_SA_CA<3>
   68  M_B_CPU0_SA_CA<2>  CA2_A  @S9S_MB_2U_LIB.S9S_MB_2U(SCH_1):M_B_CPU0_SA_CA<2>
  211  M_B_CPU0_SA_CA<1>  CA1_A  @S9S_MB_2U_LIB.S9S_MB_2U(SCH_1):M_B_CPU0_SA_CA<1>
   66  M_B_CPU0_SA_CA<0>  CA0_A  @S9S_MB_2U_LIB.S9S_MB_2U(SCH_1):M_B_CPU0_SA_CA<0>
  217  M_B_CPU0_CLK_DP<0>   CK_P  @S9S_MB_2U_LIB.S9S_MB_2U(SCH_1):M_B_CPU0_CLK_DP<0>
  218  M_B_CPU0_CLK_DN<0>   CK_N  @S9S_MB_2U_LIB.S9S_MB_2U(SCH_1):M_B_CPU0_CLK_DN<0>
   62  M_B_CPU0_ALERT_N  ALERT_N  @S9S_MB_2U_LIB.S9S_MB_2U(SCH_1):M_B_CPU0_ALERT_N
    5  I3C_SPD_DDRABCD_CPU0_LVC1_SDA   HSDA  @S9S_MB_2U_LIB.S9S_MB_2U(SCH_1):I3C_SPD_DDRABCD_CPU0_LVC1_SDA
    4  I3C_SPD_DDRABCD_CPU0_LVC1_SCL   HSCL  @S9S_MB_2U_LIB.S9S_MB_2U(SCH_1):I3C_SPD_DDRABCD_CPU0_LVC1_SCL

SCONN288_ADR50001P003C01  I174  J4     [SCONN288_ADR50001P003C01-SCONNA]
  146  P12V_S3_AUX_CPU0_NVDIMM  VIN_BULK2  @S9S_MB_2U_LIB.S9S_MB_2U(SCH_1):P12V_S3_AUX_CPU0_NVDIMM
  145  P12V_S3_AUX_CPU0_NVDIMM  VIN_BULK1  @S9S_MB_2U_LIB.S9S_MB_2U(SCH_1):P12V_S3_AUX_CPU0_NVDIMM
    1  P12V_S3_AUX_CPU0_NVDIMM  VIN_BULK0  @S9S_MB_2U_LIB.S9S_MB_2U(SCH_1):P12V_S3_AUX_CPU0_NVDIMM
  288  GND            VSS126  @S9S_MB_2U_LIB.S9S_MB_2U(SCH_1):GND
  286  GND            VSS125  @S9S_MB_2U_LIB.S9S_MB_2U(SCH_1):GND
  284  GND            VSS124  @S9S_MB_2U_LIB.S9S_MB_2U(SCH_1):GND
  281  GND            VSS123  @S9S_MB_2U_LIB.S9S_MB_2U(SCH_1):GND
  279  GND            VSS122  @S9S_MB_2U_LIB.S9S_MB_2U(SCH_1):GND
  277  GND            VSS121  @S9S_MB_2U_LIB.S9S_MB_2U(SCH_1):GND
  275  GND            VSS120  @S9S_MB_2U_LIB.S9S_MB_2U(SCH_1):GND
  273  GND            VSS119  @S9S_MB_2U_LIB.S9S_MB_2U(SCH_1):GND
  270  GND            VSS118  @S9S_MB_2U_LIB.S9S_MB_2U(SCH_1):GND
  268  GND            VSS117  @S9S_MB_2U_LIB.S9S_MB_2U(SCH_1):GND
  266  GND            VSS116  @S9S_MB_2U_LIB.S9S_MB_2U(SCH_1):GND
  264  GND            VSS115  @S9S_MB_2U_LIB.S9S_MB_2U(SCH_1):GND
  262  GND            VSS114  @S9S_MB_2U_LIB.S9S_MB_2U(SCH_1):GND
  259  GND            VSS113  @S9S_MB_2U_LIB.S9S_MB_2U(SCH_1):GND
  257  GND            VSS112  @S9S_MB_2U_LIB.S9S_MB_2U(SCH_1):GND
  255  GND            VSS111  @S9S_MB_2U_LIB.S9S_MB_2U(SCH_1):GND
  253  GND            VSS110  @S9S_MB_2U_LIB.S9S_MB_2U(SCH_1):GND
  251  GND            VSS109  @S9S_MB_2U_LIB.S9S_MB_2U(SCH_1):GND
  248  GND            VSS108  @S9S_MB_2U_LIB.S9S_MB_2U(SCH_1):GND
  246  GND            VSS107  @S9S_MB_2U_LIB.S9S_MB_2U(SCH_1):GND
  244  GND            VSS106  @S9S_MB_2U_LIB.S9S_MB_2U(SCH_1):GND
  242  GND            VSS105  @S9S_MB_2U_LIB.S9S_MB_2U(SCH_1):GND
  240  GND            VSS104  @S9S_MB_2U_LIB.S9S_MB_2U(SCH_1):GND
  237  GND            VSS103  @S9S_MB_2U_LIB.S9S_MB_2U(SCH_1):GND
  235  GND            VSS102  @S9S_MB_2U_LIB.S9S_MB_2U(SCH_1):GND
  233  GND            VSS101  @S9S_MB_2U_LIB.S9S_MB_2U(SCH_1):GND
  230  GND            VSS100  @S9S_MB_2U_LIB.S9S_MB_2U(SCH_1):GND
  228  GND            VSS99  @S9S_MB_2U_LIB.S9S_MB_2U(SCH_1):GND
  226  GND            VSS98  @S9S_MB_2U_LIB.S9S_MB_2U(SCH_1):GND
  224  GND            VSS97  @S9S_MB_2U_LIB.S9S_MB_2U(SCH_1):GND
  222  GND            VSS96  @S9S_MB_2U_LIB.S9S_MB_2U(SCH_1):GND
  219  GND            VSS95  @S9S_MB_2U_LIB.S9S_MB_2U(SCH_1):GND
  216  GND            VSS94  @S9S_MB_2U_LIB.S9S_MB_2U(SCH_1):GND
  214  GND            VSS93  @S9S_MB_2U_LIB.S9S_MB_2U(SCH_1):GND
  212  GND            VSS92  @S9S_MB_2U_LIB.S9S_MB_2U(SCH_1):GND
  210  GND            VSS91  @S9S_MB_2U_LIB.S9S_MB_2U(SCH_1):GND
  208  GND            VSS90  @S9S_MB_2U_LIB.S9S_MB_2U(SCH_1):GND
  206  GND            VSS89  @S9S_MB_2U_LIB.S9S_MB_2U(SCH_1):GND
  204  GND            VSS88  @S9S_MB_2U_LIB.S9S_MB_2U(SCH_1):GND
  202  GND            VSS87  @S9S_MB_2U_LIB.S9S_MB_2U(SCH_1):GND
  199  GND            VSS86  @S9S_MB_2U_LIB.S9S_MB_2U(SCH_1):GND
  197  GND            VSS85  @S9S_MB_2U_LIB.S9S_MB_2U(SCH_1):GND
  195  GND            VSS84  @S9S_MB_2U_LIB.S9S_MB_2U(SCH_1):GND
  193  GND            VSS83  @S9S_MB_2U_LIB.S9S_MB_2U(SCH_1):GND
  191  GND            VSS82  @S9S_MB_2U_LIB.S9S_MB_2U(SCH_1):GND
  188  GND            VSS81  @S9S_MB_2U_LIB.S9S_MB_2U(SCH_1):GND
  186  GND            VSS80  @S9S_MB_2U_LIB.S9S_MB_2U(SCH_1):GND
  184  GND            VSS79  @S9S_MB_2U_LIB.S9S_MB_2U(SCH_1):GND
  182  GND            VSS78  @S9S_MB_2U_LIB.S9S_MB_2U(SCH_1):GND
  180  GND            VSS77  @S9S_MB_2U_LIB.S9S_MB_2U(SCH_1):GND
  177  GND            VSS76  @S9S_MB_2U_LIB.S9S_MB_2U(SCH_1):GND
  175  GND            VSS75  @S9S_MB_2U_LIB.S9S_MB_2U(SCH_1):GND
  173  GND            VSS74  @S9S_MB_2U_LIB.S9S_MB_2U(SCH_1):GND
  171  GND            VSS73  @S9S_MB_2U_LIB.S9S_MB_2U(SCH_1):GND
  169  GND            VSS72  @S9S_MB_2U_LIB.S9S_MB_2U(SCH_1):GND
  166  GND            VSS71  @S9S_MB_2U_LIB.S9S_MB_2U(SCH_1):GND
  164  GND            VSS70  @S9S_MB_2U_LIB.S9S_MB_2U(SCH_1):GND
  162  GND            VSS69  @S9S_MB_2U_LIB.S9S_MB_2U(SCH_1):GND
  160  GND            VSS68  @S9S_MB_2U_LIB.S9S_MB_2U(SCH_1):GND
  158  GND            VSS67  @S9S_MB_2U_LIB.S9S_MB_2U(SCH_1):GND
  155  GND            VSS66  @S9S_MB_2U_LIB.S9S_MB_2U(SCH_1):GND
  153  GND            VSS65  @S9S_MB_2U_LIB.S9S_MB_2U(SCH_1):GND
  151  GND            VSS64  @S9S_MB_2U_LIB.S9S_MB_2U(SCH_1):GND
  143  GND            VSS63  @S9S_MB_2U_LIB.S9S_MB_2U(SCH_1):GND
  141  GND            VSS62  @S9S_MB_2U_LIB.S9S_MB_2U(SCH_1):GND
  139  GND            VSS61  @S9S_MB_2U_LIB.S9S_MB_2U(SCH_1):GND
  136  GND            VSS60  @S9S_MB_2U_LIB.S9S_MB_2U(SCH_1):GND
  134  GND            VSS59  @S9S_MB_2U_LIB.S9S_MB_2U(SCH_1):GND
  132  GND            VSS58  @S9S_MB_2U_LIB.S9S_MB_2U(SCH_1):GND
  130  GND            VSS57  @S9S_MB_2U_LIB.S9S_MB_2U(SCH_1):GND
  128  GND            VSS56  @S9S_MB_2U_LIB.S9S_MB_2U(SCH_1):GND
  125  GND            VSS55  @S9S_MB_2U_LIB.S9S_MB_2U(SCH_1):GND
  123  GND            VSS54  @S9S_MB_2U_LIB.S9S_MB_2U(SCH_1):GND
  121  GND            VSS53  @S9S_MB_2U_LIB.S9S_MB_2U(SCH_1):GND
  119  GND            VSS52  @S9S_MB_2U_LIB.S9S_MB_2U(SCH_1):GND
  117  GND            VSS51  @S9S_MB_2U_LIB.S9S_MB_2U(SCH_1):GND
  114  GND            VSS50  @S9S_MB_2U_LIB.S9S_MB_2U(SCH_1):GND
  112  GND            VSS49  @S9S_MB_2U_LIB.S9S_MB_2U(SCH_1):GND
  110  GND            VSS48  @S9S_MB_2U_LIB.S9S_MB_2U(SCH_1):GND
  108  GND            VSS47  @S9S_MB_2U_LIB.S9S_MB_2U(SCH_1):GND
  106  GND            VSS46  @S9S_MB_2U_LIB.S9S_MB_2U(SCH_1):GND
  103  GND            VSS45  @S9S_MB_2U_LIB.S9S_MB_2U(SCH_1):GND
  101  GND            VSS44  @S9S_MB_2U_LIB.S9S_MB_2U(SCH_1):GND
   99  GND            VSS43  @S9S_MB_2U_LIB.S9S_MB_2U(SCH_1):GND
   97  GND            VSS42  @S9S_MB_2U_LIB.S9S_MB_2U(SCH_1):GND
   95  GND            VSS41  @S9S_MB_2U_LIB.S9S_MB_2U(SCH_1):GND
   92  GND            VSS40  @S9S_MB_2U_LIB.S9S_MB_2U(SCH_1):GND
   90  GND            VSS39  @S9S_MB_2U_LIB.S9S_MB_2U(SCH_1):GND
   88  GND            VSS38  @S9S_MB_2U_LIB.S9S_MB_2U(SCH_1):GND
   85  GND            VSS37  @S9S_MB_2U_LIB.S9S_MB_2U(SCH_1):GND
   83  GND            VSS36  @S9S_MB_2U_LIB.S9S_MB_2U(SCH_1):GND
   81  GND            VSS35  @S9S_MB_2U_LIB.S9S_MB_2U(SCH_1):GND
   79  GND            VSS34  @S9S_MB_2U_LIB.S9S_MB_2U(SCH_1):GND
   77  GND            VSS33  @S9S_MB_2U_LIB.S9S_MB_2U(SCH_1):GND
   75  GND            VSS32  @S9S_MB_2U_LIB.S9S_MB_2U(SCH_1):GND
   73  GND            VSS31  @S9S_MB_2U_LIB.S9S_MB_2U(SCH_1):GND
   71  GND            VSS30  @S9S_MB_2U_LIB.S9S_MB_2U(SCH_1):GND
   69  GND            VSS29  @S9S_MB_2U_LIB.S9S_MB_2U(SCH_1):GND
   67  GND            VSS28  @S9S_MB_2U_LIB.S9S_MB_2U(SCH_1):GND
   65  GND            VSS27  @S9S_MB_2U_LIB.S9S_MB_2U(SCH_1):GND
   63  GND            VSS26  @S9S_MB_2U_LIB.S9S_MB_2U(SCH_1):GND
   61  GND            VSS25  @S9S_MB_2U_LIB.S9S_MB_2U(SCH_1):GND
   59  GND            VSS24  @S9S_MB_2U_LIB.S9S_MB_2U(SCH_1):GND
   57  GND            VSS23  @S9S_MB_2U_LIB.S9S_MB_2U(SCH_1):GND
   54  GND            VSS22  @S9S_MB_2U_LIB.S9S_MB_2U(SCH_1):GND
   52  GND            VSS21  @S9S_MB_2U_LIB.S9S_MB_2U(SCH_1):GND
   50  GND            VSS20  @S9S_MB_2U_LIB.S9S_MB_2U(SCH_1):GND
   48  GND            VSS19  @S9S_MB_2U_LIB.S9S_MB_2U(SCH_1):GND
   46  GND            VSS18  @S9S_MB_2U_LIB.S9S_MB_2U(SCH_1):GND
   43  GND            VSS17  @S9S_MB_2U_LIB.S9S_MB_2U(SCH_1):GND
   41  GND            VSS16  @S9S_MB_2U_LIB.S9S_MB_2U(SCH_1):GND
   39  GND            VSS15  @S9S_MB_2U_LIB.S9S_MB_2U(SCH_1):GND
   37  GND            VSS14  @S9S_MB_2U_LIB.S9S_MB_2U(SCH_1):GND
   35  GND            VSS13  @S9S_MB_2U_LIB.S9S_MB_2U(SCH_1):GND
   32  GND            VSS12  @S9S_MB_2U_LIB.S9S_MB_2U(SCH_1):GND
   30  GND            VSS11  @S9S_MB_2U_LIB.S9S_MB_2U(SCH_1):GND
   28  GND            VSS10  @S9S_MB_2U_LIB.S9S_MB_2U(SCH_1):GND
   26  GND             VSS9  @S9S_MB_2U_LIB.S9S_MB_2U(SCH_1):GND
   24  GND             VSS8  @S9S_MB_2U_LIB.S9S_MB_2U(SCH_1):GND
   21  GND             VSS7  @S9S_MB_2U_LIB.S9S_MB_2U(SCH_1):GND
   19  GND             VSS6  @S9S_MB_2U_LIB.S9S_MB_2U(SCH_1):GND
   17  GND             VSS5  @S9S_MB_2U_LIB.S9S_MB_2U(SCH_1):GND
   15  GND             VSS4  @S9S_MB_2U_LIB.S9S_MB_2U(SCH_1):GND
   13  GND             VSS3  @S9S_MB_2U_LIB.S9S_MB_2U(SCH_1):GND
   10  GND             VSS2  @S9S_MB_2U_LIB.S9S_MB_2U(SCH_1):GND
    8  GND             VSS1  @S9S_MB_2U_LIB.S9S_MB_2U(SCH_1):GND
    6  GND             VSS0  @S9S_MB_2U_LIB.S9S_MB_2U(SCH_1):GND
   G3  GND               G3  @S9S_MB_2U_LIB.S9S_MB_2U(SCH_1):GND
   G2  GND               G2  @S9S_MB_2U_LIB.S9S_MB_2U(SCH_1):GND
   G1  GND               G1  @S9S_MB_2U_LIB.S9S_MB_2U(SCH_1):GND

SCONN288_ADR50001P003C01  I124  J4     [SCONN288_ADR50001P003C01-SCONNA]
   93  M_B_CPU0_SB_DQS_DP<9>  DQS9_B_P  @S9S_MB_2U_LIB.S9S_MB_2U(SCH_1):M_B_CPU0_SB_DQS_DP<9>
  283  M_B_CPU0_SB_DQS_DP<8>  DQS8_B_P  @S9S_MB_2U_LIB.S9S_MB_2U(SCH_1):M_B_CPU0_SB_DQS_DP<8>
  272  M_B_CPU0_SB_DQS_DP<7>  DQS7_B_P  @S9S_MB_2U_LIB.S9S_MB_2U(SCH_1):M_B_CPU0_SB_DQS_DP<7>
  261  M_B_CPU0_SB_DQS_DP<6>  DQS6_B_P  @S9S_MB_2U_LIB.S9S_MB_2U(SCH_1):M_B_CPU0_SB_DQS_DP<6>
  250  M_B_CPU0_SB_DQS_DP<5>  DQS5_B_P  @S9S_MB_2U_LIB.S9S_MB_2U(SCH_1):M_B_CPU0_SB_DQS_DP<5>
  239  M_B_CPU0_SB_DQS_DP<4>  DQS4_B_P  @S9S_MB_2U_LIB.S9S_MB_2U(SCH_1):M_B_CPU0_SB_DQS_DP<4>
  137  M_B_CPU0_SB_DQS_DP<3>  DQS3_B_P  @S9S_MB_2U_LIB.S9S_MB_2U(SCH_1):M_B_CPU0_SB_DQS_DP<3>
  126  M_B_CPU0_SB_DQS_DP<2>  DQS2_B_P  @S9S_MB_2U_LIB.S9S_MB_2U(SCH_1):M_B_CPU0_SB_DQS_DP<2>
  115  M_B_CPU0_SB_DQS_DP<1>  DQS1_B_P  @S9S_MB_2U_LIB.S9S_MB_2U(SCH_1):M_B_CPU0_SB_DQS_DP<1>
  104  M_B_CPU0_SB_DQS_DP<0>  DQS0_B_P  @S9S_MB_2U_LIB.S9S_MB_2U(SCH_1):M_B_CPU0_SB_DQS_DP<0>
   94  M_B_CPU0_SB_DQS_DN<9>  DQS9_B_N  @S9S_MB_2U_LIB.S9S_MB_2U(SCH_1):M_B_CPU0_SB_DQS_DN<9>
  282  M_B_CPU0_SB_DQS_DN<8>  DQS8_B_N  @S9S_MB_2U_LIB.S9S_MB_2U(SCH_1):M_B_CPU0_SB_DQS_DN<8>
  271  M_B_CPU0_SB_DQS_DN<7>  DQS7_B_N  @S9S_MB_2U_LIB.S9S_MB_2U(SCH_1):M_B_CPU0_SB_DQS_DN<7>
  260  M_B_CPU0_SB_DQS_DN<6>  DQS6_B_N  @S9S_MB_2U_LIB.S9S_MB_2U(SCH_1):M_B_CPU0_SB_DQS_DN<6>
  249  M_B_CPU0_SB_DQS_DN<5>  DQS5_B_N  @S9S_MB_2U_LIB.S9S_MB_2U(SCH_1):M_B_CPU0_SB_DQS_DN<5>
  238  M_B_CPU0_SB_DQS_DN<4>  DQS4_B_N  @S9S_MB_2U_LIB.S9S_MB_2U(SCH_1):M_B_CPU0_SB_DQS_DN<4>
  138  M_B_CPU0_SB_DQS_DN<3>  DQS3_B_N  @S9S_MB_2U_LIB.S9S_MB_2U(SCH_1):M_B_CPU0_SB_DQS_DN<3>
  127  M_B_CPU0_SB_DQS_DN<2>  DQS2_B_N  @S9S_MB_2U_LIB.S9S_MB_2U(SCH_1):M_B_CPU0_SB_DQS_DN<2>
  116  M_B_CPU0_SB_DQS_DN<1>  DQS1_B_N  @S9S_MB_2U_LIB.S9S_MB_2U(SCH_1):M_B_CPU0_SB_DQS_DN<1>
  105  M_B_CPU0_SB_DQS_DN<0>  DQS0_B_N  @S9S_MB_2U_LIB.S9S_MB_2U(SCH_1):M_B_CPU0_SB_DQS_DN<0>
  201  M_B_CPU0_SA_DQS_DP<9>  DQS9_A_P  @S9S_MB_2U_LIB.S9S_MB_2U(SCH_1):M_B_CPU0_SA_DQS_DP<9>
  190  M_B_CPU0_SA_DQS_DP<8>  DQS8_A_P  @S9S_MB_2U_LIB.S9S_MB_2U(SCH_1):M_B_CPU0_SA_DQS_DP<8>
  179  M_B_CPU0_SA_DQS_DP<7>  DQS7_A_P  @S9S_MB_2U_LIB.S9S_MB_2U(SCH_1):M_B_CPU0_SA_DQS_DP<7>
  168  M_B_CPU0_SA_DQS_DP<6>  DQS6_A_P  @S9S_MB_2U_LIB.S9S_MB_2U(SCH_1):M_B_CPU0_SA_DQS_DP<6>
  157  M_B_CPU0_SA_DQS_DP<5>  DQS5_A_P  @S9S_MB_2U_LIB.S9S_MB_2U(SCH_1):M_B_CPU0_SA_DQS_DP<5>
   55  M_B_CPU0_SA_DQS_DP<4>  DQS4_A_P  @S9S_MB_2U_LIB.S9S_MB_2U(SCH_1):M_B_CPU0_SA_DQS_DP<4>
   44  M_B_CPU0_SA_DQS_DP<3>  DQS3_A_P  @S9S_MB_2U_LIB.S9S_MB_2U(SCH_1):M_B_CPU0_SA_DQS_DP<3>
   33  M_B_CPU0_SA_DQS_DP<2>  DQS2_A_P  @S9S_MB_2U_LIB.S9S_MB_2U(SCH_1):M_B_CPU0_SA_DQS_DP<2>
   22  M_B_CPU0_SA_DQS_DP<1>  DQS1_A_P  @S9S_MB_2U_LIB.S9S_MB_2U(SCH_1):M_B_CPU0_SA_DQS_DP<1>
   11  M_B_CPU0_SA_DQS_DP<0>  DQS0_A_P  @S9S_MB_2U_LIB.S9S_MB_2U(SCH_1):M_B_CPU0_SA_DQS_DP<0>
  200  M_B_CPU0_SA_DQS_DN<9>  DQS9_A_N  @S9S_MB_2U_LIB.S9S_MB_2U(SCH_1):M_B_CPU0_SA_DQS_DN<9>
  189  M_B_CPU0_SA_DQS_DN<8>  DQS8_A_N  @S9S_MB_2U_LIB.S9S_MB_2U(SCH_1):M_B_CPU0_SA_DQS_DN<8>
  178  M_B_CPU0_SA_DQS_DN<7>  DQS7_A_N  @S9S_MB_2U_LIB.S9S_MB_2U(SCH_1):M_B_CPU0_SA_DQS_DN<7>
  167  M_B_CPU0_SA_DQS_DN<6>  DQS6_A_N  @S9S_MB_2U_LIB.S9S_MB_2U(SCH_1):M_B_CPU0_SA_DQS_DN<6>
  156  M_B_CPU0_SA_DQS_DN<5>  DQS5_A_N  @S9S_MB_2U_LIB.S9S_MB_2U(SCH_1):M_B_CPU0_SA_DQS_DN<5>
   56  M_B_CPU0_SA_DQS_DN<4>  DQS4_A_N  @S9S_MB_2U_LIB.S9S_MB_2U(SCH_1):M_B_CPU0_SA_DQS_DN<4>
   45  M_B_CPU0_SA_DQS_DN<3>  DQS3_A_N  @S9S_MB_2U_LIB.S9S_MB_2U(SCH_1):M_B_CPU0_SA_DQS_DN<3>
   34  M_B_CPU0_SA_DQS_DN<2>  DQS2_A_N  @S9S_MB_2U_LIB.S9S_MB_2U(SCH_1):M_B_CPU0_SA_DQS_DN<2>
   23  M_B_CPU0_SA_DQS_DN<1>  DQS1_A_N  @S9S_MB_2U_LIB.S9S_MB_2U(SCH_1):M_B_CPU0_SA_DQS_DN<1>
   12  M_B_CPU0_SA_DQS_DN<0>  DQS0_A_N  @S9S_MB_2U_LIB.S9S_MB_2U(SCH_1):M_B_CPU0_SA_DQS_DN<0>

SCONN288_ADR50001P003C01  I23  J4     [SCONN288_ADR50001P003C01-SCONNA]
  232  NC              RFU6  NC
  231  NC              RFU5  NC
  220  NC              RFU4  NC
  150  NC              RFU3  NC
  149  NC              RFU2  NC
  144  NC              RFU1  NC
    2  NC              RFU0  NC
  207  RST_M_AB_CPU0_FPGA_N  RESET_N  @S9S_MB_2U_LIB.S9S_MB_2U(SCH_1):RST_M_AB_CPU0_FPGA_N
  147  PWRGD_CHB_CPU0_DIMM2  PWR_GOOD||FAIL_N  @S9S_MB_2U_LIB.S9S_MB_2U(SCH_1):PWRGD_CHB_CPU0_DIMM2
  148  PD_CHB_CPU0_DIMM2_SAA    HAS  @S9S_MB_2U_LIB.S9S_MB_2U(SCH_1):PD_CHB_CPU0_DIMM2_SAA
    3  P3V3_AUX       VIN_MGMT  @S9S_MB_2U_LIB.S9S_MB_2U(SCH_1):P3V3_AUX
   87  M_B_CPU0_SB_RSP<1>  LBS||RSP_N_B  @S9S_MB_2U_LIB.S9S_MB_2U(SCH_1):M_B_CPU0_SB_RSP<1>
  227  M_B_CPU0_SB_PAR  PAR_B  @S9S_MB_2U_LIB.S9S_MB_2U(SCH_1):M_B_CPU0_SB_PAR
  113  M_B_CPU0_SB_DQ<9>  DQ_B9  @S9S_MB_2U_LIB.S9S_MB_2U(SCH_1):M_B_CPU0_SB_DQ<9>
  111  M_B_CPU0_SB_DQ<8>  DQ_B8  @S9S_MB_2U_LIB.S9S_MB_2U(SCH_1):M_B_CPU0_SB_DQ<8>
  254  M_B_CPU0_SB_DQ<7>  DQ_B7  @S9S_MB_2U_LIB.S9S_MB_2U(SCH_1):M_B_CPU0_SB_DQ<7>
  252  M_B_CPU0_SB_DQ<6>  DQ_B6  @S9S_MB_2U_LIB.S9S_MB_2U(SCH_1):M_B_CPU0_SB_DQ<6>
  109  M_B_CPU0_SB_DQ<5>  DQ_B5  @S9S_MB_2U_LIB.S9S_MB_2U(SCH_1):M_B_CPU0_SB_DQ<5>
  107  M_B_CPU0_SB_DQ<4>  DQ_B4  @S9S_MB_2U_LIB.S9S_MB_2U(SCH_1):M_B_CPU0_SB_DQ<4>
  247  M_B_CPU0_SB_DQ<3>  DQ_B3  @S9S_MB_2U_LIB.S9S_MB_2U(SCH_1):M_B_CPU0_SB_DQ<3>
  287  M_B_CPU0_SB_DQ<31>  DQ_B31  @S9S_MB_2U_LIB.S9S_MB_2U(SCH_1):M_B_CPU0_SB_DQ<31>
  285  M_B_CPU0_SB_DQ<30>  DQ_B30  @S9S_MB_2U_LIB.S9S_MB_2U(SCH_1):M_B_CPU0_SB_DQ<30>
  245  M_B_CPU0_SB_DQ<2>  DQ_B2  @S9S_MB_2U_LIB.S9S_MB_2U(SCH_1):M_B_CPU0_SB_DQ<2>
  142  M_B_CPU0_SB_DQ<29>  DQ_B29  @S9S_MB_2U_LIB.S9S_MB_2U(SCH_1):M_B_CPU0_SB_DQ<29>
  140  M_B_CPU0_SB_DQ<28>  DQ_B28  @S9S_MB_2U_LIB.S9S_MB_2U(SCH_1):M_B_CPU0_SB_DQ<28>
  280  M_B_CPU0_SB_DQ<27>  DQ_B27  @S9S_MB_2U_LIB.S9S_MB_2U(SCH_1):M_B_CPU0_SB_DQ<27>
  278  M_B_CPU0_SB_DQ<26>  DQ_B26  @S9S_MB_2U_LIB.S9S_MB_2U(SCH_1):M_B_CPU0_SB_DQ<26>
  135  M_B_CPU0_SB_DQ<25>  DQ_B25  @S9S_MB_2U_LIB.S9S_MB_2U(SCH_1):M_B_CPU0_SB_DQ<25>
  133  M_B_CPU0_SB_DQ<24>  DQ_B24  @S9S_MB_2U_LIB.S9S_MB_2U(SCH_1):M_B_CPU0_SB_DQ<24>
  276  M_B_CPU0_SB_DQ<23>  DQ_B23  @S9S_MB_2U_LIB.S9S_MB_2U(SCH_1):M_B_CPU0_SB_DQ<23>
  274  M_B_CPU0_SB_DQ<22>  DQ_B22  @S9S_MB_2U_LIB.S9S_MB_2U(SCH_1):M_B_CPU0_SB_DQ<22>
  131  M_B_CPU0_SB_DQ<21>  DQ_B21  @S9S_MB_2U_LIB.S9S_MB_2U(SCH_1):M_B_CPU0_SB_DQ<21>
  129  M_B_CPU0_SB_DQ<20>  DQ_B20  @S9S_MB_2U_LIB.S9S_MB_2U(SCH_1):M_B_CPU0_SB_DQ<20>
  102  M_B_CPU0_SB_DQ<1>  DQ_B1  @S9S_MB_2U_LIB.S9S_MB_2U(SCH_1):M_B_CPU0_SB_DQ<1>
  269  M_B_CPU0_SB_DQ<19>  DQ_B19  @S9S_MB_2U_LIB.S9S_MB_2U(SCH_1):M_B_CPU0_SB_DQ<19>
  267  M_B_CPU0_SB_DQ<18>  DQ_B18  @S9S_MB_2U_LIB.S9S_MB_2U(SCH_1):M_B_CPU0_SB_DQ<18>
  124  M_B_CPU0_SB_DQ<17>  DQ_B17  @S9S_MB_2U_LIB.S9S_MB_2U(SCH_1):M_B_CPU0_SB_DQ<17>
  122  M_B_CPU0_SB_DQ<16>  DQ_B16  @S9S_MB_2U_LIB.S9S_MB_2U(SCH_1):M_B_CPU0_SB_DQ<16>
  265  M_B_CPU0_SB_DQ<15>  DQ_B15  @S9S_MB_2U_LIB.S9S_MB_2U(SCH_1):M_B_CPU0_SB_DQ<15>
  263  M_B_CPU0_SB_DQ<14>  DQ_B14  @S9S_MB_2U_LIB.S9S_MB_2U(SCH_1):M_B_CPU0_SB_DQ<14>
  120  M_B_CPU0_SB_DQ<13>  DQ_B13  @S9S_MB_2U_LIB.S9S_MB_2U(SCH_1):M_B_CPU0_SB_DQ<13>
  118  M_B_CPU0_SB_DQ<12>  DQ_B12  @S9S_MB_2U_LIB.S9S_MB_2U(SCH_1):M_B_CPU0_SB_DQ<12>
  258  M_B_CPU0_SB_DQ<11>  DQ_B11  @S9S_MB_2U_LIB.S9S_MB_2U(SCH_1):M_B_CPU0_SB_DQ<11>
  256  M_B_CPU0_SB_DQ<10>  DQ_B10  @S9S_MB_2U_LIB.S9S_MB_2U(SCH_1):M_B_CPU0_SB_DQ<10>
  100  M_B_CPU0_SB_DQ<0>  DQ_B0  @S9S_MB_2U_LIB.S9S_MB_2U(SCH_1):M_B_CPU0_SB_DQ<0>
  229  M_B_CPU0_SB_CS_N<3>  CS1_N_B  @S9S_MB_2U_LIB.S9S_MB_2U(SCH_1):M_B_CPU0_SB_CS_N<3>
   84  M_B_CPU0_SB_CS_N<2>  CS0_N_B  @S9S_MB_2U_LIB.S9S_MB_2U(SCH_1):M_B_CPU0_SB_CS_N<2>
  236  M_B_CPU0_SB_CB<7>  CB_B7  @S9S_MB_2U_LIB.S9S_MB_2U(SCH_1):M_B_CPU0_SB_CB<7>
  234  M_B_CPU0_SB_CB<6>  CB_B6  @S9S_MB_2U_LIB.S9S_MB_2U(SCH_1):M_B_CPU0_SB_CB<6>
   91  M_B_CPU0_SB_CB<5>  CB_B5  @S9S_MB_2U_LIB.S9S_MB_2U(SCH_1):M_B_CPU0_SB_CB<5>
   89  M_B_CPU0_SB_CB<4>  CB_B4  @S9S_MB_2U_LIB.S9S_MB_2U(SCH_1):M_B_CPU0_SB_CB<4>
  243  M_B_CPU0_SB_CB<3>  CB_B3  @S9S_MB_2U_LIB.S9S_MB_2U(SCH_1):M_B_CPU0_SB_CB<3>
  241  M_B_CPU0_SB_CB<2>  CB_B2  @S9S_MB_2U_LIB.S9S_MB_2U(SCH_1):M_B_CPU0_SB_CB<2>
   98  M_B_CPU0_SB_CB<1>  CB_B1  @S9S_MB_2U_LIB.S9S_MB_2U(SCH_1):M_B_CPU0_SB_CB<1>
   96  M_B_CPU0_SB_CB<0>  CB_B0  @S9S_MB_2U_LIB.S9S_MB_2U(SCH_1):M_B_CPU0_SB_CB<0>
   82  M_B_CPU0_SB_CA<6>  CA6_B  @S9S_MB_2U_LIB.S9S_MB_2U(SCH_1):M_B_CPU0_SB_CA<6>
  225  M_B_CPU0_SB_CA<5>  CA5_B  @S9S_MB_2U_LIB.S9S_MB_2U(SCH_1):M_B_CPU0_SB_CA<5>
   80  M_B_CPU0_SB_CA<4>  CA4_B  @S9S_MB_2U_LIB.S9S_MB_2U(SCH_1):M_B_CPU0_SB_CA<4>
  223  M_B_CPU0_SB_CA<3>  CA3_B  @S9S_MB_2U_LIB.S9S_MB_2U(SCH_1):M_B_CPU0_SB_CA<3>
   78  M_B_CPU0_SB_CA<2>  CA2_B  @S9S_MB_2U_LIB.S9S_MB_2U(SCH_1):M_B_CPU0_SB_CA<2>
  221  M_B_CPU0_SB_CA<1>  CA1_B  @S9S_MB_2U_LIB.S9S_MB_2U(SCH_1):M_B_CPU0_SB_CA<1>
   76  M_B_CPU0_SB_CA<0>  CA0_B  @S9S_MB_2U_LIB.S9S_MB_2U(SCH_1):M_B_CPU0_SB_CA<0>
   86  M_B_CPU0_SA_RSP<1>  LBD||RSP_N_A  @S9S_MB_2U_LIB.S9S_MB_2U(SCH_1):M_B_CPU0_SA_RSP<1>
   74  M_B_CPU0_SA_PAR  PAR_A  @S9S_MB_2U_LIB.S9S_MB_2U(SCH_1):M_B_CPU0_SA_PAR
   20  M_B_CPU0_SA_DQ<9>  DQ_A9  @S9S_MB_2U_LIB.S9S_MB_2U(SCH_1):M_B_CPU0_SA_DQ<9>
   18  M_B_CPU0_SA_DQ<8>  DQ_A8  @S9S_MB_2U_LIB.S9S_MB_2U(SCH_1):M_B_CPU0_SA_DQ<8>
  161  M_B_CPU0_SA_DQ<7>  DQ_A7  @S9S_MB_2U_LIB.S9S_MB_2U(SCH_1):M_B_CPU0_SA_DQ<7>
  159  M_B_CPU0_SA_DQ<6>  DQ_A6  @S9S_MB_2U_LIB.S9S_MB_2U(SCH_1):M_B_CPU0_SA_DQ<6>
   16  M_B_CPU0_SA_DQ<5>  DQ_A5  @S9S_MB_2U_LIB.S9S_MB_2U(SCH_1):M_B_CPU0_SA_DQ<5>
   14  M_B_CPU0_SA_DQ<4>  DQ_A4  @S9S_MB_2U_LIB.S9S_MB_2U(SCH_1):M_B_CPU0_SA_DQ<4>
  154  M_B_CPU0_SA_DQ<3>  DQ_A3  @S9S_MB_2U_LIB.S9S_MB_2U(SCH_1):M_B_CPU0_SA_DQ<3>
  194  M_B_CPU0_SA_DQ<31>  DQ_A31  @S9S_MB_2U_LIB.S9S_MB_2U(SCH_1):M_B_CPU0_SA_DQ<31>
  192  M_B_CPU0_SA_DQ<30>  DQ_A30  @S9S_MB_2U_LIB.S9S_MB_2U(SCH_1):M_B_CPU0_SA_DQ<30>
  152  M_B_CPU0_SA_DQ<2>  DQ_A2  @S9S_MB_2U_LIB.S9S_MB_2U(SCH_1):M_B_CPU0_SA_DQ<2>
   49  M_B_CPU0_SA_DQ<29>  DQ_A29  @S9S_MB_2U_LIB.S9S_MB_2U(SCH_1):M_B_CPU0_SA_DQ<29>
   47  M_B_CPU0_SA_DQ<28>  DQ_A28  @S9S_MB_2U_LIB.S9S_MB_2U(SCH_1):M_B_CPU0_SA_DQ<28>
  187  M_B_CPU0_SA_DQ<27>  DQ_A27  @S9S_MB_2U_LIB.S9S_MB_2U(SCH_1):M_B_CPU0_SA_DQ<27>
  185  M_B_CPU0_SA_DQ<26>  DQ_A26  @S9S_MB_2U_LIB.S9S_MB_2U(SCH_1):M_B_CPU0_SA_DQ<26>
   42  M_B_CPU0_SA_DQ<25>  DQ_A25  @S9S_MB_2U_LIB.S9S_MB_2U(SCH_1):M_B_CPU0_SA_DQ<25>
   40  M_B_CPU0_SA_DQ<24>  DQ_A24  @S9S_MB_2U_LIB.S9S_MB_2U(SCH_1):M_B_CPU0_SA_DQ<24>
  183  M_B_CPU0_SA_DQ<23>  DQ_A23  @S9S_MB_2U_LIB.S9S_MB_2U(SCH_1):M_B_CPU0_SA_DQ<23>
  181  M_B_CPU0_SA_DQ<22>  DQ_A22  @S9S_MB_2U_LIB.S9S_MB_2U(SCH_1):M_B_CPU0_SA_DQ<22>
   38  M_B_CPU0_SA_DQ<21>  DQ_A21  @S9S_MB_2U_LIB.S9S_MB_2U(SCH_1):M_B_CPU0_SA_DQ<21>
   36  M_B_CPU0_SA_DQ<20>  DQ_A20  @S9S_MB_2U_LIB.S9S_MB_2U(SCH_1):M_B_CPU0_SA_DQ<20>
    9  M_B_CPU0_SA_DQ<1>  DQ_A1  @S9S_MB_2U_LIB.S9S_MB_2U(SCH_1):M_B_CPU0_SA_DQ<1>
  176  M_B_CPU0_SA_DQ<19>  DQ_A19  @S9S_MB_2U_LIB.S9S_MB_2U(SCH_1):M_B_CPU0_SA_DQ<19>
  174  M_B_CPU0_SA_DQ<18>  DQ_A18  @S9S_MB_2U_LIB.S9S_MB_2U(SCH_1):M_B_CPU0_SA_DQ<18>
   31  M_B_CPU0_SA_DQ<17>  DQ_A17  @S9S_MB_2U_LIB.S9S_MB_2U(SCH_1):M_B_CPU0_SA_DQ<17>
   29  M_B_CPU0_SA_DQ<16>  DQ_A16  @S9S_MB_2U_LIB.S9S_MB_2U(SCH_1):M_B_CPU0_SA_DQ<16>
  172  M_B_CPU0_SA_DQ<15>  DQ_A15  @S9S_MB_2U_LIB.S9S_MB_2U(SCH_1):M_B_CPU0_SA_DQ<15>
  170  M_B_CPU0_SA_DQ<14>  DQ_A14  @S9S_MB_2U_LIB.S9S_MB_2U(SCH_1):M_B_CPU0_SA_DQ<14>
   27  M_B_CPU0_SA_DQ<13>  DQ_A13  @S9S_MB_2U_LIB.S9S_MB_2U(SCH_1):M_B_CPU0_SA_DQ<13>
   25  M_B_CPU0_SA_DQ<12>  DQ_A12  @S9S_MB_2U_LIB.S9S_MB_2U(SCH_1):M_B_CPU0_SA_DQ<12>
  165  M_B_CPU0_SA_DQ<11>  DQ_A11  @S9S_MB_2U_LIB.S9S_MB_2U(SCH_1):M_B_CPU0_SA_DQ<11>
  163  M_B_CPU0_SA_DQ<10>  DQ_A10  @S9S_MB_2U_LIB.S9S_MB_2U(SCH_1):M_B_CPU0_SA_DQ<10>
    7  M_B_CPU0_SA_DQ<0>  DQ_A0  @S9S_MB_2U_LIB.S9S_MB_2U(SCH_1):M_B_CPU0_SA_DQ<0>
  209  M_B_CPU0_SA_CS_N<3>  CS1_N_A  @S9S_MB_2U_LIB.S9S_MB_2U(SCH_1):M_B_CPU0_SA_CS_N<3>
   64  M_B_CPU0_SA_CS_N<2>  CS0_N_A  @S9S_MB_2U_LIB.S9S_MB_2U(SCH_1):M_B_CPU0_SA_CS_N<2>
  205  M_B_CPU0_SA_CB<7>  CB_A7  @S9S_MB_2U_LIB.S9S_MB_2U(SCH_1):M_B_CPU0_SA_CB<7>
  203  M_B_CPU0_SA_CB<6>  CB_A6  @S9S_MB_2U_LIB.S9S_MB_2U(SCH_1):M_B_CPU0_SA_CB<6>
   60  M_B_CPU0_SA_CB<5>  CB_A5  @S9S_MB_2U_LIB.S9S_MB_2U(SCH_1):M_B_CPU0_SA_CB<5>
   58  M_B_CPU0_SA_CB<4>  CB_A4  @S9S_MB_2U_LIB.S9S_MB_2U(SCH_1):M_B_CPU0_SA_CB<4>
  198  M_B_CPU0_SA_CB<3>  CB_A3  @S9S_MB_2U_LIB.S9S_MB_2U(SCH_1):M_B_CPU0_SA_CB<3>
  196  M_B_CPU0_SA_CB<2>  CB_A2  @S9S_MB_2U_LIB.S9S_MB_2U(SCH_1):M_B_CPU0_SA_CB<2>
   53  M_B_CPU0_SA_CB<1>  CB_A1  @S9S_MB_2U_LIB.S9S_MB_2U(SCH_1):M_B_CPU0_SA_CB<1>
   51  M_B_CPU0_SA_CB<0>  CB_A0  @S9S_MB_2U_LIB.S9S_MB_2U(SCH_1):M_B_CPU0_SA_CB<0>
   72  M_B_CPU0_SA_CA<6>  CA6_A  @S9S_MB_2U_LIB.S9S_MB_2U(SCH_1):M_B_CPU0_SA_CA<6>
  215  M_B_CPU0_SA_CA<5>  CA5_A  @S9S_MB_2U_LIB.S9S_MB_2U(SCH_1):M_B_CPU0_SA_CA<5>
   70  M_B_CPU0_SA_CA<4>  CA4_A  @S9S_MB_2U_LIB.S9S_MB_2U(SCH_1):M_B_CPU0_SA_CA<4>
  213  M_B_CPU0_SA_CA<3>  CA3_A  @S9S_MB_2U_LIB.S9S_MB_2U(SCH_1):M_B_CPU0_SA_CA<3>
   68  M_B_CPU0_SA_CA<2>  CA2_A  @S9S_MB_2U_LIB.S9S_MB_2U(SCH_1):M_B_CPU0_SA_CA<2>
  211  M_B_CPU0_SA_CA<1>  CA1_A  @S9S_MB_2U_LIB.S9S_MB_2U(SCH_1):M_B_CPU0_SA_CA<1>
   66  M_B_CPU0_SA_CA<0>  CA0_A  @S9S_MB_2U_LIB.S9S_MB_2U(SCH_1):M_B_CPU0_SA_CA<0>
  217  M_B_CPU0_CLK_DP<1>   CK_P  @S9S_MB_2U_LIB.S9S_MB_2U(SCH_1):M_B_CPU0_CLK_DP<1>
  218  M_B_CPU0_CLK_DN<1>   CK_N  @S9S_MB_2U_LIB.S9S_MB_2U(SCH_1):M_B_CPU0_CLK_DN<1>
   62  M_B_CPU0_ALERT_N  ALERT_N  @S9S_MB_2U_LIB.S9S_MB_2U(SCH_1):M_B_CPU0_ALERT_N
    5  I3C_SPD_DDRABCD_CPU0_LVC1_SDA   HSDA  @S9S_MB_2U_LIB.S9S_MB_2U(SCH_1):I3C_SPD_DDRABCD_CPU0_LVC1_SDA
    4  I3C_SPD_DDRABCD_CPU0_LVC1_SCL   HSCL  @S9S_MB_2U_LIB.S9S_MB_2U(SCH_1):I3C_SPD_DDRABCD_CPU0_LVC1_SCL

SCONN288_ADR50001P013C01  I174  J5     [SCONN288_ADR50001P013C01-SCONNA]
  146  P12V_S3_AUX_CPU0_NVDIMM  VIN_BULK2  @S9S_MB_2U_LIB.S9S_MB_2U(SCH_1):P12V_S3_AUX_CPU0_NVDIMM
  145  P12V_S3_AUX_CPU0_NVDIMM  VIN_BULK1  @S9S_MB_2U_LIB.S9S_MB_2U(SCH_1):P12V_S3_AUX_CPU0_NVDIMM
    1  P12V_S3_AUX_CPU0_NVDIMM  VIN_BULK0  @S9S_MB_2U_LIB.S9S_MB_2U(SCH_1):P12V_S3_AUX_CPU0_NVDIMM
  288  GND            VSS126  @S9S_MB_2U_LIB.S9S_MB_2U(SCH_1):GND
  286  GND            VSS125  @S9S_MB_2U_LIB.S9S_MB_2U(SCH_1):GND
  284  GND            VSS124  @S9S_MB_2U_LIB.S9S_MB_2U(SCH_1):GND
  281  GND            VSS123  @S9S_MB_2U_LIB.S9S_MB_2U(SCH_1):GND
  279  GND            VSS122  @S9S_MB_2U_LIB.S9S_MB_2U(SCH_1):GND
  277  GND            VSS121  @S9S_MB_2U_LIB.S9S_MB_2U(SCH_1):GND
  275  GND            VSS120  @S9S_MB_2U_LIB.S9S_MB_2U(SCH_1):GND
  273  GND            VSS119  @S9S_MB_2U_LIB.S9S_MB_2U(SCH_1):GND
  270  GND            VSS118  @S9S_MB_2U_LIB.S9S_MB_2U(SCH_1):GND
  268  GND            VSS117  @S9S_MB_2U_LIB.S9S_MB_2U(SCH_1):GND
  266  GND            VSS116  @S9S_MB_2U_LIB.S9S_MB_2U(SCH_1):GND
  264  GND            VSS115  @S9S_MB_2U_LIB.S9S_MB_2U(SCH_1):GND
  262  GND            VSS114  @S9S_MB_2U_LIB.S9S_MB_2U(SCH_1):GND
  259  GND            VSS113  @S9S_MB_2U_LIB.S9S_MB_2U(SCH_1):GND
  257  GND            VSS112  @S9S_MB_2U_LIB.S9S_MB_2U(SCH_1):GND
  255  GND            VSS111  @S9S_MB_2U_LIB.S9S_MB_2U(SCH_1):GND
  253  GND            VSS110  @S9S_MB_2U_LIB.S9S_MB_2U(SCH_1):GND
  251  GND            VSS109  @S9S_MB_2U_LIB.S9S_MB_2U(SCH_1):GND
  248  GND            VSS108  @S9S_MB_2U_LIB.S9S_MB_2U(SCH_1):GND
  246  GND            VSS107  @S9S_MB_2U_LIB.S9S_MB_2U(SCH_1):GND
  244  GND            VSS106  @S9S_MB_2U_LIB.S9S_MB_2U(SCH_1):GND
  242  GND            VSS105  @S9S_MB_2U_LIB.S9S_MB_2U(SCH_1):GND
  240  GND            VSS104  @S9S_MB_2U_LIB.S9S_MB_2U(SCH_1):GND
  237  GND            VSS103  @S9S_MB_2U_LIB.S9S_MB_2U(SCH_1):GND
  235  GND            VSS102  @S9S_MB_2U_LIB.S9S_MB_2U(SCH_1):GND
  233  GND            VSS101  @S9S_MB_2U_LIB.S9S_MB_2U(SCH_1):GND
  230  GND            VSS100  @S9S_MB_2U_LIB.S9S_MB_2U(SCH_1):GND
  228  GND            VSS99  @S9S_MB_2U_LIB.S9S_MB_2U(SCH_1):GND
  226  GND            VSS98  @S9S_MB_2U_LIB.S9S_MB_2U(SCH_1):GND
  224  GND            VSS97  @S9S_MB_2U_LIB.S9S_MB_2U(SCH_1):GND
  222  GND            VSS96  @S9S_MB_2U_LIB.S9S_MB_2U(SCH_1):GND
  219  GND            VSS95  @S9S_MB_2U_LIB.S9S_MB_2U(SCH_1):GND
  216  GND            VSS94  @S9S_MB_2U_LIB.S9S_MB_2U(SCH_1):GND
  214  GND            VSS93  @S9S_MB_2U_LIB.S9S_MB_2U(SCH_1):GND
  212  GND            VSS92  @S9S_MB_2U_LIB.S9S_MB_2U(SCH_1):GND
  210  GND            VSS91  @S9S_MB_2U_LIB.S9S_MB_2U(SCH_1):GND
  208  GND            VSS90  @S9S_MB_2U_LIB.S9S_MB_2U(SCH_1):GND
  206  GND            VSS89  @S9S_MB_2U_LIB.S9S_MB_2U(SCH_1):GND
  204  GND            VSS88  @S9S_MB_2U_LIB.S9S_MB_2U(SCH_1):GND
  202  GND            VSS87  @S9S_MB_2U_LIB.S9S_MB_2U(SCH_1):GND
  199  GND            VSS86  @S9S_MB_2U_LIB.S9S_MB_2U(SCH_1):GND
  197  GND            VSS85  @S9S_MB_2U_LIB.S9S_MB_2U(SCH_1):GND
  195  GND            VSS84  @S9S_MB_2U_LIB.S9S_MB_2U(SCH_1):GND
  193  GND            VSS83  @S9S_MB_2U_LIB.S9S_MB_2U(SCH_1):GND
  191  GND            VSS82  @S9S_MB_2U_LIB.S9S_MB_2U(SCH_1):GND
  188  GND            VSS81  @S9S_MB_2U_LIB.S9S_MB_2U(SCH_1):GND
  186  GND            VSS80  @S9S_MB_2U_LIB.S9S_MB_2U(SCH_1):GND
  184  GND            VSS79  @S9S_MB_2U_LIB.S9S_MB_2U(SCH_1):GND
  182  GND            VSS78  @S9S_MB_2U_LIB.S9S_MB_2U(SCH_1):GND
  180  GND            VSS77  @S9S_MB_2U_LIB.S9S_MB_2U(SCH_1):GND
  177  GND            VSS76  @S9S_MB_2U_LIB.S9S_MB_2U(SCH_1):GND
  175  GND            VSS75  @S9S_MB_2U_LIB.S9S_MB_2U(SCH_1):GND
  173  GND            VSS74  @S9S_MB_2U_LIB.S9S_MB_2U(SCH_1):GND
  171  GND            VSS73  @S9S_MB_2U_LIB.S9S_MB_2U(SCH_1):GND
  169  GND            VSS72  @S9S_MB_2U_LIB.S9S_MB_2U(SCH_1):GND
  166  GND            VSS71  @S9S_MB_2U_LIB.S9S_MB_2U(SCH_1):GND
  164  GND            VSS70  @S9S_MB_2U_LIB.S9S_MB_2U(SCH_1):GND
  162  GND            VSS69  @S9S_MB_2U_LIB.S9S_MB_2U(SCH_1):GND
  160  GND            VSS68  @S9S_MB_2U_LIB.S9S_MB_2U(SCH_1):GND
  158  GND            VSS67  @S9S_MB_2U_LIB.S9S_MB_2U(SCH_1):GND
  155  GND            VSS66  @S9S_MB_2U_LIB.S9S_MB_2U(SCH_1):GND
  153  GND            VSS65  @S9S_MB_2U_LIB.S9S_MB_2U(SCH_1):GND
  151  GND            VSS64  @S9S_MB_2U_LIB.S9S_MB_2U(SCH_1):GND
  143  GND            VSS63  @S9S_MB_2U_LIB.S9S_MB_2U(SCH_1):GND
  141  GND            VSS62  @S9S_MB_2U_LIB.S9S_MB_2U(SCH_1):GND
  139  GND            VSS61  @S9S_MB_2U_LIB.S9S_MB_2U(SCH_1):GND
  136  GND            VSS60  @S9S_MB_2U_LIB.S9S_MB_2U(SCH_1):GND
  134  GND            VSS59  @S9S_MB_2U_LIB.S9S_MB_2U(SCH_1):GND
  132  GND            VSS58  @S9S_MB_2U_LIB.S9S_MB_2U(SCH_1):GND
  130  GND            VSS57  @S9S_MB_2U_LIB.S9S_MB_2U(SCH_1):GND
  128  GND            VSS56  @S9S_MB_2U_LIB.S9S_MB_2U(SCH_1):GND
  125  GND            VSS55  @S9S_MB_2U_LIB.S9S_MB_2U(SCH_1):GND
  123  GND            VSS54  @S9S_MB_2U_LIB.S9S_MB_2U(SCH_1):GND
  121  GND            VSS53  @S9S_MB_2U_LIB.S9S_MB_2U(SCH_1):GND
  119  GND            VSS52  @S9S_MB_2U_LIB.S9S_MB_2U(SCH_1):GND
  117  GND            VSS51  @S9S_MB_2U_LIB.S9S_MB_2U(SCH_1):GND
  114  GND            VSS50  @S9S_MB_2U_LIB.S9S_MB_2U(SCH_1):GND
  112  GND            VSS49  @S9S_MB_2U_LIB.S9S_MB_2U(SCH_1):GND
  110  GND            VSS48  @S9S_MB_2U_LIB.S9S_MB_2U(SCH_1):GND
  108  GND            VSS47  @S9S_MB_2U_LIB.S9S_MB_2U(SCH_1):GND
  106  GND            VSS46  @S9S_MB_2U_LIB.S9S_MB_2U(SCH_1):GND
  103  GND            VSS45  @S9S_MB_2U_LIB.S9S_MB_2U(SCH_1):GND
  101  GND            VSS44  @S9S_MB_2U_LIB.S9S_MB_2U(SCH_1):GND
   99  GND            VSS43  @S9S_MB_2U_LIB.S9S_MB_2U(SCH_1):GND
   97  GND            VSS42  @S9S_MB_2U_LIB.S9S_MB_2U(SCH_1):GND
   95  GND            VSS41  @S9S_MB_2U_LIB.S9S_MB_2U(SCH_1):GND
   92  GND            VSS40  @S9S_MB_2U_LIB.S9S_MB_2U(SCH_1):GND
   90  GND            VSS39  @S9S_MB_2U_LIB.S9S_MB_2U(SCH_1):GND
   88  GND            VSS38  @S9S_MB_2U_LIB.S9S_MB_2U(SCH_1):GND
   85  GND            VSS37  @S9S_MB_2U_LIB.S9S_MB_2U(SCH_1):GND
   83  GND            VSS36  @S9S_MB_2U_LIB.S9S_MB_2U(SCH_1):GND
   81  GND            VSS35  @S9S_MB_2U_LIB.S9S_MB_2U(SCH_1):GND
   79  GND            VSS34  @S9S_MB_2U_LIB.S9S_MB_2U(SCH_1):GND
   77  GND            VSS33  @S9S_MB_2U_LIB.S9S_MB_2U(SCH_1):GND
   75  GND            VSS32  @S9S_MB_2U_LIB.S9S_MB_2U(SCH_1):GND
   73  GND            VSS31  @S9S_MB_2U_LIB.S9S_MB_2U(SCH_1):GND
   71  GND            VSS30  @S9S_MB_2U_LIB.S9S_MB_2U(SCH_1):GND
   69  GND            VSS29  @S9S_MB_2U_LIB.S9S_MB_2U(SCH_1):GND
   67  GND            VSS28  @S9S_MB_2U_LIB.S9S_MB_2U(SCH_1):GND
   65  GND            VSS27  @S9S_MB_2U_LIB.S9S_MB_2U(SCH_1):GND
   63  GND            VSS26  @S9S_MB_2U_LIB.S9S_MB_2U(SCH_1):GND
   61  GND            VSS25  @S9S_MB_2U_LIB.S9S_MB_2U(SCH_1):GND
   59  GND            VSS24  @S9S_MB_2U_LIB.S9S_MB_2U(SCH_1):GND
   57  GND            VSS23  @S9S_MB_2U_LIB.S9S_MB_2U(SCH_1):GND
   54  GND            VSS22  @S9S_MB_2U_LIB.S9S_MB_2U(SCH_1):GND
   52  GND            VSS21  @S9S_MB_2U_LIB.S9S_MB_2U(SCH_1):GND
   50  GND            VSS20  @S9S_MB_2U_LIB.S9S_MB_2U(SCH_1):GND
   48  GND            VSS19  @S9S_MB_2U_LIB.S9S_MB_2U(SCH_1):GND
   46  GND            VSS18  @S9S_MB_2U_LIB.S9S_MB_2U(SCH_1):GND
   43  GND            VSS17  @S9S_MB_2U_LIB.S9S_MB_2U(SCH_1):GND
   41  GND            VSS16  @S9S_MB_2U_LIB.S9S_MB_2U(SCH_1):GND
   39  GND            VSS15  @S9S_MB_2U_LIB.S9S_MB_2U(SCH_1):GND
   37  GND            VSS14  @S9S_MB_2U_LIB.S9S_MB_2U(SCH_1):GND
   35  GND            VSS13  @S9S_MB_2U_LIB.S9S_MB_2U(SCH_1):GND
   32  GND            VSS12  @S9S_MB_2U_LIB.S9S_MB_2U(SCH_1):GND
   30  GND            VSS11  @S9S_MB_2U_LIB.S9S_MB_2U(SCH_1):GND
   28  GND            VSS10  @S9S_MB_2U_LIB.S9S_MB_2U(SCH_1):GND
   26  GND             VSS9  @S9S_MB_2U_LIB.S9S_MB_2U(SCH_1):GND
   24  GND             VSS8  @S9S_MB_2U_LIB.S9S_MB_2U(SCH_1):GND
   21  GND             VSS7  @S9S_MB_2U_LIB.S9S_MB_2U(SCH_1):GND
   19  GND             VSS6  @S9S_MB_2U_LIB.S9S_MB_2U(SCH_1):GND
   17  GND             VSS5  @S9S_MB_2U_LIB.S9S_MB_2U(SCH_1):GND
   15  GND             VSS4  @S9S_MB_2U_LIB.S9S_MB_2U(SCH_1):GND
   13  GND             VSS3  @S9S_MB_2U_LIB.S9S_MB_2U(SCH_1):GND
   10  GND             VSS2  @S9S_MB_2U_LIB.S9S_MB_2U(SCH_1):GND
    8  GND             VSS1  @S9S_MB_2U_LIB.S9S_MB_2U(SCH_1):GND
    6  GND             VSS0  @S9S_MB_2U_LIB.S9S_MB_2U(SCH_1):GND
   G3  GND               G3  @S9S_MB_2U_LIB.S9S_MB_2U(SCH_1):GND
   G2  GND               G2  @S9S_MB_2U_LIB.S9S_MB_2U(SCH_1):GND
   G1  GND               G1  @S9S_MB_2U_LIB.S9S_MB_2U(SCH_1):GND

SCONN288_ADR50001P013C01  I125  J5     [SCONN288_ADR50001P013C01-SCONNA]
   93  M_C_CPU0_SB_DQS_DP<9>  DQS9_B_P  @S9S_MB_2U_LIB.S9S_MB_2U(SCH_1):M_C_CPU0_SB_DQS_DP<9>
  283  M_C_CPU0_SB_DQS_DP<8>  DQS8_B_P  @S9S_MB_2U_LIB.S9S_MB_2U(SCH_1):M_C_CPU0_SB_DQS_DP<8>
  272  M_C_CPU0_SB_DQS_DP<7>  DQS7_B_P  @S9S_MB_2U_LIB.S9S_MB_2U(SCH_1):M_C_CPU0_SB_DQS_DP<7>
  261  M_C_CPU0_SB_DQS_DP<6>  DQS6_B_P  @S9S_MB_2U_LIB.S9S_MB_2U(SCH_1):M_C_CPU0_SB_DQS_DP<6>
  250  M_C_CPU0_SB_DQS_DP<5>  DQS5_B_P  @S9S_MB_2U_LIB.S9S_MB_2U(SCH_1):M_C_CPU0_SB_DQS_DP<5>
  239  M_C_CPU0_SB_DQS_DP<4>  DQS4_B_P  @S9S_MB_2U_LIB.S9S_MB_2U(SCH_1):M_C_CPU0_SB_DQS_DP<4>
  137  M_C_CPU0_SB_DQS_DP<3>  DQS3_B_P  @S9S_MB_2U_LIB.S9S_MB_2U(SCH_1):M_C_CPU0_SB_DQS_DP<3>
  126  M_C_CPU0_SB_DQS_DP<2>  DQS2_B_P  @S9S_MB_2U_LIB.S9S_MB_2U(SCH_1):M_C_CPU0_SB_DQS_DP<2>
  115  M_C_CPU0_SB_DQS_DP<1>  DQS1_B_P  @S9S_MB_2U_LIB.S9S_MB_2U(SCH_1):M_C_CPU0_SB_DQS_DP<1>
  104  M_C_CPU0_SB_DQS_DP<0>  DQS0_B_P  @S9S_MB_2U_LIB.S9S_MB_2U(SCH_1):M_C_CPU0_SB_DQS_DP<0>
   94  M_C_CPU0_SB_DQS_DN<9>  DQS9_B_N  @S9S_MB_2U_LIB.S9S_MB_2U(SCH_1):M_C_CPU0_SB_DQS_DN<9>
  282  M_C_CPU0_SB_DQS_DN<8>  DQS8_B_N  @S9S_MB_2U_LIB.S9S_MB_2U(SCH_1):M_C_CPU0_SB_DQS_DN<8>
  271  M_C_CPU0_SB_DQS_DN<7>  DQS7_B_N  @S9S_MB_2U_LIB.S9S_MB_2U(SCH_1):M_C_CPU0_SB_DQS_DN<7>
  260  M_C_CPU0_SB_DQS_DN<6>  DQS6_B_N  @S9S_MB_2U_LIB.S9S_MB_2U(SCH_1):M_C_CPU0_SB_DQS_DN<6>
  249  M_C_CPU0_SB_DQS_DN<5>  DQS5_B_N  @S9S_MB_2U_LIB.S9S_MB_2U(SCH_1):M_C_CPU0_SB_DQS_DN<5>
  238  M_C_CPU0_SB_DQS_DN<4>  DQS4_B_N  @S9S_MB_2U_LIB.S9S_MB_2U(SCH_1):M_C_CPU0_SB_DQS_DN<4>
  138  M_C_CPU0_SB_DQS_DN<3>  DQS3_B_N  @S9S_MB_2U_LIB.S9S_MB_2U(SCH_1):M_C_CPU0_SB_DQS_DN<3>
  127  M_C_CPU0_SB_DQS_DN<2>  DQS2_B_N  @S9S_MB_2U_LIB.S9S_MB_2U(SCH_1):M_C_CPU0_SB_DQS_DN<2>
  116  M_C_CPU0_SB_DQS_DN<1>  DQS1_B_N  @S9S_MB_2U_LIB.S9S_MB_2U(SCH_1):M_C_CPU0_SB_DQS_DN<1>
  105  M_C_CPU0_SB_DQS_DN<0>  DQS0_B_N  @S9S_MB_2U_LIB.S9S_MB_2U(SCH_1):M_C_CPU0_SB_DQS_DN<0>
  201  M_C_CPU0_SA_DQS_DP<9>  DQS9_A_P  @S9S_MB_2U_LIB.S9S_MB_2U(SCH_1):M_C_CPU0_SA_DQS_DP<9>
  190  M_C_CPU0_SA_DQS_DP<8>  DQS8_A_P  @S9S_MB_2U_LIB.S9S_MB_2U(SCH_1):M_C_CPU0_SA_DQS_DP<8>
  179  M_C_CPU0_SA_DQS_DP<7>  DQS7_A_P  @S9S_MB_2U_LIB.S9S_MB_2U(SCH_1):M_C_CPU0_SA_DQS_DP<7>
  168  M_C_CPU0_SA_DQS_DP<6>  DQS6_A_P  @S9S_MB_2U_LIB.S9S_MB_2U(SCH_1):M_C_CPU0_SA_DQS_DP<6>
  157  M_C_CPU0_SA_DQS_DP<5>  DQS5_A_P  @S9S_MB_2U_LIB.S9S_MB_2U(SCH_1):M_C_CPU0_SA_DQS_DP<5>
   55  M_C_CPU0_SA_DQS_DP<4>  DQS4_A_P  @S9S_MB_2U_LIB.S9S_MB_2U(SCH_1):M_C_CPU0_SA_DQS_DP<4>
   44  M_C_CPU0_SA_DQS_DP<3>  DQS3_A_P  @S9S_MB_2U_LIB.S9S_MB_2U(SCH_1):M_C_CPU0_SA_DQS_DP<3>
   33  M_C_CPU0_SA_DQS_DP<2>  DQS2_A_P  @S9S_MB_2U_LIB.S9S_MB_2U(SCH_1):M_C_CPU0_SA_DQS_DP<2>
   22  M_C_CPU0_SA_DQS_DP<1>  DQS1_A_P  @S9S_MB_2U_LIB.S9S_MB_2U(SCH_1):M_C_CPU0_SA_DQS_DP<1>
   11  M_C_CPU0_SA_DQS_DP<0>  DQS0_A_P  @S9S_MB_2U_LIB.S9S_MB_2U(SCH_1):M_C_CPU0_SA_DQS_DP<0>
  200  M_C_CPU0_SA_DQS_DN<9>  DQS9_A_N  @S9S_MB_2U_LIB.S9S_MB_2U(SCH_1):M_C_CPU0_SA_DQS_DN<9>
  189  M_C_CPU0_SA_DQS_DN<8>  DQS8_A_N  @S9S_MB_2U_LIB.S9S_MB_2U(SCH_1):M_C_CPU0_SA_DQS_DN<8>
  178  M_C_CPU0_SA_DQS_DN<7>  DQS7_A_N  @S9S_MB_2U_LIB.S9S_MB_2U(SCH_1):M_C_CPU0_SA_DQS_DN<7>
  167  M_C_CPU0_SA_DQS_DN<6>  DQS6_A_N  @S9S_MB_2U_LIB.S9S_MB_2U(SCH_1):M_C_CPU0_SA_DQS_DN<6>
  156  M_C_CPU0_SA_DQS_DN<5>  DQS5_A_N  @S9S_MB_2U_LIB.S9S_MB_2U(SCH_1):M_C_CPU0_SA_DQS_DN<5>
   56  M_C_CPU0_SA_DQS_DN<4>  DQS4_A_N  @S9S_MB_2U_LIB.S9S_MB_2U(SCH_1):M_C_CPU0_SA_DQS_DN<4>
   45  M_C_CPU0_SA_DQS_DN<3>  DQS3_A_N  @S9S_MB_2U_LIB.S9S_MB_2U(SCH_1):M_C_CPU0_SA_DQS_DN<3>
   34  M_C_CPU0_SA_DQS_DN<2>  DQS2_A_N  @S9S_MB_2U_LIB.S9S_MB_2U(SCH_1):M_C_CPU0_SA_DQS_DN<2>
   23  M_C_CPU0_SA_DQS_DN<1>  DQS1_A_N  @S9S_MB_2U_LIB.S9S_MB_2U(SCH_1):M_C_CPU0_SA_DQS_DN<1>
   12  M_C_CPU0_SA_DQS_DN<0>  DQS0_A_N  @S9S_MB_2U_LIB.S9S_MB_2U(SCH_1):M_C_CPU0_SA_DQS_DN<0>

SCONN288_ADR50001P013C01  I24  J5     [SCONN288_ADR50001P013C01-SCONNA]
  232  NC              RFU6  NC
  231  NC              RFU5  NC
  220  NC              RFU4  NC
  150  NC              RFU3  NC
  149  NC              RFU2  NC
  144  NC              RFU1  NC
    2  NC              RFU0  NC
  207  RST_M_CD_CPU0_FPGA_N  RESET_N  @S9S_MB_2U_LIB.S9S_MB_2U(SCH_1):RST_M_CD_CPU0_FPGA_N
  147  PWRGD_CHC_CPU0_DIMM1  PWR_GOOD||FAIL_N  @S9S_MB_2U_LIB.S9S_MB_2U(SCH_1):PWRGD_CHC_CPU0_DIMM1
  148  PD_CHC_CPU0_DIMM1_SAA    HAS  @S9S_MB_2U_LIB.S9S_MB_2U(SCH_1):PD_CHC_CPU0_DIMM1_SAA
    3  P3V3_AUX       VIN_MGMT  @S9S_MB_2U_LIB.S9S_MB_2U(SCH_1):P3V3_AUX
   87  M_C_CPU0_SB_RSP<0>  LBS||RSP_N_B  @S9S_MB_2U_LIB.S9S_MB_2U(SCH_1):M_C_CPU0_SB_RSP<0>
  227  M_C_CPU0_SB_PAR  PAR_B  @S9S_MB_2U_LIB.S9S_MB_2U(SCH_1):M_C_CPU0_SB_PAR
  113  M_C_CPU0_SB_DQ<9>  DQ_B9  @S9S_MB_2U_LIB.S9S_MB_2U(SCH_1):M_C_CPU0_SB_DQ<9>
  111  M_C_CPU0_SB_DQ<8>  DQ_B8  @S9S_MB_2U_LIB.S9S_MB_2U(SCH_1):M_C_CPU0_SB_DQ<8>
  254  M_C_CPU0_SB_DQ<7>  DQ_B7  @S9S_MB_2U_LIB.S9S_MB_2U(SCH_1):M_C_CPU0_SB_DQ<7>
  252  M_C_CPU0_SB_DQ<6>  DQ_B6  @S9S_MB_2U_LIB.S9S_MB_2U(SCH_1):M_C_CPU0_SB_DQ<6>
  109  M_C_CPU0_SB_DQ<5>  DQ_B5  @S9S_MB_2U_LIB.S9S_MB_2U(SCH_1):M_C_CPU0_SB_DQ<5>
  107  M_C_CPU0_SB_DQ<4>  DQ_B4  @S9S_MB_2U_LIB.S9S_MB_2U(SCH_1):M_C_CPU0_SB_DQ<4>
  247  M_C_CPU0_SB_DQ<3>  DQ_B3  @S9S_MB_2U_LIB.S9S_MB_2U(SCH_1):M_C_CPU0_SB_DQ<3>
  287  M_C_CPU0_SB_DQ<31>  DQ_B31  @S9S_MB_2U_LIB.S9S_MB_2U(SCH_1):M_C_CPU0_SB_DQ<31>
  285  M_C_CPU0_SB_DQ<30>  DQ_B30  @S9S_MB_2U_LIB.S9S_MB_2U(SCH_1):M_C_CPU0_SB_DQ<30>
  245  M_C_CPU0_SB_DQ<2>  DQ_B2  @S9S_MB_2U_LIB.S9S_MB_2U(SCH_1):M_C_CPU0_SB_DQ<2>
  142  M_C_CPU0_SB_DQ<29>  DQ_B29  @S9S_MB_2U_LIB.S9S_MB_2U(SCH_1):M_C_CPU0_SB_DQ<29>
  140  M_C_CPU0_SB_DQ<28>  DQ_B28  @S9S_MB_2U_LIB.S9S_MB_2U(SCH_1):M_C_CPU0_SB_DQ<28>
  280  M_C_CPU0_SB_DQ<27>  DQ_B27  @S9S_MB_2U_LIB.S9S_MB_2U(SCH_1):M_C_CPU0_SB_DQ<27>
  278  M_C_CPU0_SB_DQ<26>  DQ_B26  @S9S_MB_2U_LIB.S9S_MB_2U(SCH_1):M_C_CPU0_SB_DQ<26>
  135  M_C_CPU0_SB_DQ<25>  DQ_B25  @S9S_MB_2U_LIB.S9S_MB_2U(SCH_1):M_C_CPU0_SB_DQ<25>
  133  M_C_CPU0_SB_DQ<24>  DQ_B24  @S9S_MB_2U_LIB.S9S_MB_2U(SCH_1):M_C_CPU0_SB_DQ<24>
  276  M_C_CPU0_SB_DQ<23>  DQ_B23  @S9S_MB_2U_LIB.S9S_MB_2U(SCH_1):M_C_CPU0_SB_DQ<23>
  274  M_C_CPU0_SB_DQ<22>  DQ_B22  @S9S_MB_2U_LIB.S9S_MB_2U(SCH_1):M_C_CPU0_SB_DQ<22>
  131  M_C_CPU0_SB_DQ<21>  DQ_B21  @S9S_MB_2U_LIB.S9S_MB_2U(SCH_1):M_C_CPU0_SB_DQ<21>
  129  M_C_CPU0_SB_DQ<20>  DQ_B20  @S9S_MB_2U_LIB.S9S_MB_2U(SCH_1):M_C_CPU0_SB_DQ<20>
  102  M_C_CPU0_SB_DQ<1>  DQ_B1  @S9S_MB_2U_LIB.S9S_MB_2U(SCH_1):M_C_CPU0_SB_DQ<1>
  269  M_C_CPU0_SB_DQ<19>  DQ_B19  @S9S_MB_2U_LIB.S9S_MB_2U(SCH_1):M_C_CPU0_SB_DQ<19>
  267  M_C_CPU0_SB_DQ<18>  DQ_B18  @S9S_MB_2U_LIB.S9S_MB_2U(SCH_1):M_C_CPU0_SB_DQ<18>
  124  M_C_CPU0_SB_DQ<17>  DQ_B17  @S9S_MB_2U_LIB.S9S_MB_2U(SCH_1):M_C_CPU0_SB_DQ<17>
  122  M_C_CPU0_SB_DQ<16>  DQ_B16  @S9S_MB_2U_LIB.S9S_MB_2U(SCH_1):M_C_CPU0_SB_DQ<16>
  265  M_C_CPU0_SB_DQ<15>  DQ_B15  @S9S_MB_2U_LIB.S9S_MB_2U(SCH_1):M_C_CPU0_SB_DQ<15>
  263  M_C_CPU0_SB_DQ<14>  DQ_B14  @S9S_MB_2U_LIB.S9S_MB_2U(SCH_1):M_C_CPU0_SB_DQ<14>
  120  M_C_CPU0_SB_DQ<13>  DQ_B13  @S9S_MB_2U_LIB.S9S_MB_2U(SCH_1):M_C_CPU0_SB_DQ<13>
  118  M_C_CPU0_SB_DQ<12>  DQ_B12  @S9S_MB_2U_LIB.S9S_MB_2U(SCH_1):M_C_CPU0_SB_DQ<12>
  258  M_C_CPU0_SB_DQ<11>  DQ_B11  @S9S_MB_2U_LIB.S9S_MB_2U(SCH_1):M_C_CPU0_SB_DQ<11>
  256  M_C_CPU0_SB_DQ<10>  DQ_B10  @S9S_MB_2U_LIB.S9S_MB_2U(SCH_1):M_C_CPU0_SB_DQ<10>
  100  M_C_CPU0_SB_DQ<0>  DQ_B0  @S9S_MB_2U_LIB.S9S_MB_2U(SCH_1):M_C_CPU0_SB_DQ<0>
  229  M_C_CPU0_SB_CS_N<1>  CS1_N_B  @S9S_MB_2U_LIB.S9S_MB_2U(SCH_1):M_C_CPU0_SB_CS_N<1>
   84  M_C_CPU0_SB_CS_N<0>  CS0_N_B  @S9S_MB_2U_LIB.S9S_MB_2U(SCH_1):M_C_CPU0_SB_CS_N<0>
  236  M_C_CPU0_SB_CB<7>  CB_B7  @S9S_MB_2U_LIB.S9S_MB_2U(SCH_1):M_C_CPU0_SB_CB<7>
  234  M_C_CPU0_SB_CB<6>  CB_B6  @S9S_MB_2U_LIB.S9S_MB_2U(SCH_1):M_C_CPU0_SB_CB<6>
   91  M_C_CPU0_SB_CB<5>  CB_B5  @S9S_MB_2U_LIB.S9S_MB_2U(SCH_1):M_C_CPU0_SB_CB<5>
   89  M_C_CPU0_SB_CB<4>  CB_B4  @S9S_MB_2U_LIB.S9S_MB_2U(SCH_1):M_C_CPU0_SB_CB<4>
  243  M_C_CPU0_SB_CB<3>  CB_B3  @S9S_MB_2U_LIB.S9S_MB_2U(SCH_1):M_C_CPU0_SB_CB<3>
  241  M_C_CPU0_SB_CB<2>  CB_B2  @S9S_MB_2U_LIB.S9S_MB_2U(SCH_1):M_C_CPU0_SB_CB<2>
   98  M_C_CPU0_SB_CB<1>  CB_B1  @S9S_MB_2U_LIB.S9S_MB_2U(SCH_1):M_C_CPU0_SB_CB<1>
   96  M_C_CPU0_SB_CB<0>  CB_B0  @S9S_MB_2U_LIB.S9S_MB_2U(SCH_1):M_C_CPU0_SB_CB<0>
   82  M_C_CPU0_SB_CA<6>  CA6_B  @S9S_MB_2U_LIB.S9S_MB_2U(SCH_1):M_C_CPU0_SB_CA<6>
  225  M_C_CPU0_SB_CA<5>  CA5_B  @S9S_MB_2U_LIB.S9S_MB_2U(SCH_1):M_C_CPU0_SB_CA<5>
   80  M_C_CPU0_SB_CA<4>  CA4_B  @S9S_MB_2U_LIB.S9S_MB_2U(SCH_1):M_C_CPU0_SB_CA<4>
  223  M_C_CPU0_SB_CA<3>  CA3_B  @S9S_MB_2U_LIB.S9S_MB_2U(SCH_1):M_C_CPU0_SB_CA<3>
   78  M_C_CPU0_SB_CA<2>  CA2_B  @S9S_MB_2U_LIB.S9S_MB_2U(SCH_1):M_C_CPU0_SB_CA<2>
  221  M_C_CPU0_SB_CA<1>  CA1_B  @S9S_MB_2U_LIB.S9S_MB_2U(SCH_1):M_C_CPU0_SB_CA<1>
   76  M_C_CPU0_SB_CA<0>  CA0_B  @S9S_MB_2U_LIB.S9S_MB_2U(SCH_1):M_C_CPU0_SB_CA<0>
   86  M_C_CPU0_SA_RSP<0>  LBD||RSP_N_A  @S9S_MB_2U_LIB.S9S_MB_2U(SCH_1):M_C_CPU0_SA_RSP<0>
   74  M_C_CPU0_SA_PAR  PAR_A  @S9S_MB_2U_LIB.S9S_MB_2U(SCH_1):M_C_CPU0_SA_PAR
   20  M_C_CPU0_SA_DQ<9>  DQ_A9  @S9S_MB_2U_LIB.S9S_MB_2U(SCH_1):M_C_CPU0_SA_DQ<9>
   18  M_C_CPU0_SA_DQ<8>  DQ_A8  @S9S_MB_2U_LIB.S9S_MB_2U(SCH_1):M_C_CPU0_SA_DQ<8>
  161  M_C_CPU0_SA_DQ<7>  DQ_A7  @S9S_MB_2U_LIB.S9S_MB_2U(SCH_1):M_C_CPU0_SA_DQ<7>
  159  M_C_CPU0_SA_DQ<6>  DQ_A6  @S9S_MB_2U_LIB.S9S_MB_2U(SCH_1):M_C_CPU0_SA_DQ<6>
   16  M_C_CPU0_SA_DQ<5>  DQ_A5  @S9S_MB_2U_LIB.S9S_MB_2U(SCH_1):M_C_CPU0_SA_DQ<5>
   14  M_C_CPU0_SA_DQ<4>  DQ_A4  @S9S_MB_2U_LIB.S9S_MB_2U(SCH_1):M_C_CPU0_SA_DQ<4>
  154  M_C_CPU0_SA_DQ<3>  DQ_A3  @S9S_MB_2U_LIB.S9S_MB_2U(SCH_1):M_C_CPU0_SA_DQ<3>
  194  M_C_CPU0_SA_DQ<31>  DQ_A31  @S9S_MB_2U_LIB.S9S_MB_2U(SCH_1):M_C_CPU0_SA_DQ<31>
  192  M_C_CPU0_SA_DQ<30>  DQ_A30  @S9S_MB_2U_LIB.S9S_MB_2U(SCH_1):M_C_CPU0_SA_DQ<30>
  152  M_C_CPU0_SA_DQ<2>  DQ_A2  @S9S_MB_2U_LIB.S9S_MB_2U(SCH_1):M_C_CPU0_SA_DQ<2>
   49  M_C_CPU0_SA_DQ<29>  DQ_A29  @S9S_MB_2U_LIB.S9S_MB_2U(SCH_1):M_C_CPU0_SA_DQ<29>
   47  M_C_CPU0_SA_DQ<28>  DQ_A28  @S9S_MB_2U_LIB.S9S_MB_2U(SCH_1):M_C_CPU0_SA_DQ<28>
  187  M_C_CPU0_SA_DQ<27>  DQ_A27  @S9S_MB_2U_LIB.S9S_MB_2U(SCH_1):M_C_CPU0_SA_DQ<27>
  185  M_C_CPU0_SA_DQ<26>  DQ_A26  @S9S_MB_2U_LIB.S9S_MB_2U(SCH_1):M_C_CPU0_SA_DQ<26>
   42  M_C_CPU0_SA_DQ<25>  DQ_A25  @S9S_MB_2U_LIB.S9S_MB_2U(SCH_1):M_C_CPU0_SA_DQ<25>
   40  M_C_CPU0_SA_DQ<24>  DQ_A24  @S9S_MB_2U_LIB.S9S_MB_2U(SCH_1):M_C_CPU0_SA_DQ<24>
  183  M_C_CPU0_SA_DQ<23>  DQ_A23  @S9S_MB_2U_LIB.S9S_MB_2U(SCH_1):M_C_CPU0_SA_DQ<23>
  181  M_C_CPU0_SA_DQ<22>  DQ_A22  @S9S_MB_2U_LIB.S9S_MB_2U(SCH_1):M_C_CPU0_SA_DQ<22>
   38  M_C_CPU0_SA_DQ<21>  DQ_A21  @S9S_MB_2U_LIB.S9S_MB_2U(SCH_1):M_C_CPU0_SA_DQ<21>
   36  M_C_CPU0_SA_DQ<20>  DQ_A20  @S9S_MB_2U_LIB.S9S_MB_2U(SCH_1):M_C_CPU0_SA_DQ<20>
    9  M_C_CPU0_SA_DQ<1>  DQ_A1  @S9S_MB_2U_LIB.S9S_MB_2U(SCH_1):M_C_CPU0_SA_DQ<1>
  176  M_C_CPU0_SA_DQ<19>  DQ_A19  @S9S_MB_2U_LIB.S9S_MB_2U(SCH_1):M_C_CPU0_SA_DQ<19>
  174  M_C_CPU0_SA_DQ<18>  DQ_A18  @S9S_MB_2U_LIB.S9S_MB_2U(SCH_1):M_C_CPU0_SA_DQ<18>
   31  M_C_CPU0_SA_DQ<17>  DQ_A17  @S9S_MB_2U_LIB.S9S_MB_2U(SCH_1):M_C_CPU0_SA_DQ<17>
   29  M_C_CPU0_SA_DQ<16>  DQ_A16  @S9S_MB_2U_LIB.S9S_MB_2U(SCH_1):M_C_CPU0_SA_DQ<16>
  172  M_C_CPU0_SA_DQ<15>  DQ_A15  @S9S_MB_2U_LIB.S9S_MB_2U(SCH_1):M_C_CPU0_SA_DQ<15>
  170  M_C_CPU0_SA_DQ<14>  DQ_A14  @S9S_MB_2U_LIB.S9S_MB_2U(SCH_1):M_C_CPU0_SA_DQ<14>
   27  M_C_CPU0_SA_DQ<13>  DQ_A13  @S9S_MB_2U_LIB.S9S_MB_2U(SCH_1):M_C_CPU0_SA_DQ<13>
   25  M_C_CPU0_SA_DQ<12>  DQ_A12  @S9S_MB_2U_LIB.S9S_MB_2U(SCH_1):M_C_CPU0_SA_DQ<12>
  165  M_C_CPU0_SA_DQ<11>  DQ_A11  @S9S_MB_2U_LIB.S9S_MB_2U(SCH_1):M_C_CPU0_SA_DQ<11>
  163  M_C_CPU0_SA_DQ<10>  DQ_A10  @S9S_MB_2U_LIB.S9S_MB_2U(SCH_1):M_C_CPU0_SA_DQ<10>
    7  M_C_CPU0_SA_DQ<0>  DQ_A0  @S9S_MB_2U_LIB.S9S_MB_2U(SCH_1):M_C_CPU0_SA_DQ<0>
  209  M_C_CPU0_SA_CS_N<1>  CS1_N_A  @S9S_MB_2U_LIB.S9S_MB_2U(SCH_1):M_C_CPU0_SA_CS_N<1>
   64  M_C_CPU0_SA_CS_N<0>  CS0_N_A  @S9S_MB_2U_LIB.S9S_MB_2U(SCH_1):M_C_CPU0_SA_CS_N<0>
  205  M_C_CPU0_SA_CB<7>  CB_A7  @S9S_MB_2U_LIB.S9S_MB_2U(SCH_1):M_C_CPU0_SA_CB<7>
  203  M_C_CPU0_SA_CB<6>  CB_A6  @S9S_MB_2U_LIB.S9S_MB_2U(SCH_1):M_C_CPU0_SA_CB<6>
   60  M_C_CPU0_SA_CB<5>  CB_A5  @S9S_MB_2U_LIB.S9S_MB_2U(SCH_1):M_C_CPU0_SA_CB<5>
   58  M_C_CPU0_SA_CB<4>  CB_A4  @S9S_MB_2U_LIB.S9S_MB_2U(SCH_1):M_C_CPU0_SA_CB<4>
  198  M_C_CPU0_SA_CB<3>  CB_A3  @S9S_MB_2U_LIB.S9S_MB_2U(SCH_1):M_C_CPU0_SA_CB<3>
  196  M_C_CPU0_SA_CB<2>  CB_A2  @S9S_MB_2U_LIB.S9S_MB_2U(SCH_1):M_C_CPU0_SA_CB<2>
   53  M_C_CPU0_SA_CB<1>  CB_A1  @S9S_MB_2U_LIB.S9S_MB_2U(SCH_1):M_C_CPU0_SA_CB<1>
   51  M_C_CPU0_SA_CB<0>  CB_A0  @S9S_MB_2U_LIB.S9S_MB_2U(SCH_1):M_C_CPU0_SA_CB<0>
   72  M_C_CPU0_SA_CA<6>  CA6_A  @S9S_MB_2U_LIB.S9S_MB_2U(SCH_1):M_C_CPU0_SA_CA<6>
  215  M_C_CPU0_SA_CA<5>  CA5_A  @S9S_MB_2U_LIB.S9S_MB_2U(SCH_1):M_C_CPU0_SA_CA<5>
   70  M_C_CPU0_SA_CA<4>  CA4_A  @S9S_MB_2U_LIB.S9S_MB_2U(SCH_1):M_C_CPU0_SA_CA<4>
  213  M_C_CPU0_SA_CA<3>  CA3_A  @S9S_MB_2U_LIB.S9S_MB_2U(SCH_1):M_C_CPU0_SA_CA<3>
   68  M_C_CPU0_SA_CA<2>  CA2_A  @S9S_MB_2U_LIB.S9S_MB_2U(SCH_1):M_C_CPU0_SA_CA<2>
  211  M_C_CPU0_SA_CA<1>  CA1_A  @S9S_MB_2U_LIB.S9S_MB_2U(SCH_1):M_C_CPU0_SA_CA<1>
   66  M_C_CPU0_SA_CA<0>  CA0_A  @S9S_MB_2U_LIB.S9S_MB_2U(SCH_1):M_C_CPU0_SA_CA<0>
  217  M_C_CPU0_CLK_DP<0>   CK_P  @S9S_MB_2U_LIB.S9S_MB_2U(SCH_1):M_C_CPU0_CLK_DP<0>
  218  M_C_CPU0_CLK_DN<0>   CK_N  @S9S_MB_2U_LIB.S9S_MB_2U(SCH_1):M_C_CPU0_CLK_DN<0>
   62  M_C_CPU0_ALERT_N  ALERT_N  @S9S_MB_2U_LIB.S9S_MB_2U(SCH_1):M_C_CPU0_ALERT_N
    5  I3C_SPD_DDRABCD_CPU0_LVC1_SDA   HSDA  @S9S_MB_2U_LIB.S9S_MB_2U(SCH_1):I3C_SPD_DDRABCD_CPU0_LVC1_SDA
    4  I3C_SPD_DDRABCD_CPU0_LVC1_SCL   HSCL  @S9S_MB_2U_LIB.S9S_MB_2U(SCH_1):I3C_SPD_DDRABCD_CPU0_LVC1_SCL

SCONN288_ADR50001P003C01  I175  J6     [SCONN288_ADR50001P003C01-SCONNA]
  146  P12V_S3_AUX_CPU0_NVDIMM  VIN_BULK2  @S9S_MB_2U_LIB.S9S_MB_2U(SCH_1):P12V_S3_AUX_CPU0_NVDIMM
  145  P12V_S3_AUX_CPU0_NVDIMM  VIN_BULK1  @S9S_MB_2U_LIB.S9S_MB_2U(SCH_1):P12V_S3_AUX_CPU0_NVDIMM
    1  P12V_S3_AUX_CPU0_NVDIMM  VIN_BULK0  @S9S_MB_2U_LIB.S9S_MB_2U(SCH_1):P12V_S3_AUX_CPU0_NVDIMM
  288  GND            VSS126  @S9S_MB_2U_LIB.S9S_MB_2U(SCH_1):GND
  286  GND            VSS125  @S9S_MB_2U_LIB.S9S_MB_2U(SCH_1):GND
  284  GND            VSS124  @S9S_MB_2U_LIB.S9S_MB_2U(SCH_1):GND
  281  GND            VSS123  @S9S_MB_2U_LIB.S9S_MB_2U(SCH_1):GND
  279  GND            VSS122  @S9S_MB_2U_LIB.S9S_MB_2U(SCH_1):GND
  277  GND            VSS121  @S9S_MB_2U_LIB.S9S_MB_2U(SCH_1):GND
  275  GND            VSS120  @S9S_MB_2U_LIB.S9S_MB_2U(SCH_1):GND
  273  GND            VSS119  @S9S_MB_2U_LIB.S9S_MB_2U(SCH_1):GND
  270  GND            VSS118  @S9S_MB_2U_LIB.S9S_MB_2U(SCH_1):GND
  268  GND            VSS117  @S9S_MB_2U_LIB.S9S_MB_2U(SCH_1):GND
  266  GND            VSS116  @S9S_MB_2U_LIB.S9S_MB_2U(SCH_1):GND
  264  GND            VSS115  @S9S_MB_2U_LIB.S9S_MB_2U(SCH_1):GND
  262  GND            VSS114  @S9S_MB_2U_LIB.S9S_MB_2U(SCH_1):GND
  259  GND            VSS113  @S9S_MB_2U_LIB.S9S_MB_2U(SCH_1):GND
  257  GND            VSS112  @S9S_MB_2U_LIB.S9S_MB_2U(SCH_1):GND
  255  GND            VSS111  @S9S_MB_2U_LIB.S9S_MB_2U(SCH_1):GND
  253  GND            VSS110  @S9S_MB_2U_LIB.S9S_MB_2U(SCH_1):GND
  251  GND            VSS109  @S9S_MB_2U_LIB.S9S_MB_2U(SCH_1):GND
  248  GND            VSS108  @S9S_MB_2U_LIB.S9S_MB_2U(SCH_1):GND
  246  GND            VSS107  @S9S_MB_2U_LIB.S9S_MB_2U(SCH_1):GND
  244  GND            VSS106  @S9S_MB_2U_LIB.S9S_MB_2U(SCH_1):GND
  242  GND            VSS105  @S9S_MB_2U_LIB.S9S_MB_2U(SCH_1):GND
  240  GND            VSS104  @S9S_MB_2U_LIB.S9S_MB_2U(SCH_1):GND
  237  GND            VSS103  @S9S_MB_2U_LIB.S9S_MB_2U(SCH_1):GND
  235  GND            VSS102  @S9S_MB_2U_LIB.S9S_MB_2U(SCH_1):GND
  233  GND            VSS101  @S9S_MB_2U_LIB.S9S_MB_2U(SCH_1):GND
  230  GND            VSS100  @S9S_MB_2U_LIB.S9S_MB_2U(SCH_1):GND
  228  GND            VSS99  @S9S_MB_2U_LIB.S9S_MB_2U(SCH_1):GND
  226  GND            VSS98  @S9S_MB_2U_LIB.S9S_MB_2U(SCH_1):GND
  224  GND            VSS97  @S9S_MB_2U_LIB.S9S_MB_2U(SCH_1):GND
  222  GND            VSS96  @S9S_MB_2U_LIB.S9S_MB_2U(SCH_1):GND
  219  GND            VSS95  @S9S_MB_2U_LIB.S9S_MB_2U(SCH_1):GND
  216  GND            VSS94  @S9S_MB_2U_LIB.S9S_MB_2U(SCH_1):GND
  214  GND            VSS93  @S9S_MB_2U_LIB.S9S_MB_2U(SCH_1):GND
  212  GND            VSS92  @S9S_MB_2U_LIB.S9S_MB_2U(SCH_1):GND
  210  GND            VSS91  @S9S_MB_2U_LIB.S9S_MB_2U(SCH_1):GND
  208  GND            VSS90  @S9S_MB_2U_LIB.S9S_MB_2U(SCH_1):GND
  206  GND            VSS89  @S9S_MB_2U_LIB.S9S_MB_2U(SCH_1):GND
  204  GND            VSS88  @S9S_MB_2U_LIB.S9S_MB_2U(SCH_1):GND
  202  GND            VSS87  @S9S_MB_2U_LIB.S9S_MB_2U(SCH_1):GND
  199  GND            VSS86  @S9S_MB_2U_LIB.S9S_MB_2U(SCH_1):GND
  197  GND            VSS85  @S9S_MB_2U_LIB.S9S_MB_2U(SCH_1):GND
  195  GND            VSS84  @S9S_MB_2U_LIB.S9S_MB_2U(SCH_1):GND
  193  GND            VSS83  @S9S_MB_2U_LIB.S9S_MB_2U(SCH_1):GND
  191  GND            VSS82  @S9S_MB_2U_LIB.S9S_MB_2U(SCH_1):GND
  188  GND            VSS81  @S9S_MB_2U_LIB.S9S_MB_2U(SCH_1):GND
  186  GND            VSS80  @S9S_MB_2U_LIB.S9S_MB_2U(SCH_1):GND
  184  GND            VSS79  @S9S_MB_2U_LIB.S9S_MB_2U(SCH_1):GND
  182  GND            VSS78  @S9S_MB_2U_LIB.S9S_MB_2U(SCH_1):GND
  180  GND            VSS77  @S9S_MB_2U_LIB.S9S_MB_2U(SCH_1):GND
  177  GND            VSS76  @S9S_MB_2U_LIB.S9S_MB_2U(SCH_1):GND
  175  GND            VSS75  @S9S_MB_2U_LIB.S9S_MB_2U(SCH_1):GND
  173  GND            VSS74  @S9S_MB_2U_LIB.S9S_MB_2U(SCH_1):GND
  171  GND            VSS73  @S9S_MB_2U_LIB.S9S_MB_2U(SCH_1):GND
  169  GND            VSS72  @S9S_MB_2U_LIB.S9S_MB_2U(SCH_1):GND
  166  GND            VSS71  @S9S_MB_2U_LIB.S9S_MB_2U(SCH_1):GND
  164  GND            VSS70  @S9S_MB_2U_LIB.S9S_MB_2U(SCH_1):GND
  162  GND            VSS69  @S9S_MB_2U_LIB.S9S_MB_2U(SCH_1):GND
  160  GND            VSS68  @S9S_MB_2U_LIB.S9S_MB_2U(SCH_1):GND
  158  GND            VSS67  @S9S_MB_2U_LIB.S9S_MB_2U(SCH_1):GND
  155  GND            VSS66  @S9S_MB_2U_LIB.S9S_MB_2U(SCH_1):GND
  153  GND            VSS65  @S9S_MB_2U_LIB.S9S_MB_2U(SCH_1):GND
  151  GND            VSS64  @S9S_MB_2U_LIB.S9S_MB_2U(SCH_1):GND
  143  GND            VSS63  @S9S_MB_2U_LIB.S9S_MB_2U(SCH_1):GND
  141  GND            VSS62  @S9S_MB_2U_LIB.S9S_MB_2U(SCH_1):GND
  139  GND            VSS61  @S9S_MB_2U_LIB.S9S_MB_2U(SCH_1):GND
  136  GND            VSS60  @S9S_MB_2U_LIB.S9S_MB_2U(SCH_1):GND
  134  GND            VSS59  @S9S_MB_2U_LIB.S9S_MB_2U(SCH_1):GND
  132  GND            VSS58  @S9S_MB_2U_LIB.S9S_MB_2U(SCH_1):GND
  130  GND            VSS57  @S9S_MB_2U_LIB.S9S_MB_2U(SCH_1):GND
  128  GND            VSS56  @S9S_MB_2U_LIB.S9S_MB_2U(SCH_1):GND
  125  GND            VSS55  @S9S_MB_2U_LIB.S9S_MB_2U(SCH_1):GND
  123  GND            VSS54  @S9S_MB_2U_LIB.S9S_MB_2U(SCH_1):GND
  121  GND            VSS53  @S9S_MB_2U_LIB.S9S_MB_2U(SCH_1):GND
  119  GND            VSS52  @S9S_MB_2U_LIB.S9S_MB_2U(SCH_1):GND
  117  GND            VSS51  @S9S_MB_2U_LIB.S9S_MB_2U(SCH_1):GND
  114  GND            VSS50  @S9S_MB_2U_LIB.S9S_MB_2U(SCH_1):GND
  112  GND            VSS49  @S9S_MB_2U_LIB.S9S_MB_2U(SCH_1):GND
  110  GND            VSS48  @S9S_MB_2U_LIB.S9S_MB_2U(SCH_1):GND
  108  GND            VSS47  @S9S_MB_2U_LIB.S9S_MB_2U(SCH_1):GND
  106  GND            VSS46  @S9S_MB_2U_LIB.S9S_MB_2U(SCH_1):GND
  103  GND            VSS45  @S9S_MB_2U_LIB.S9S_MB_2U(SCH_1):GND
  101  GND            VSS44  @S9S_MB_2U_LIB.S9S_MB_2U(SCH_1):GND
   99  GND            VSS43  @S9S_MB_2U_LIB.S9S_MB_2U(SCH_1):GND
   97  GND            VSS42  @S9S_MB_2U_LIB.S9S_MB_2U(SCH_1):GND
   95  GND            VSS41  @S9S_MB_2U_LIB.S9S_MB_2U(SCH_1):GND
   92  GND            VSS40  @S9S_MB_2U_LIB.S9S_MB_2U(SCH_1):GND
   90  GND            VSS39  @S9S_MB_2U_LIB.S9S_MB_2U(SCH_1):GND
   88  GND            VSS38  @S9S_MB_2U_LIB.S9S_MB_2U(SCH_1):GND
   85  GND            VSS37  @S9S_MB_2U_LIB.S9S_MB_2U(SCH_1):GND
   83  GND            VSS36  @S9S_MB_2U_LIB.S9S_MB_2U(SCH_1):GND
   81  GND            VSS35  @S9S_MB_2U_LIB.S9S_MB_2U(SCH_1):GND
   79  GND            VSS34  @S9S_MB_2U_LIB.S9S_MB_2U(SCH_1):GND
   77  GND            VSS33  @S9S_MB_2U_LIB.S9S_MB_2U(SCH_1):GND
   75  GND            VSS32  @S9S_MB_2U_LIB.S9S_MB_2U(SCH_1):GND
   73  GND            VSS31  @S9S_MB_2U_LIB.S9S_MB_2U(SCH_1):GND
   71  GND            VSS30  @S9S_MB_2U_LIB.S9S_MB_2U(SCH_1):GND
   69  GND            VSS29  @S9S_MB_2U_LIB.S9S_MB_2U(SCH_1):GND
   67  GND            VSS28  @S9S_MB_2U_LIB.S9S_MB_2U(SCH_1):GND
   65  GND            VSS27  @S9S_MB_2U_LIB.S9S_MB_2U(SCH_1):GND
   63  GND            VSS26  @S9S_MB_2U_LIB.S9S_MB_2U(SCH_1):GND
   61  GND            VSS25  @S9S_MB_2U_LIB.S9S_MB_2U(SCH_1):GND
   59  GND            VSS24  @S9S_MB_2U_LIB.S9S_MB_2U(SCH_1):GND
   57  GND            VSS23  @S9S_MB_2U_LIB.S9S_MB_2U(SCH_1):GND
   54  GND            VSS22  @S9S_MB_2U_LIB.S9S_MB_2U(SCH_1):GND
   52  GND            VSS21  @S9S_MB_2U_LIB.S9S_MB_2U(SCH_1):GND
   50  GND            VSS20  @S9S_MB_2U_LIB.S9S_MB_2U(SCH_1):GND
   48  GND            VSS19  @S9S_MB_2U_LIB.S9S_MB_2U(SCH_1):GND
   46  GND            VSS18  @S9S_MB_2U_LIB.S9S_MB_2U(SCH_1):GND
   43  GND            VSS17  @S9S_MB_2U_LIB.S9S_MB_2U(SCH_1):GND
   41  GND            VSS16  @S9S_MB_2U_LIB.S9S_MB_2U(SCH_1):GND
   39  GND            VSS15  @S9S_MB_2U_LIB.S9S_MB_2U(SCH_1):GND
   37  GND            VSS14  @S9S_MB_2U_LIB.S9S_MB_2U(SCH_1):GND
   35  GND            VSS13  @S9S_MB_2U_LIB.S9S_MB_2U(SCH_1):GND
   32  GND            VSS12  @S9S_MB_2U_LIB.S9S_MB_2U(SCH_1):GND
   30  GND            VSS11  @S9S_MB_2U_LIB.S9S_MB_2U(SCH_1):GND
   28  GND            VSS10  @S9S_MB_2U_LIB.S9S_MB_2U(SCH_1):GND
   26  GND             VSS9  @S9S_MB_2U_LIB.S9S_MB_2U(SCH_1):GND
   24  GND             VSS8  @S9S_MB_2U_LIB.S9S_MB_2U(SCH_1):GND
   21  GND             VSS7  @S9S_MB_2U_LIB.S9S_MB_2U(SCH_1):GND
   19  GND             VSS6  @S9S_MB_2U_LIB.S9S_MB_2U(SCH_1):GND
   17  GND             VSS5  @S9S_MB_2U_LIB.S9S_MB_2U(SCH_1):GND
   15  GND             VSS4  @S9S_MB_2U_LIB.S9S_MB_2U(SCH_1):GND
   13  GND             VSS3  @S9S_MB_2U_LIB.S9S_MB_2U(SCH_1):GND
   10  GND             VSS2  @S9S_MB_2U_LIB.S9S_MB_2U(SCH_1):GND
    8  GND             VSS1  @S9S_MB_2U_LIB.S9S_MB_2U(SCH_1):GND
    6  GND             VSS0  @S9S_MB_2U_LIB.S9S_MB_2U(SCH_1):GND
   G3  GND               G3  @S9S_MB_2U_LIB.S9S_MB_2U(SCH_1):GND
   G2  GND               G2  @S9S_MB_2U_LIB.S9S_MB_2U(SCH_1):GND
   G1  GND               G1  @S9S_MB_2U_LIB.S9S_MB_2U(SCH_1):GND

SCONN288_ADR50001P003C01  I123  J6     [SCONN288_ADR50001P003C01-SCONNA]
   93  M_C_CPU0_SB_DQS_DP<9>  DQS9_B_P  @S9S_MB_2U_LIB.S9S_MB_2U(SCH_1):M_C_CPU0_SB_DQS_DP<9>
  283  M_C_CPU0_SB_DQS_DP<8>  DQS8_B_P  @S9S_MB_2U_LIB.S9S_MB_2U(SCH_1):M_C_CPU0_SB_DQS_DP<8>
  272  M_C_CPU0_SB_DQS_DP<7>  DQS7_B_P  @S9S_MB_2U_LIB.S9S_MB_2U(SCH_1):M_C_CPU0_SB_DQS_DP<7>
  261  M_C_CPU0_SB_DQS_DP<6>  DQS6_B_P  @S9S_MB_2U_LIB.S9S_MB_2U(SCH_1):M_C_CPU0_SB_DQS_DP<6>
  250  M_C_CPU0_SB_DQS_DP<5>  DQS5_B_P  @S9S_MB_2U_LIB.S9S_MB_2U(SCH_1):M_C_CPU0_SB_DQS_DP<5>
  239  M_C_CPU0_SB_DQS_DP<4>  DQS4_B_P  @S9S_MB_2U_LIB.S9S_MB_2U(SCH_1):M_C_CPU0_SB_DQS_DP<4>
  137  M_C_CPU0_SB_DQS_DP<3>  DQS3_B_P  @S9S_MB_2U_LIB.S9S_MB_2U(SCH_1):M_C_CPU0_SB_DQS_DP<3>
  126  M_C_CPU0_SB_DQS_DP<2>  DQS2_B_P  @S9S_MB_2U_LIB.S9S_MB_2U(SCH_1):M_C_CPU0_SB_DQS_DP<2>
  115  M_C_CPU0_SB_DQS_DP<1>  DQS1_B_P  @S9S_MB_2U_LIB.S9S_MB_2U(SCH_1):M_C_CPU0_SB_DQS_DP<1>
  104  M_C_CPU0_SB_DQS_DP<0>  DQS0_B_P  @S9S_MB_2U_LIB.S9S_MB_2U(SCH_1):M_C_CPU0_SB_DQS_DP<0>
   94  M_C_CPU0_SB_DQS_DN<9>  DQS9_B_N  @S9S_MB_2U_LIB.S9S_MB_2U(SCH_1):M_C_CPU0_SB_DQS_DN<9>
  282  M_C_CPU0_SB_DQS_DN<8>  DQS8_B_N  @S9S_MB_2U_LIB.S9S_MB_2U(SCH_1):M_C_CPU0_SB_DQS_DN<8>
  271  M_C_CPU0_SB_DQS_DN<7>  DQS7_B_N  @S9S_MB_2U_LIB.S9S_MB_2U(SCH_1):M_C_CPU0_SB_DQS_DN<7>
  260  M_C_CPU0_SB_DQS_DN<6>  DQS6_B_N  @S9S_MB_2U_LIB.S9S_MB_2U(SCH_1):M_C_CPU0_SB_DQS_DN<6>
  249  M_C_CPU0_SB_DQS_DN<5>  DQS5_B_N  @S9S_MB_2U_LIB.S9S_MB_2U(SCH_1):M_C_CPU0_SB_DQS_DN<5>
  238  M_C_CPU0_SB_DQS_DN<4>  DQS4_B_N  @S9S_MB_2U_LIB.S9S_MB_2U(SCH_1):M_C_CPU0_SB_DQS_DN<4>
  138  M_C_CPU0_SB_DQS_DN<3>  DQS3_B_N  @S9S_MB_2U_LIB.S9S_MB_2U(SCH_1):M_C_CPU0_SB_DQS_DN<3>
  127  M_C_CPU0_SB_DQS_DN<2>  DQS2_B_N  @S9S_MB_2U_LIB.S9S_MB_2U(SCH_1):M_C_CPU0_SB_DQS_DN<2>
  116  M_C_CPU0_SB_DQS_DN<1>  DQS1_B_N  @S9S_MB_2U_LIB.S9S_MB_2U(SCH_1):M_C_CPU0_SB_DQS_DN<1>
  105  M_C_CPU0_SB_DQS_DN<0>  DQS0_B_N  @S9S_MB_2U_LIB.S9S_MB_2U(SCH_1):M_C_CPU0_SB_DQS_DN<0>
  201  M_C_CPU0_SA_DQS_DP<9>  DQS9_A_P  @S9S_MB_2U_LIB.S9S_MB_2U(SCH_1):M_C_CPU0_SA_DQS_DP<9>
  190  M_C_CPU0_SA_DQS_DP<8>  DQS8_A_P  @S9S_MB_2U_LIB.S9S_MB_2U(SCH_1):M_C_CPU0_SA_DQS_DP<8>
  179  M_C_CPU0_SA_DQS_DP<7>  DQS7_A_P  @S9S_MB_2U_LIB.S9S_MB_2U(SCH_1):M_C_CPU0_SA_DQS_DP<7>
  168  M_C_CPU0_SA_DQS_DP<6>  DQS6_A_P  @S9S_MB_2U_LIB.S9S_MB_2U(SCH_1):M_C_CPU0_SA_DQS_DP<6>
  157  M_C_CPU0_SA_DQS_DP<5>  DQS5_A_P  @S9S_MB_2U_LIB.S9S_MB_2U(SCH_1):M_C_CPU0_SA_DQS_DP<5>
   55  M_C_CPU0_SA_DQS_DP<4>  DQS4_A_P  @S9S_MB_2U_LIB.S9S_MB_2U(SCH_1):M_C_CPU0_SA_DQS_DP<4>
   44  M_C_CPU0_SA_DQS_DP<3>  DQS3_A_P  @S9S_MB_2U_LIB.S9S_MB_2U(SCH_1):M_C_CPU0_SA_DQS_DP<3>
   33  M_C_CPU0_SA_DQS_DP<2>  DQS2_A_P  @S9S_MB_2U_LIB.S9S_MB_2U(SCH_1):M_C_CPU0_SA_DQS_DP<2>
   22  M_C_CPU0_SA_DQS_DP<1>  DQS1_A_P  @S9S_MB_2U_LIB.S9S_MB_2U(SCH_1):M_C_CPU0_SA_DQS_DP<1>
   11  M_C_CPU0_SA_DQS_DP<0>  DQS0_A_P  @S9S_MB_2U_LIB.S9S_MB_2U(SCH_1):M_C_CPU0_SA_DQS_DP<0>
  200  M_C_CPU0_SA_DQS_DN<9>  DQS9_A_N  @S9S_MB_2U_LIB.S9S_MB_2U(SCH_1):M_C_CPU0_SA_DQS_DN<9>
  189  M_C_CPU0_SA_DQS_DN<8>  DQS8_A_N  @S9S_MB_2U_LIB.S9S_MB_2U(SCH_1):M_C_CPU0_SA_DQS_DN<8>
  178  M_C_CPU0_SA_DQS_DN<7>  DQS7_A_N  @S9S_MB_2U_LIB.S9S_MB_2U(SCH_1):M_C_CPU0_SA_DQS_DN<7>
  167  M_C_CPU0_SA_DQS_DN<6>  DQS6_A_N  @S9S_MB_2U_LIB.S9S_MB_2U(SCH_1):M_C_CPU0_SA_DQS_DN<6>
  156  M_C_CPU0_SA_DQS_DN<5>  DQS5_A_N  @S9S_MB_2U_LIB.S9S_MB_2U(SCH_1):M_C_CPU0_SA_DQS_DN<5>
   56  M_C_CPU0_SA_DQS_DN<4>  DQS4_A_N  @S9S_MB_2U_LIB.S9S_MB_2U(SCH_1):M_C_CPU0_SA_DQS_DN<4>
   45  M_C_CPU0_SA_DQS_DN<3>  DQS3_A_N  @S9S_MB_2U_LIB.S9S_MB_2U(SCH_1):M_C_CPU0_SA_DQS_DN<3>
   34  M_C_CPU0_SA_DQS_DN<2>  DQS2_A_N  @S9S_MB_2U_LIB.S9S_MB_2U(SCH_1):M_C_CPU0_SA_DQS_DN<2>
   23  M_C_CPU0_SA_DQS_DN<1>  DQS1_A_N  @S9S_MB_2U_LIB.S9S_MB_2U(SCH_1):M_C_CPU0_SA_DQS_DN<1>
   12  M_C_CPU0_SA_DQS_DN<0>  DQS0_A_N  @S9S_MB_2U_LIB.S9S_MB_2U(SCH_1):M_C_CPU0_SA_DQS_DN<0>

SCONN288_ADR50001P003C01  I46  J6     [SCONN288_ADR50001P003C01-SCONNA]
  232  NC              RFU6  NC
  231  NC              RFU5  NC
  220  NC              RFU4  NC
  150  NC              RFU3  NC
  149  NC              RFU2  NC
  144  NC              RFU1  NC
    2  NC              RFU0  NC
  207  RST_M_CD_CPU0_FPGA_N  RESET_N  @S9S_MB_2U_LIB.S9S_MB_2U(SCH_1):RST_M_CD_CPU0_FPGA_N
  147  PWRGD_CHC_CPU0_DIMM2  PWR_GOOD||FAIL_N  @S9S_MB_2U_LIB.S9S_MB_2U(SCH_1):PWRGD_CHC_CPU0_DIMM2
  148  PD_CHC_CPU0_DIMM2_SAA    HAS  @S9S_MB_2U_LIB.S9S_MB_2U(SCH_1):PD_CHC_CPU0_DIMM2_SAA
    3  P3V3_AUX       VIN_MGMT  @S9S_MB_2U_LIB.S9S_MB_2U(SCH_1):P3V3_AUX
   87  M_C_CPU0_SB_RSP<1>  LBS||RSP_N_B  @S9S_MB_2U_LIB.S9S_MB_2U(SCH_1):M_C_CPU0_SB_RSP<1>
  227  M_C_CPU0_SB_PAR  PAR_B  @S9S_MB_2U_LIB.S9S_MB_2U(SCH_1):M_C_CPU0_SB_PAR
  113  M_C_CPU0_SB_DQ<9>  DQ_B9  @S9S_MB_2U_LIB.S9S_MB_2U(SCH_1):M_C_CPU0_SB_DQ<9>
  111  M_C_CPU0_SB_DQ<8>  DQ_B8  @S9S_MB_2U_LIB.S9S_MB_2U(SCH_1):M_C_CPU0_SB_DQ<8>
  254  M_C_CPU0_SB_DQ<7>  DQ_B7  @S9S_MB_2U_LIB.S9S_MB_2U(SCH_1):M_C_CPU0_SB_DQ<7>
  252  M_C_CPU0_SB_DQ<6>  DQ_B6  @S9S_MB_2U_LIB.S9S_MB_2U(SCH_1):M_C_CPU0_SB_DQ<6>
  109  M_C_CPU0_SB_DQ<5>  DQ_B5  @S9S_MB_2U_LIB.S9S_MB_2U(SCH_1):M_C_CPU0_SB_DQ<5>
  107  M_C_CPU0_SB_DQ<4>  DQ_B4  @S9S_MB_2U_LIB.S9S_MB_2U(SCH_1):M_C_CPU0_SB_DQ<4>
  247  M_C_CPU0_SB_DQ<3>  DQ_B3  @S9S_MB_2U_LIB.S9S_MB_2U(SCH_1):M_C_CPU0_SB_DQ<3>
  287  M_C_CPU0_SB_DQ<31>  DQ_B31  @S9S_MB_2U_LIB.S9S_MB_2U(SCH_1):M_C_CPU0_SB_DQ<31>
  285  M_C_CPU0_SB_DQ<30>  DQ_B30  @S9S_MB_2U_LIB.S9S_MB_2U(SCH_1):M_C_CPU0_SB_DQ<30>
  245  M_C_CPU0_SB_DQ<2>  DQ_B2  @S9S_MB_2U_LIB.S9S_MB_2U(SCH_1):M_C_CPU0_SB_DQ<2>
  142  M_C_CPU0_SB_DQ<29>  DQ_B29  @S9S_MB_2U_LIB.S9S_MB_2U(SCH_1):M_C_CPU0_SB_DQ<29>
  140  M_C_CPU0_SB_DQ<28>  DQ_B28  @S9S_MB_2U_LIB.S9S_MB_2U(SCH_1):M_C_CPU0_SB_DQ<28>
  280  M_C_CPU0_SB_DQ<27>  DQ_B27  @S9S_MB_2U_LIB.S9S_MB_2U(SCH_1):M_C_CPU0_SB_DQ<27>
  278  M_C_CPU0_SB_DQ<26>  DQ_B26  @S9S_MB_2U_LIB.S9S_MB_2U(SCH_1):M_C_CPU0_SB_DQ<26>
  135  M_C_CPU0_SB_DQ<25>  DQ_B25  @S9S_MB_2U_LIB.S9S_MB_2U(SCH_1):M_C_CPU0_SB_DQ<25>
  133  M_C_CPU0_SB_DQ<24>  DQ_B24  @S9S_MB_2U_LIB.S9S_MB_2U(SCH_1):M_C_CPU0_SB_DQ<24>
  276  M_C_CPU0_SB_DQ<23>  DQ_B23  @S9S_MB_2U_LIB.S9S_MB_2U(SCH_1):M_C_CPU0_SB_DQ<23>
  274  M_C_CPU0_SB_DQ<22>  DQ_B22  @S9S_MB_2U_LIB.S9S_MB_2U(SCH_1):M_C_CPU0_SB_DQ<22>
  131  M_C_CPU0_SB_DQ<21>  DQ_B21  @S9S_MB_2U_LIB.S9S_MB_2U(SCH_1):M_C_CPU0_SB_DQ<21>
  129  M_C_CPU0_SB_DQ<20>  DQ_B20  @S9S_MB_2U_LIB.S9S_MB_2U(SCH_1):M_C_CPU0_SB_DQ<20>
  102  M_C_CPU0_SB_DQ<1>  DQ_B1  @S9S_MB_2U_LIB.S9S_MB_2U(SCH_1):M_C_CPU0_SB_DQ<1>
  269  M_C_CPU0_SB_DQ<19>  DQ_B19  @S9S_MB_2U_LIB.S9S_MB_2U(SCH_1):M_C_CPU0_SB_DQ<19>
  267  M_C_CPU0_SB_DQ<18>  DQ_B18  @S9S_MB_2U_LIB.S9S_MB_2U(SCH_1):M_C_CPU0_SB_DQ<18>
  124  M_C_CPU0_SB_DQ<17>  DQ_B17  @S9S_MB_2U_LIB.S9S_MB_2U(SCH_1):M_C_CPU0_SB_DQ<17>
  122  M_C_CPU0_SB_DQ<16>  DQ_B16  @S9S_MB_2U_LIB.S9S_MB_2U(SCH_1):M_C_CPU0_SB_DQ<16>
  265  M_C_CPU0_SB_DQ<15>  DQ_B15  @S9S_MB_2U_LIB.S9S_MB_2U(SCH_1):M_C_CPU0_SB_DQ<15>
  263  M_C_CPU0_SB_DQ<14>  DQ_B14  @S9S_MB_2U_LIB.S9S_MB_2U(SCH_1):M_C_CPU0_SB_DQ<14>
  120  M_C_CPU0_SB_DQ<13>  DQ_B13  @S9S_MB_2U_LIB.S9S_MB_2U(SCH_1):M_C_CPU0_SB_DQ<13>
  118  M_C_CPU0_SB_DQ<12>  DQ_B12  @S9S_MB_2U_LIB.S9S_MB_2U(SCH_1):M_C_CPU0_SB_DQ<12>
  258  M_C_CPU0_SB_DQ<11>  DQ_B11  @S9S_MB_2U_LIB.S9S_MB_2U(SCH_1):M_C_CPU0_SB_DQ<11>
  256  M_C_CPU0_SB_DQ<10>  DQ_B10  @S9S_MB_2U_LIB.S9S_MB_2U(SCH_1):M_C_CPU0_SB_DQ<10>
  100  M_C_CPU0_SB_DQ<0>  DQ_B0  @S9S_MB_2U_LIB.S9S_MB_2U(SCH_1):M_C_CPU0_SB_DQ<0>
  229  M_C_CPU0_SB_CS_N<3>  CS1_N_B  @S9S_MB_2U_LIB.S9S_MB_2U(SCH_1):M_C_CPU0_SB_CS_N<3>
   84  M_C_CPU0_SB_CS_N<2>  CS0_N_B  @S9S_MB_2U_LIB.S9S_MB_2U(SCH_1):M_C_CPU0_SB_CS_N<2>
  236  M_C_CPU0_SB_CB<7>  CB_B7  @S9S_MB_2U_LIB.S9S_MB_2U(SCH_1):M_C_CPU0_SB_CB<7>
  234  M_C_CPU0_SB_CB<6>  CB_B6  @S9S_MB_2U_LIB.S9S_MB_2U(SCH_1):M_C_CPU0_SB_CB<6>
   91  M_C_CPU0_SB_CB<5>  CB_B5  @S9S_MB_2U_LIB.S9S_MB_2U(SCH_1):M_C_CPU0_SB_CB<5>
   89  M_C_CPU0_SB_CB<4>  CB_B4  @S9S_MB_2U_LIB.S9S_MB_2U(SCH_1):M_C_CPU0_SB_CB<4>
  243  M_C_CPU0_SB_CB<3>  CB_B3  @S9S_MB_2U_LIB.S9S_MB_2U(SCH_1):M_C_CPU0_SB_CB<3>
  241  M_C_CPU0_SB_CB<2>  CB_B2  @S9S_MB_2U_LIB.S9S_MB_2U(SCH_1):M_C_CPU0_SB_CB<2>
   98  M_C_CPU0_SB_CB<1>  CB_B1  @S9S_MB_2U_LIB.S9S_MB_2U(SCH_1):M_C_CPU0_SB_CB<1>
   96  M_C_CPU0_SB_CB<0>  CB_B0  @S9S_MB_2U_LIB.S9S_MB_2U(SCH_1):M_C_CPU0_SB_CB<0>
   82  M_C_CPU0_SB_CA<6>  CA6_B  @S9S_MB_2U_LIB.S9S_MB_2U(SCH_1):M_C_CPU0_SB_CA<6>
  225  M_C_CPU0_SB_CA<5>  CA5_B  @S9S_MB_2U_LIB.S9S_MB_2U(SCH_1):M_C_CPU0_SB_CA<5>
   80  M_C_CPU0_SB_CA<4>  CA4_B  @S9S_MB_2U_LIB.S9S_MB_2U(SCH_1):M_C_CPU0_SB_CA<4>
  223  M_C_CPU0_SB_CA<3>  CA3_B  @S9S_MB_2U_LIB.S9S_MB_2U(SCH_1):M_C_CPU0_SB_CA<3>
   78  M_C_CPU0_SB_CA<2>  CA2_B  @S9S_MB_2U_LIB.S9S_MB_2U(SCH_1):M_C_CPU0_SB_CA<2>
  221  M_C_CPU0_SB_CA<1>  CA1_B  @S9S_MB_2U_LIB.S9S_MB_2U(SCH_1):M_C_CPU0_SB_CA<1>
   76  M_C_CPU0_SB_CA<0>  CA0_B  @S9S_MB_2U_LIB.S9S_MB_2U(SCH_1):M_C_CPU0_SB_CA<0>
   86  M_C_CPU0_SA_RSP<1>  LBD||RSP_N_A  @S9S_MB_2U_LIB.S9S_MB_2U(SCH_1):M_C_CPU0_SA_RSP<1>
   74  M_C_CPU0_SA_PAR  PAR_A  @S9S_MB_2U_LIB.S9S_MB_2U(SCH_1):M_C_CPU0_SA_PAR
   20  M_C_CPU0_SA_DQ<9>  DQ_A9  @S9S_MB_2U_LIB.S9S_MB_2U(SCH_1):M_C_CPU0_SA_DQ<9>
   18  M_C_CPU0_SA_DQ<8>  DQ_A8  @S9S_MB_2U_LIB.S9S_MB_2U(SCH_1):M_C_CPU0_SA_DQ<8>
  161  M_C_CPU0_SA_DQ<7>  DQ_A7  @S9S_MB_2U_LIB.S9S_MB_2U(SCH_1):M_C_CPU0_SA_DQ<7>
  159  M_C_CPU0_SA_DQ<6>  DQ_A6  @S9S_MB_2U_LIB.S9S_MB_2U(SCH_1):M_C_CPU0_SA_DQ<6>
   16  M_C_CPU0_SA_DQ<5>  DQ_A5  @S9S_MB_2U_LIB.S9S_MB_2U(SCH_1):M_C_CPU0_SA_DQ<5>
   14  M_C_CPU0_SA_DQ<4>  DQ_A4  @S9S_MB_2U_LIB.S9S_MB_2U(SCH_1):M_C_CPU0_SA_DQ<4>
  154  M_C_CPU0_SA_DQ<3>  DQ_A3  @S9S_MB_2U_LIB.S9S_MB_2U(SCH_1):M_C_CPU0_SA_DQ<3>
  194  M_C_CPU0_SA_DQ<31>  DQ_A31  @S9S_MB_2U_LIB.S9S_MB_2U(SCH_1):M_C_CPU0_SA_DQ<31>
  192  M_C_CPU0_SA_DQ<30>  DQ_A30  @S9S_MB_2U_LIB.S9S_MB_2U(SCH_1):M_C_CPU0_SA_DQ<30>
  152  M_C_CPU0_SA_DQ<2>  DQ_A2  @S9S_MB_2U_LIB.S9S_MB_2U(SCH_1):M_C_CPU0_SA_DQ<2>
   49  M_C_CPU0_SA_DQ<29>  DQ_A29  @S9S_MB_2U_LIB.S9S_MB_2U(SCH_1):M_C_CPU0_SA_DQ<29>
   47  M_C_CPU0_SA_DQ<28>  DQ_A28  @S9S_MB_2U_LIB.S9S_MB_2U(SCH_1):M_C_CPU0_SA_DQ<28>
  187  M_C_CPU0_SA_DQ<27>  DQ_A27  @S9S_MB_2U_LIB.S9S_MB_2U(SCH_1):M_C_CPU0_SA_DQ<27>
  185  M_C_CPU0_SA_DQ<26>  DQ_A26  @S9S_MB_2U_LIB.S9S_MB_2U(SCH_1):M_C_CPU0_SA_DQ<26>
   42  M_C_CPU0_SA_DQ<25>  DQ_A25  @S9S_MB_2U_LIB.S9S_MB_2U(SCH_1):M_C_CPU0_SA_DQ<25>
   40  M_C_CPU0_SA_DQ<24>  DQ_A24  @S9S_MB_2U_LIB.S9S_MB_2U(SCH_1):M_C_CPU0_SA_DQ<24>
  183  M_C_CPU0_SA_DQ<23>  DQ_A23  @S9S_MB_2U_LIB.S9S_MB_2U(SCH_1):M_C_CPU0_SA_DQ<23>
  181  M_C_CPU0_SA_DQ<22>  DQ_A22  @S9S_MB_2U_LIB.S9S_MB_2U(SCH_1):M_C_CPU0_SA_DQ<22>
   38  M_C_CPU0_SA_DQ<21>  DQ_A21  @S9S_MB_2U_LIB.S9S_MB_2U(SCH_1):M_C_CPU0_SA_DQ<21>
   36  M_C_CPU0_SA_DQ<20>  DQ_A20  @S9S_MB_2U_LIB.S9S_MB_2U(SCH_1):M_C_CPU0_SA_DQ<20>
    9  M_C_CPU0_SA_DQ<1>  DQ_A1  @S9S_MB_2U_LIB.S9S_MB_2U(SCH_1):M_C_CPU0_SA_DQ<1>
  176  M_C_CPU0_SA_DQ<19>  DQ_A19  @S9S_MB_2U_LIB.S9S_MB_2U(SCH_1):M_C_CPU0_SA_DQ<19>
  174  M_C_CPU0_SA_DQ<18>  DQ_A18  @S9S_MB_2U_LIB.S9S_MB_2U(SCH_1):M_C_CPU0_SA_DQ<18>
   31  M_C_CPU0_SA_DQ<17>  DQ_A17  @S9S_MB_2U_LIB.S9S_MB_2U(SCH_1):M_C_CPU0_SA_DQ<17>
   29  M_C_CPU0_SA_DQ<16>  DQ_A16  @S9S_MB_2U_LIB.S9S_MB_2U(SCH_1):M_C_CPU0_SA_DQ<16>
  172  M_C_CPU0_SA_DQ<15>  DQ_A15  @S9S_MB_2U_LIB.S9S_MB_2U(SCH_1):M_C_CPU0_SA_DQ<15>
  170  M_C_CPU0_SA_DQ<14>  DQ_A14  @S9S_MB_2U_LIB.S9S_MB_2U(SCH_1):M_C_CPU0_SA_DQ<14>
   27  M_C_CPU0_SA_DQ<13>  DQ_A13  @S9S_MB_2U_LIB.S9S_MB_2U(SCH_1):M_C_CPU0_SA_DQ<13>
   25  M_C_CPU0_SA_DQ<12>  DQ_A12  @S9S_MB_2U_LIB.S9S_MB_2U(SCH_1):M_C_CPU0_SA_DQ<12>
  165  M_C_CPU0_SA_DQ<11>  DQ_A11  @S9S_MB_2U_LIB.S9S_MB_2U(SCH_1):M_C_CPU0_SA_DQ<11>
  163  M_C_CPU0_SA_DQ<10>  DQ_A10  @S9S_MB_2U_LIB.S9S_MB_2U(SCH_1):M_C_CPU0_SA_DQ<10>
    7  M_C_CPU0_SA_DQ<0>  DQ_A0  @S9S_MB_2U_LIB.S9S_MB_2U(SCH_1):M_C_CPU0_SA_DQ<0>
  209  M_C_CPU0_SA_CS_N<3>  CS1_N_A  @S9S_MB_2U_LIB.S9S_MB_2U(SCH_1):M_C_CPU0_SA_CS_N<3>
   64  M_C_CPU0_SA_CS_N<2>  CS0_N_A  @S9S_MB_2U_LIB.S9S_MB_2U(SCH_1):M_C_CPU0_SA_CS_N<2>
  205  M_C_CPU0_SA_CB<7>  CB_A7  @S9S_MB_2U_LIB.S9S_MB_2U(SCH_1):M_C_CPU0_SA_CB<7>
  203  M_C_CPU0_SA_CB<6>  CB_A6  @S9S_MB_2U_LIB.S9S_MB_2U(SCH_1):M_C_CPU0_SA_CB<6>
   60  M_C_CPU0_SA_CB<5>  CB_A5  @S9S_MB_2U_LIB.S9S_MB_2U(SCH_1):M_C_CPU0_SA_CB<5>
   58  M_C_CPU0_SA_CB<4>  CB_A4  @S9S_MB_2U_LIB.S9S_MB_2U(SCH_1):M_C_CPU0_SA_CB<4>
  198  M_C_CPU0_SA_CB<3>  CB_A3  @S9S_MB_2U_LIB.S9S_MB_2U(SCH_1):M_C_CPU0_SA_CB<3>
  196  M_C_CPU0_SA_CB<2>  CB_A2  @S9S_MB_2U_LIB.S9S_MB_2U(SCH_1):M_C_CPU0_SA_CB<2>
   53  M_C_CPU0_SA_CB<1>  CB_A1  @S9S_MB_2U_LIB.S9S_MB_2U(SCH_1):M_C_CPU0_SA_CB<1>
   51  M_C_CPU0_SA_CB<0>  CB_A0  @S9S_MB_2U_LIB.S9S_MB_2U(SCH_1):M_C_CPU0_SA_CB<0>
   72  M_C_CPU0_SA_CA<6>  CA6_A  @S9S_MB_2U_LIB.S9S_MB_2U(SCH_1):M_C_CPU0_SA_CA<6>
  215  M_C_CPU0_SA_CA<5>  CA5_A  @S9S_MB_2U_LIB.S9S_MB_2U(SCH_1):M_C_CPU0_SA_CA<5>
   70  M_C_CPU0_SA_CA<4>  CA4_A  @S9S_MB_2U_LIB.S9S_MB_2U(SCH_1):M_C_CPU0_SA_CA<4>
  213  M_C_CPU0_SA_CA<3>  CA3_A  @S9S_MB_2U_LIB.S9S_MB_2U(SCH_1):M_C_CPU0_SA_CA<3>
   68  M_C_CPU0_SA_CA<2>  CA2_A  @S9S_MB_2U_LIB.S9S_MB_2U(SCH_1):M_C_CPU0_SA_CA<2>
  211  M_C_CPU0_SA_CA<1>  CA1_A  @S9S_MB_2U_LIB.S9S_MB_2U(SCH_1):M_C_CPU0_SA_CA<1>
   66  M_C_CPU0_SA_CA<0>  CA0_A  @S9S_MB_2U_LIB.S9S_MB_2U(SCH_1):M_C_CPU0_SA_CA<0>
  217  M_C_CPU0_CLK_DP<1>   CK_P  @S9S_MB_2U_LIB.S9S_MB_2U(SCH_1):M_C_CPU0_CLK_DP<1>
  218  M_C_CPU0_CLK_DN<1>   CK_N  @S9S_MB_2U_LIB.S9S_MB_2U(SCH_1):M_C_CPU0_CLK_DN<1>
   62  M_C_CPU0_ALERT_N  ALERT_N  @S9S_MB_2U_LIB.S9S_MB_2U(SCH_1):M_C_CPU0_ALERT_N
    5  I3C_SPD_DDRABCD_CPU0_LVC1_SDA   HSDA  @S9S_MB_2U_LIB.S9S_MB_2U(SCH_1):I3C_SPD_DDRABCD_CPU0_LVC1_SDA
    4  I3C_SPD_DDRABCD_CPU0_LVC1_SCL   HSCL  @S9S_MB_2U_LIB.S9S_MB_2U(SCH_1):I3C_SPD_DDRABCD_CPU0_LVC1_SCL

SCONN288_ADR50001P013C01  I168  J7     [SCONN288_ADR50001P013C01-SCONNA]
  146  P12V_S3_AUX_CPU0_NVDIMM  VIN_BULK2  @S9S_MB_2U_LIB.S9S_MB_2U(SCH_1):P12V_S3_AUX_CPU0_NVDIMM
  145  P12V_S3_AUX_CPU0_NVDIMM  VIN_BULK1  @S9S_MB_2U_LIB.S9S_MB_2U(SCH_1):P12V_S3_AUX_CPU0_NVDIMM
    1  P12V_S3_AUX_CPU0_NVDIMM  VIN_BULK0  @S9S_MB_2U_LIB.S9S_MB_2U(SCH_1):P12V_S3_AUX_CPU0_NVDIMM
  288  GND            VSS126  @S9S_MB_2U_LIB.S9S_MB_2U(SCH_1):GND
  286  GND            VSS125  @S9S_MB_2U_LIB.S9S_MB_2U(SCH_1):GND
  284  GND            VSS124  @S9S_MB_2U_LIB.S9S_MB_2U(SCH_1):GND
  281  GND            VSS123  @S9S_MB_2U_LIB.S9S_MB_2U(SCH_1):GND
  279  GND            VSS122  @S9S_MB_2U_LIB.S9S_MB_2U(SCH_1):GND
  277  GND            VSS121  @S9S_MB_2U_LIB.S9S_MB_2U(SCH_1):GND
  275  GND            VSS120  @S9S_MB_2U_LIB.S9S_MB_2U(SCH_1):GND
  273  GND            VSS119  @S9S_MB_2U_LIB.S9S_MB_2U(SCH_1):GND
  270  GND            VSS118  @S9S_MB_2U_LIB.S9S_MB_2U(SCH_1):GND
  268  GND            VSS117  @S9S_MB_2U_LIB.S9S_MB_2U(SCH_1):GND
  266  GND            VSS116  @S9S_MB_2U_LIB.S9S_MB_2U(SCH_1):GND
  264  GND            VSS115  @S9S_MB_2U_LIB.S9S_MB_2U(SCH_1):GND
  262  GND            VSS114  @S9S_MB_2U_LIB.S9S_MB_2U(SCH_1):GND
  259  GND            VSS113  @S9S_MB_2U_LIB.S9S_MB_2U(SCH_1):GND
  257  GND            VSS112  @S9S_MB_2U_LIB.S9S_MB_2U(SCH_1):GND
  255  GND            VSS111  @S9S_MB_2U_LIB.S9S_MB_2U(SCH_1):GND
  253  GND            VSS110  @S9S_MB_2U_LIB.S9S_MB_2U(SCH_1):GND
  251  GND            VSS109  @S9S_MB_2U_LIB.S9S_MB_2U(SCH_1):GND
  248  GND            VSS108  @S9S_MB_2U_LIB.S9S_MB_2U(SCH_1):GND
  246  GND            VSS107  @S9S_MB_2U_LIB.S9S_MB_2U(SCH_1):GND
  244  GND            VSS106  @S9S_MB_2U_LIB.S9S_MB_2U(SCH_1):GND
  242  GND            VSS105  @S9S_MB_2U_LIB.S9S_MB_2U(SCH_1):GND
  240  GND            VSS104  @S9S_MB_2U_LIB.S9S_MB_2U(SCH_1):GND
  237  GND            VSS103  @S9S_MB_2U_LIB.S9S_MB_2U(SCH_1):GND
  235  GND            VSS102  @S9S_MB_2U_LIB.S9S_MB_2U(SCH_1):GND
  233  GND            VSS101  @S9S_MB_2U_LIB.S9S_MB_2U(SCH_1):GND
  230  GND            VSS100  @S9S_MB_2U_LIB.S9S_MB_2U(SCH_1):GND
  228  GND            VSS99  @S9S_MB_2U_LIB.S9S_MB_2U(SCH_1):GND
  226  GND            VSS98  @S9S_MB_2U_LIB.S9S_MB_2U(SCH_1):GND
  224  GND            VSS97  @S9S_MB_2U_LIB.S9S_MB_2U(SCH_1):GND
  222  GND            VSS96  @S9S_MB_2U_LIB.S9S_MB_2U(SCH_1):GND
  219  GND            VSS95  @S9S_MB_2U_LIB.S9S_MB_2U(SCH_1):GND
  216  GND            VSS94  @S9S_MB_2U_LIB.S9S_MB_2U(SCH_1):GND
  214  GND            VSS93  @S9S_MB_2U_LIB.S9S_MB_2U(SCH_1):GND
  212  GND            VSS92  @S9S_MB_2U_LIB.S9S_MB_2U(SCH_1):GND
  210  GND            VSS91  @S9S_MB_2U_LIB.S9S_MB_2U(SCH_1):GND
  208  GND            VSS90  @S9S_MB_2U_LIB.S9S_MB_2U(SCH_1):GND
  206  GND            VSS89  @S9S_MB_2U_LIB.S9S_MB_2U(SCH_1):GND
  204  GND            VSS88  @S9S_MB_2U_LIB.S9S_MB_2U(SCH_1):GND
  202  GND            VSS87  @S9S_MB_2U_LIB.S9S_MB_2U(SCH_1):GND
  199  GND            VSS86  @S9S_MB_2U_LIB.S9S_MB_2U(SCH_1):GND
  197  GND            VSS85  @S9S_MB_2U_LIB.S9S_MB_2U(SCH_1):GND
  195  GND            VSS84  @S9S_MB_2U_LIB.S9S_MB_2U(SCH_1):GND
  193  GND            VSS83  @S9S_MB_2U_LIB.S9S_MB_2U(SCH_1):GND
  191  GND            VSS82  @S9S_MB_2U_LIB.S9S_MB_2U(SCH_1):GND
  188  GND            VSS81  @S9S_MB_2U_LIB.S9S_MB_2U(SCH_1):GND
  186  GND            VSS80  @S9S_MB_2U_LIB.S9S_MB_2U(SCH_1):GND
  184  GND            VSS79  @S9S_MB_2U_LIB.S9S_MB_2U(SCH_1):GND
  182  GND            VSS78  @S9S_MB_2U_LIB.S9S_MB_2U(SCH_1):GND
  180  GND            VSS77  @S9S_MB_2U_LIB.S9S_MB_2U(SCH_1):GND
  177  GND            VSS76  @S9S_MB_2U_LIB.S9S_MB_2U(SCH_1):GND
  175  GND            VSS75  @S9S_MB_2U_LIB.S9S_MB_2U(SCH_1):GND
  173  GND            VSS74  @S9S_MB_2U_LIB.S9S_MB_2U(SCH_1):GND
  171  GND            VSS73  @S9S_MB_2U_LIB.S9S_MB_2U(SCH_1):GND
  169  GND            VSS72  @S9S_MB_2U_LIB.S9S_MB_2U(SCH_1):GND
  166  GND            VSS71  @S9S_MB_2U_LIB.S9S_MB_2U(SCH_1):GND
  164  GND            VSS70  @S9S_MB_2U_LIB.S9S_MB_2U(SCH_1):GND
  162  GND            VSS69  @S9S_MB_2U_LIB.S9S_MB_2U(SCH_1):GND
  160  GND            VSS68  @S9S_MB_2U_LIB.S9S_MB_2U(SCH_1):GND
  158  GND            VSS67  @S9S_MB_2U_LIB.S9S_MB_2U(SCH_1):GND
  155  GND            VSS66  @S9S_MB_2U_LIB.S9S_MB_2U(SCH_1):GND
  153  GND            VSS65  @S9S_MB_2U_LIB.S9S_MB_2U(SCH_1):GND
  151  GND            VSS64  @S9S_MB_2U_LIB.S9S_MB_2U(SCH_1):GND
  143  GND            VSS63  @S9S_MB_2U_LIB.S9S_MB_2U(SCH_1):GND
  141  GND            VSS62  @S9S_MB_2U_LIB.S9S_MB_2U(SCH_1):GND
  139  GND            VSS61  @S9S_MB_2U_LIB.S9S_MB_2U(SCH_1):GND
  136  GND            VSS60  @S9S_MB_2U_LIB.S9S_MB_2U(SCH_1):GND
  134  GND            VSS59  @S9S_MB_2U_LIB.S9S_MB_2U(SCH_1):GND
  132  GND            VSS58  @S9S_MB_2U_LIB.S9S_MB_2U(SCH_1):GND
  130  GND            VSS57  @S9S_MB_2U_LIB.S9S_MB_2U(SCH_1):GND
  128  GND            VSS56  @S9S_MB_2U_LIB.S9S_MB_2U(SCH_1):GND
  125  GND            VSS55  @S9S_MB_2U_LIB.S9S_MB_2U(SCH_1):GND
  123  GND            VSS54  @S9S_MB_2U_LIB.S9S_MB_2U(SCH_1):GND
  121  GND            VSS53  @S9S_MB_2U_LIB.S9S_MB_2U(SCH_1):GND
  119  GND            VSS52  @S9S_MB_2U_LIB.S9S_MB_2U(SCH_1):GND
  117  GND            VSS51  @S9S_MB_2U_LIB.S9S_MB_2U(SCH_1):GND
  114  GND            VSS50  @S9S_MB_2U_LIB.S9S_MB_2U(SCH_1):GND
  112  GND            VSS49  @S9S_MB_2U_LIB.S9S_MB_2U(SCH_1):GND
  110  GND            VSS48  @S9S_MB_2U_LIB.S9S_MB_2U(SCH_1):GND
  108  GND            VSS47  @S9S_MB_2U_LIB.S9S_MB_2U(SCH_1):GND
  106  GND            VSS46  @S9S_MB_2U_LIB.S9S_MB_2U(SCH_1):GND
  103  GND            VSS45  @S9S_MB_2U_LIB.S9S_MB_2U(SCH_1):GND
  101  GND            VSS44  @S9S_MB_2U_LIB.S9S_MB_2U(SCH_1):GND
   99  GND            VSS43  @S9S_MB_2U_LIB.S9S_MB_2U(SCH_1):GND
   97  GND            VSS42  @S9S_MB_2U_LIB.S9S_MB_2U(SCH_1):GND
   95  GND            VSS41  @S9S_MB_2U_LIB.S9S_MB_2U(SCH_1):GND
   92  GND            VSS40  @S9S_MB_2U_LIB.S9S_MB_2U(SCH_1):GND
   90  GND            VSS39  @S9S_MB_2U_LIB.S9S_MB_2U(SCH_1):GND
   88  GND            VSS38  @S9S_MB_2U_LIB.S9S_MB_2U(SCH_1):GND
   85  GND            VSS37  @S9S_MB_2U_LIB.S9S_MB_2U(SCH_1):GND
   83  GND            VSS36  @S9S_MB_2U_LIB.S9S_MB_2U(SCH_1):GND
   81  GND            VSS35  @S9S_MB_2U_LIB.S9S_MB_2U(SCH_1):GND
   79  GND            VSS34  @S9S_MB_2U_LIB.S9S_MB_2U(SCH_1):GND
   77  GND            VSS33  @S9S_MB_2U_LIB.S9S_MB_2U(SCH_1):GND
   75  GND            VSS32  @S9S_MB_2U_LIB.S9S_MB_2U(SCH_1):GND
   73  GND            VSS31  @S9S_MB_2U_LIB.S9S_MB_2U(SCH_1):GND
   71  GND            VSS30  @S9S_MB_2U_LIB.S9S_MB_2U(SCH_1):GND
   69  GND            VSS29  @S9S_MB_2U_LIB.S9S_MB_2U(SCH_1):GND
   67  GND            VSS28  @S9S_MB_2U_LIB.S9S_MB_2U(SCH_1):GND
   65  GND            VSS27  @S9S_MB_2U_LIB.S9S_MB_2U(SCH_1):GND
   63  GND            VSS26  @S9S_MB_2U_LIB.S9S_MB_2U(SCH_1):GND
   61  GND            VSS25  @S9S_MB_2U_LIB.S9S_MB_2U(SCH_1):GND
   59  GND            VSS24  @S9S_MB_2U_LIB.S9S_MB_2U(SCH_1):GND
   57  GND            VSS23  @S9S_MB_2U_LIB.S9S_MB_2U(SCH_1):GND
   54  GND            VSS22  @S9S_MB_2U_LIB.S9S_MB_2U(SCH_1):GND
   52  GND            VSS21  @S9S_MB_2U_LIB.S9S_MB_2U(SCH_1):GND
   50  GND            VSS20  @S9S_MB_2U_LIB.S9S_MB_2U(SCH_1):GND
   48  GND            VSS19  @S9S_MB_2U_LIB.S9S_MB_2U(SCH_1):GND
   46  GND            VSS18  @S9S_MB_2U_LIB.S9S_MB_2U(SCH_1):GND
   43  GND            VSS17  @S9S_MB_2U_LIB.S9S_MB_2U(SCH_1):GND
   41  GND            VSS16  @S9S_MB_2U_LIB.S9S_MB_2U(SCH_1):GND
   39  GND            VSS15  @S9S_MB_2U_LIB.S9S_MB_2U(SCH_1):GND
   37  GND            VSS14  @S9S_MB_2U_LIB.S9S_MB_2U(SCH_1):GND
   35  GND            VSS13  @S9S_MB_2U_LIB.S9S_MB_2U(SCH_1):GND
   32  GND            VSS12  @S9S_MB_2U_LIB.S9S_MB_2U(SCH_1):GND
   30  GND            VSS11  @S9S_MB_2U_LIB.S9S_MB_2U(SCH_1):GND
   28  GND            VSS10  @S9S_MB_2U_LIB.S9S_MB_2U(SCH_1):GND
   26  GND             VSS9  @S9S_MB_2U_LIB.S9S_MB_2U(SCH_1):GND
   24  GND             VSS8  @S9S_MB_2U_LIB.S9S_MB_2U(SCH_1):GND
   21  GND             VSS7  @S9S_MB_2U_LIB.S9S_MB_2U(SCH_1):GND
   19  GND             VSS6  @S9S_MB_2U_LIB.S9S_MB_2U(SCH_1):GND
   17  GND             VSS5  @S9S_MB_2U_LIB.S9S_MB_2U(SCH_1):GND
   15  GND             VSS4  @S9S_MB_2U_LIB.S9S_MB_2U(SCH_1):GND
   13  GND             VSS3  @S9S_MB_2U_LIB.S9S_MB_2U(SCH_1):GND
   10  GND             VSS2  @S9S_MB_2U_LIB.S9S_MB_2U(SCH_1):GND
    8  GND             VSS1  @S9S_MB_2U_LIB.S9S_MB_2U(SCH_1):GND
    6  GND             VSS0  @S9S_MB_2U_LIB.S9S_MB_2U(SCH_1):GND
   G3  GND               G3  @S9S_MB_2U_LIB.S9S_MB_2U(SCH_1):GND
   G2  GND               G2  @S9S_MB_2U_LIB.S9S_MB_2U(SCH_1):GND
   G1  GND               G1  @S9S_MB_2U_LIB.S9S_MB_2U(SCH_1):GND

SCONN288_ADR50001P013C01  I125  J7     [SCONN288_ADR50001P013C01-SCONNA]
   93  M_D_CPU0_SB_DQS_DP<9>  DQS9_B_P  @S9S_MB_2U_LIB.S9S_MB_2U(SCH_1):M_D_CPU0_SB_DQS_DP<9>
  283  M_D_CPU0_SB_DQS_DP<8>  DQS8_B_P  @S9S_MB_2U_LIB.S9S_MB_2U(SCH_1):M_D_CPU0_SB_DQS_DP<8>
  272  M_D_CPU0_SB_DQS_DP<7>  DQS7_B_P  @S9S_MB_2U_LIB.S9S_MB_2U(SCH_1):M_D_CPU0_SB_DQS_DP<7>
  261  M_D_CPU0_SB_DQS_DP<6>  DQS6_B_P  @S9S_MB_2U_LIB.S9S_MB_2U(SCH_1):M_D_CPU0_SB_DQS_DP<6>
  250  M_D_CPU0_SB_DQS_DP<5>  DQS5_B_P  @S9S_MB_2U_LIB.S9S_MB_2U(SCH_1):M_D_CPU0_SB_DQS_DP<5>
  239  M_D_CPU0_SB_DQS_DP<4>  DQS4_B_P  @S9S_MB_2U_LIB.S9S_MB_2U(SCH_1):M_D_CPU0_SB_DQS_DP<4>
  137  M_D_CPU0_SB_DQS_DP<3>  DQS3_B_P  @S9S_MB_2U_LIB.S9S_MB_2U(SCH_1):M_D_CPU0_SB_DQS_DP<3>
  126  M_D_CPU0_SB_DQS_DP<2>  DQS2_B_P  @S9S_MB_2U_LIB.S9S_MB_2U(SCH_1):M_D_CPU0_SB_DQS_DP<2>
  115  M_D_CPU0_SB_DQS_DP<1>  DQS1_B_P  @S9S_MB_2U_LIB.S9S_MB_2U(SCH_1):M_D_CPU0_SB_DQS_DP<1>
  104  M_D_CPU0_SB_DQS_DP<0>  DQS0_B_P  @S9S_MB_2U_LIB.S9S_MB_2U(SCH_1):M_D_CPU0_SB_DQS_DP<0>
   94  M_D_CPU0_SB_DQS_DN<9>  DQS9_B_N  @S9S_MB_2U_LIB.S9S_MB_2U(SCH_1):M_D_CPU0_SB_DQS_DN<9>
  282  M_D_CPU0_SB_DQS_DN<8>  DQS8_B_N  @S9S_MB_2U_LIB.S9S_MB_2U(SCH_1):M_D_CPU0_SB_DQS_DN<8>
  271  M_D_CPU0_SB_DQS_DN<7>  DQS7_B_N  @S9S_MB_2U_LIB.S9S_MB_2U(SCH_1):M_D_CPU0_SB_DQS_DN<7>
  260  M_D_CPU0_SB_DQS_DN<6>  DQS6_B_N  @S9S_MB_2U_LIB.S9S_MB_2U(SCH_1):M_D_CPU0_SB_DQS_DN<6>
  249  M_D_CPU0_SB_DQS_DN<5>  DQS5_B_N  @S9S_MB_2U_LIB.S9S_MB_2U(SCH_1):M_D_CPU0_SB_DQS_DN<5>
  238  M_D_CPU0_SB_DQS_DN<4>  DQS4_B_N  @S9S_MB_2U_LIB.S9S_MB_2U(SCH_1):M_D_CPU0_SB_DQS_DN<4>
  138  M_D_CPU0_SB_DQS_DN<3>  DQS3_B_N  @S9S_MB_2U_LIB.S9S_MB_2U(SCH_1):M_D_CPU0_SB_DQS_DN<3>
  127  M_D_CPU0_SB_DQS_DN<2>  DQS2_B_N  @S9S_MB_2U_LIB.S9S_MB_2U(SCH_1):M_D_CPU0_SB_DQS_DN<2>
  116  M_D_CPU0_SB_DQS_DN<1>  DQS1_B_N  @S9S_MB_2U_LIB.S9S_MB_2U(SCH_1):M_D_CPU0_SB_DQS_DN<1>
  105  M_D_CPU0_SB_DQS_DN<0>  DQS0_B_N  @S9S_MB_2U_LIB.S9S_MB_2U(SCH_1):M_D_CPU0_SB_DQS_DN<0>
  201  M_D_CPU0_SA_DQS_DP<9>  DQS9_A_P  @S9S_MB_2U_LIB.S9S_MB_2U(SCH_1):M_D_CPU0_SA_DQS_DP<9>
  190  M_D_CPU0_SA_DQS_DP<8>  DQS8_A_P  @S9S_MB_2U_LIB.S9S_MB_2U(SCH_1):M_D_CPU0_SA_DQS_DP<8>
  179  M_D_CPU0_SA_DQS_DP<7>  DQS7_A_P  @S9S_MB_2U_LIB.S9S_MB_2U(SCH_1):M_D_CPU0_SA_DQS_DP<7>
  168  M_D_CPU0_SA_DQS_DP<6>  DQS6_A_P  @S9S_MB_2U_LIB.S9S_MB_2U(SCH_1):M_D_CPU0_SA_DQS_DP<6>
  157  M_D_CPU0_SA_DQS_DP<5>  DQS5_A_P  @S9S_MB_2U_LIB.S9S_MB_2U(SCH_1):M_D_CPU0_SA_DQS_DP<5>
   55  M_D_CPU0_SA_DQS_DP<4>  DQS4_A_P  @S9S_MB_2U_LIB.S9S_MB_2U(SCH_1):M_D_CPU0_SA_DQS_DP<4>
   44  M_D_CPU0_SA_DQS_DP<3>  DQS3_A_P  @S9S_MB_2U_LIB.S9S_MB_2U(SCH_1):M_D_CPU0_SA_DQS_DP<3>
   33  M_D_CPU0_SA_DQS_DP<2>  DQS2_A_P  @S9S_MB_2U_LIB.S9S_MB_2U(SCH_1):M_D_CPU0_SA_DQS_DP<2>
   22  M_D_CPU0_SA_DQS_DP<1>  DQS1_A_P  @S9S_MB_2U_LIB.S9S_MB_2U(SCH_1):M_D_CPU0_SA_DQS_DP<1>
   11  M_D_CPU0_SA_DQS_DP<0>  DQS0_A_P  @S9S_MB_2U_LIB.S9S_MB_2U(SCH_1):M_D_CPU0_SA_DQS_DP<0>
  200  M_D_CPU0_SA_DQS_DN<9>  DQS9_A_N  @S9S_MB_2U_LIB.S9S_MB_2U(SCH_1):M_D_CPU0_SA_DQS_DN<9>
  189  M_D_CPU0_SA_DQS_DN<8>  DQS8_A_N  @S9S_MB_2U_LIB.S9S_MB_2U(SCH_1):M_D_CPU0_SA_DQS_DN<8>
  178  M_D_CPU0_SA_DQS_DN<7>  DQS7_A_N  @S9S_MB_2U_LIB.S9S_MB_2U(SCH_1):M_D_CPU0_SA_DQS_DN<7>
  167  M_D_CPU0_SA_DQS_DN<6>  DQS6_A_N  @S9S_MB_2U_LIB.S9S_MB_2U(SCH_1):M_D_CPU0_SA_DQS_DN<6>
  156  M_D_CPU0_SA_DQS_DN<5>  DQS5_A_N  @S9S_MB_2U_LIB.S9S_MB_2U(SCH_1):M_D_CPU0_SA_DQS_DN<5>
   56  M_D_CPU0_SA_DQS_DN<4>  DQS4_A_N  @S9S_MB_2U_LIB.S9S_MB_2U(SCH_1):M_D_CPU0_SA_DQS_DN<4>
   45  M_D_CPU0_SA_DQS_DN<3>  DQS3_A_N  @S9S_MB_2U_LIB.S9S_MB_2U(SCH_1):M_D_CPU0_SA_DQS_DN<3>
   34  M_D_CPU0_SA_DQS_DN<2>  DQS2_A_N  @S9S_MB_2U_LIB.S9S_MB_2U(SCH_1):M_D_CPU0_SA_DQS_DN<2>
   23  M_D_CPU0_SA_DQS_DN<1>  DQS1_A_N  @S9S_MB_2U_LIB.S9S_MB_2U(SCH_1):M_D_CPU0_SA_DQS_DN<1>
   12  M_D_CPU0_SA_DQS_DN<0>  DQS0_A_N  @S9S_MB_2U_LIB.S9S_MB_2U(SCH_1):M_D_CPU0_SA_DQS_DN<0>

SCONN288_ADR50001P013C01  I12  J7     [SCONN288_ADR50001P013C01-SCONNA]
  232  NC              RFU6  NC
  231  NC              RFU5  NC
  220  NC              RFU4  NC
  150  NC              RFU3  NC
  149  NC              RFU2  NC
  144  NC              RFU1  NC
    2  NC              RFU0  NC
  207  RST_M_CD_CPU0_FPGA_N  RESET_N  @S9S_MB_2U_LIB.S9S_MB_2U(SCH_1):RST_M_CD_CPU0_FPGA_N
  147  PWRGD_CHD_CPU0_DIMM1  PWR_GOOD||FAIL_N  @S9S_MB_2U_LIB.S9S_MB_2U(SCH_1):PWRGD_CHD_CPU0_DIMM1
  148  PD_CHD_CPU0_DIMM1_SAA    HAS  @S9S_MB_2U_LIB.S9S_MB_2U(SCH_1):PD_CHD_CPU0_DIMM1_SAA
    3  P3V3_AUX       VIN_MGMT  @S9S_MB_2U_LIB.S9S_MB_2U(SCH_1):P3V3_AUX
   87  M_D_CPU0_SB_RSP<0>  LBS||RSP_N_B  @S9S_MB_2U_LIB.S9S_MB_2U(SCH_1):M_D_CPU0_SB_RSP<0>
  227  M_D_CPU0_SB_PAR  PAR_B  @S9S_MB_2U_LIB.S9S_MB_2U(SCH_1):M_D_CPU0_SB_PAR
  113  M_D_CPU0_SB_DQ<9>  DQ_B9  @S9S_MB_2U_LIB.S9S_MB_2U(SCH_1):M_D_CPU0_SB_DQ<9>
  111  M_D_CPU0_SB_DQ<8>  DQ_B8  @S9S_MB_2U_LIB.S9S_MB_2U(SCH_1):M_D_CPU0_SB_DQ<8>
  254  M_D_CPU0_SB_DQ<7>  DQ_B7  @S9S_MB_2U_LIB.S9S_MB_2U(SCH_1):M_D_CPU0_SB_DQ<7>
  252  M_D_CPU0_SB_DQ<6>  DQ_B6  @S9S_MB_2U_LIB.S9S_MB_2U(SCH_1):M_D_CPU0_SB_DQ<6>
  109  M_D_CPU0_SB_DQ<5>  DQ_B5  @S9S_MB_2U_LIB.S9S_MB_2U(SCH_1):M_D_CPU0_SB_DQ<5>
  107  M_D_CPU0_SB_DQ<4>  DQ_B4  @S9S_MB_2U_LIB.S9S_MB_2U(SCH_1):M_D_CPU0_SB_DQ<4>
  247  M_D_CPU0_SB_DQ<3>  DQ_B3  @S9S_MB_2U_LIB.S9S_MB_2U(SCH_1):M_D_CPU0_SB_DQ<3>
  287  M_D_CPU0_SB_DQ<31>  DQ_B31  @S9S_MB_2U_LIB.S9S_MB_2U(SCH_1):M_D_CPU0_SB_DQ<31>
  285  M_D_CPU0_SB_DQ<30>  DQ_B30  @S9S_MB_2U_LIB.S9S_MB_2U(SCH_1):M_D_CPU0_SB_DQ<30>
  245  M_D_CPU0_SB_DQ<2>  DQ_B2  @S9S_MB_2U_LIB.S9S_MB_2U(SCH_1):M_D_CPU0_SB_DQ<2>
  142  M_D_CPU0_SB_DQ<29>  DQ_B29  @S9S_MB_2U_LIB.S9S_MB_2U(SCH_1):M_D_CPU0_SB_DQ<29>
  140  M_D_CPU0_SB_DQ<28>  DQ_B28  @S9S_MB_2U_LIB.S9S_MB_2U(SCH_1):M_D_CPU0_SB_DQ<28>
  280  M_D_CPU0_SB_DQ<27>  DQ_B27  @S9S_MB_2U_LIB.S9S_MB_2U(SCH_1):M_D_CPU0_SB_DQ<27>
  278  M_D_CPU0_SB_DQ<26>  DQ_B26  @S9S_MB_2U_LIB.S9S_MB_2U(SCH_1):M_D_CPU0_SB_DQ<26>
  135  M_D_CPU0_SB_DQ<25>  DQ_B25  @S9S_MB_2U_LIB.S9S_MB_2U(SCH_1):M_D_CPU0_SB_DQ<25>
  133  M_D_CPU0_SB_DQ<24>  DQ_B24  @S9S_MB_2U_LIB.S9S_MB_2U(SCH_1):M_D_CPU0_SB_DQ<24>
  276  M_D_CPU0_SB_DQ<23>  DQ_B23  @S9S_MB_2U_LIB.S9S_MB_2U(SCH_1):M_D_CPU0_SB_DQ<23>
  274  M_D_CPU0_SB_DQ<22>  DQ_B22  @S9S_MB_2U_LIB.S9S_MB_2U(SCH_1):M_D_CPU0_SB_DQ<22>
  131  M_D_CPU0_SB_DQ<21>  DQ_B21  @S9S_MB_2U_LIB.S9S_MB_2U(SCH_1):M_D_CPU0_SB_DQ<21>
  129  M_D_CPU0_SB_DQ<20>  DQ_B20  @S9S_MB_2U_LIB.S9S_MB_2U(SCH_1):M_D_CPU0_SB_DQ<20>
  102  M_D_CPU0_SB_DQ<1>  DQ_B1  @S9S_MB_2U_LIB.S9S_MB_2U(SCH_1):M_D_CPU0_SB_DQ<1>
  269  M_D_CPU0_SB_DQ<19>  DQ_B19  @S9S_MB_2U_LIB.S9S_MB_2U(SCH_1):M_D_CPU0_SB_DQ<19>
  267  M_D_CPU0_SB_DQ<18>  DQ_B18  @S9S_MB_2U_LIB.S9S_MB_2U(SCH_1):M_D_CPU0_SB_DQ<18>
  124  M_D_CPU0_SB_DQ<17>  DQ_B17  @S9S_MB_2U_LIB.S9S_MB_2U(SCH_1):M_D_CPU0_SB_DQ<17>
  122  M_D_CPU0_SB_DQ<16>  DQ_B16  @S9S_MB_2U_LIB.S9S_MB_2U(SCH_1):M_D_CPU0_SB_DQ<16>
  265  M_D_CPU0_SB_DQ<15>  DQ_B15  @S9S_MB_2U_LIB.S9S_MB_2U(SCH_1):M_D_CPU0_SB_DQ<15>
  263  M_D_CPU0_SB_DQ<14>  DQ_B14  @S9S_MB_2U_LIB.S9S_MB_2U(SCH_1):M_D_CPU0_SB_DQ<14>
  120  M_D_CPU0_SB_DQ<13>  DQ_B13  @S9S_MB_2U_LIB.S9S_MB_2U(SCH_1):M_D_CPU0_SB_DQ<13>
  118  M_D_CPU0_SB_DQ<12>  DQ_B12  @S9S_MB_2U_LIB.S9S_MB_2U(SCH_1):M_D_CPU0_SB_DQ<12>
  258  M_D_CPU0_SB_DQ<11>  DQ_B11  @S9S_MB_2U_LIB.S9S_MB_2U(SCH_1):M_D_CPU0_SB_DQ<11>
  256  M_D_CPU0_SB_DQ<10>  DQ_B10  @S9S_MB_2U_LIB.S9S_MB_2U(SCH_1):M_D_CPU0_SB_DQ<10>
  100  M_D_CPU0_SB_DQ<0>  DQ_B0  @S9S_MB_2U_LIB.S9S_MB_2U(SCH_1):M_D_CPU0_SB_DQ<0>
  229  M_D_CPU0_SB_CS_N<1>  CS1_N_B  @S9S_MB_2U_LIB.S9S_MB_2U(SCH_1):M_D_CPU0_SB_CS_N<1>
   84  M_D_CPU0_SB_CS_N<0>  CS0_N_B  @S9S_MB_2U_LIB.S9S_MB_2U(SCH_1):M_D_CPU0_SB_CS_N<0>
  236  M_D_CPU0_SB_CB<7>  CB_B7  @S9S_MB_2U_LIB.S9S_MB_2U(SCH_1):M_D_CPU0_SB_CB<7>
  234  M_D_CPU0_SB_CB<6>  CB_B6  @S9S_MB_2U_LIB.S9S_MB_2U(SCH_1):M_D_CPU0_SB_CB<6>
   91  M_D_CPU0_SB_CB<5>  CB_B5  @S9S_MB_2U_LIB.S9S_MB_2U(SCH_1):M_D_CPU0_SB_CB<5>
   89  M_D_CPU0_SB_CB<4>  CB_B4  @S9S_MB_2U_LIB.S9S_MB_2U(SCH_1):M_D_CPU0_SB_CB<4>
  243  M_D_CPU0_SB_CB<3>  CB_B3  @S9S_MB_2U_LIB.S9S_MB_2U(SCH_1):M_D_CPU0_SB_CB<3>
  241  M_D_CPU0_SB_CB<2>  CB_B2  @S9S_MB_2U_LIB.S9S_MB_2U(SCH_1):M_D_CPU0_SB_CB<2>
   98  M_D_CPU0_SB_CB<1>  CB_B1  @S9S_MB_2U_LIB.S9S_MB_2U(SCH_1):M_D_CPU0_SB_CB<1>
   96  M_D_CPU0_SB_CB<0>  CB_B0  @S9S_MB_2U_LIB.S9S_MB_2U(SCH_1):M_D_CPU0_SB_CB<0>
   82  M_D_CPU0_SB_CA<6>  CA6_B  @S9S_MB_2U_LIB.S9S_MB_2U(SCH_1):M_D_CPU0_SB_CA<6>
  225  M_D_CPU0_SB_CA<5>  CA5_B  @S9S_MB_2U_LIB.S9S_MB_2U(SCH_1):M_D_CPU0_SB_CA<5>
   80  M_D_CPU0_SB_CA<4>  CA4_B  @S9S_MB_2U_LIB.S9S_MB_2U(SCH_1):M_D_CPU0_SB_CA<4>
  223  M_D_CPU0_SB_CA<3>  CA3_B  @S9S_MB_2U_LIB.S9S_MB_2U(SCH_1):M_D_CPU0_SB_CA<3>
   78  M_D_CPU0_SB_CA<2>  CA2_B  @S9S_MB_2U_LIB.S9S_MB_2U(SCH_1):M_D_CPU0_SB_CA<2>
  221  M_D_CPU0_SB_CA<1>  CA1_B  @S9S_MB_2U_LIB.S9S_MB_2U(SCH_1):M_D_CPU0_SB_CA<1>
   76  M_D_CPU0_SB_CA<0>  CA0_B  @S9S_MB_2U_LIB.S9S_MB_2U(SCH_1):M_D_CPU0_SB_CA<0>
   86  M_D_CPU0_SA_RSP<0>  LBD||RSP_N_A  @S9S_MB_2U_LIB.S9S_MB_2U(SCH_1):M_D_CPU0_SA_RSP<0>
   74  M_D_CPU0_SA_PAR  PAR_A  @S9S_MB_2U_LIB.S9S_MB_2U(SCH_1):M_D_CPU0_SA_PAR
   20  M_D_CPU0_SA_DQ<9>  DQ_A9  @S9S_MB_2U_LIB.S9S_MB_2U(SCH_1):M_D_CPU0_SA_DQ<9>
   18  M_D_CPU0_SA_DQ<8>  DQ_A8  @S9S_MB_2U_LIB.S9S_MB_2U(SCH_1):M_D_CPU0_SA_DQ<8>
  161  M_D_CPU0_SA_DQ<7>  DQ_A7  @S9S_MB_2U_LIB.S9S_MB_2U(SCH_1):M_D_CPU0_SA_DQ<7>
  159  M_D_CPU0_SA_DQ<6>  DQ_A6  @S9S_MB_2U_LIB.S9S_MB_2U(SCH_1):M_D_CPU0_SA_DQ<6>
   16  M_D_CPU0_SA_DQ<5>  DQ_A5  @S9S_MB_2U_LIB.S9S_MB_2U(SCH_1):M_D_CPU0_SA_DQ<5>
   14  M_D_CPU0_SA_DQ<4>  DQ_A4  @S9S_MB_2U_LIB.S9S_MB_2U(SCH_1):M_D_CPU0_SA_DQ<4>
  154  M_D_CPU0_SA_DQ<3>  DQ_A3  @S9S_MB_2U_LIB.S9S_MB_2U(SCH_1):M_D_CPU0_SA_DQ<3>
  194  M_D_CPU0_SA_DQ<31>  DQ_A31  @S9S_MB_2U_LIB.S9S_MB_2U(SCH_1):M_D_CPU0_SA_DQ<31>
  192  M_D_CPU0_SA_DQ<30>  DQ_A30  @S9S_MB_2U_LIB.S9S_MB_2U(SCH_1):M_D_CPU0_SA_DQ<30>
  152  M_D_CPU0_SA_DQ<2>  DQ_A2  @S9S_MB_2U_LIB.S9S_MB_2U(SCH_1):M_D_CPU0_SA_DQ<2>
   49  M_D_CPU0_SA_DQ<29>  DQ_A29  @S9S_MB_2U_LIB.S9S_MB_2U(SCH_1):M_D_CPU0_SA_DQ<29>
   47  M_D_CPU0_SA_DQ<28>  DQ_A28  @S9S_MB_2U_LIB.S9S_MB_2U(SCH_1):M_D_CPU0_SA_DQ<28>
  187  M_D_CPU0_SA_DQ<27>  DQ_A27  @S9S_MB_2U_LIB.S9S_MB_2U(SCH_1):M_D_CPU0_SA_DQ<27>
  185  M_D_CPU0_SA_DQ<26>  DQ_A26  @S9S_MB_2U_LIB.S9S_MB_2U(SCH_1):M_D_CPU0_SA_DQ<26>
   42  M_D_CPU0_SA_DQ<25>  DQ_A25  @S9S_MB_2U_LIB.S9S_MB_2U(SCH_1):M_D_CPU0_SA_DQ<25>
   40  M_D_CPU0_SA_DQ<24>  DQ_A24  @S9S_MB_2U_LIB.S9S_MB_2U(SCH_1):M_D_CPU0_SA_DQ<24>
  183  M_D_CPU0_SA_DQ<23>  DQ_A23  @S9S_MB_2U_LIB.S9S_MB_2U(SCH_1):M_D_CPU0_SA_DQ<23>
  181  M_D_CPU0_SA_DQ<22>  DQ_A22  @S9S_MB_2U_LIB.S9S_MB_2U(SCH_1):M_D_CPU0_SA_DQ<22>
   38  M_D_CPU0_SA_DQ<21>  DQ_A21  @S9S_MB_2U_LIB.S9S_MB_2U(SCH_1):M_D_CPU0_SA_DQ<21>
   36  M_D_CPU0_SA_DQ<20>  DQ_A20  @S9S_MB_2U_LIB.S9S_MB_2U(SCH_1):M_D_CPU0_SA_DQ<20>
    9  M_D_CPU0_SA_DQ<1>  DQ_A1  @S9S_MB_2U_LIB.S9S_MB_2U(SCH_1):M_D_CPU0_SA_DQ<1>
  176  M_D_CPU0_SA_DQ<19>  DQ_A19  @S9S_MB_2U_LIB.S9S_MB_2U(SCH_1):M_D_CPU0_SA_DQ<19>
  174  M_D_CPU0_SA_DQ<18>  DQ_A18  @S9S_MB_2U_LIB.S9S_MB_2U(SCH_1):M_D_CPU0_SA_DQ<18>
   31  M_D_CPU0_SA_DQ<17>  DQ_A17  @S9S_MB_2U_LIB.S9S_MB_2U(SCH_1):M_D_CPU0_SA_DQ<17>
   29  M_D_CPU0_SA_DQ<16>  DQ_A16  @S9S_MB_2U_LIB.S9S_MB_2U(SCH_1):M_D_CPU0_SA_DQ<16>
  172  M_D_CPU0_SA_DQ<15>  DQ_A15  @S9S_MB_2U_LIB.S9S_MB_2U(SCH_1):M_D_CPU0_SA_DQ<15>
  170  M_D_CPU0_SA_DQ<14>  DQ_A14  @S9S_MB_2U_LIB.S9S_MB_2U(SCH_1):M_D_CPU0_SA_DQ<14>
   27  M_D_CPU0_SA_DQ<13>  DQ_A13  @S9S_MB_2U_LIB.S9S_MB_2U(SCH_1):M_D_CPU0_SA_DQ<13>
   25  M_D_CPU0_SA_DQ<12>  DQ_A12  @S9S_MB_2U_LIB.S9S_MB_2U(SCH_1):M_D_CPU0_SA_DQ<12>
  165  M_D_CPU0_SA_DQ<11>  DQ_A11  @S9S_MB_2U_LIB.S9S_MB_2U(SCH_1):M_D_CPU0_SA_DQ<11>
  163  M_D_CPU0_SA_DQ<10>  DQ_A10  @S9S_MB_2U_LIB.S9S_MB_2U(SCH_1):M_D_CPU0_SA_DQ<10>
    7  M_D_CPU0_SA_DQ<0>  DQ_A0  @S9S_MB_2U_LIB.S9S_MB_2U(SCH_1):M_D_CPU0_SA_DQ<0>
  209  M_D_CPU0_SA_CS_N<1>  CS1_N_A  @S9S_MB_2U_LIB.S9S_MB_2U(SCH_1):M_D_CPU0_SA_CS_N<1>
   64  M_D_CPU0_SA_CS_N<0>  CS0_N_A  @S9S_MB_2U_LIB.S9S_MB_2U(SCH_1):M_D_CPU0_SA_CS_N<0>
  205  M_D_CPU0_SA_CB<7>  CB_A7  @S9S_MB_2U_LIB.S9S_MB_2U(SCH_1):M_D_CPU0_SA_CB<7>
  203  M_D_CPU0_SA_CB<6>  CB_A6  @S9S_MB_2U_LIB.S9S_MB_2U(SCH_1):M_D_CPU0_SA_CB<6>
   60  M_D_CPU0_SA_CB<5>  CB_A5  @S9S_MB_2U_LIB.S9S_MB_2U(SCH_1):M_D_CPU0_SA_CB<5>
   58  M_D_CPU0_SA_CB<4>  CB_A4  @S9S_MB_2U_LIB.S9S_MB_2U(SCH_1):M_D_CPU0_SA_CB<4>
  198  M_D_CPU0_SA_CB<3>  CB_A3  @S9S_MB_2U_LIB.S9S_MB_2U(SCH_1):M_D_CPU0_SA_CB<3>
  196  M_D_CPU0_SA_CB<2>  CB_A2  @S9S_MB_2U_LIB.S9S_MB_2U(SCH_1):M_D_CPU0_SA_CB<2>
   53  M_D_CPU0_SA_CB<1>  CB_A1  @S9S_MB_2U_LIB.S9S_MB_2U(SCH_1):M_D_CPU0_SA_CB<1>
   51  M_D_CPU0_SA_CB<0>  CB_A0  @S9S_MB_2U_LIB.S9S_MB_2U(SCH_1):M_D_CPU0_SA_CB<0>
   72  M_D_CPU0_SA_CA<6>  CA6_A  @S9S_MB_2U_LIB.S9S_MB_2U(SCH_1):M_D_CPU0_SA_CA<6>
  215  M_D_CPU0_SA_CA<5>  CA5_A  @S9S_MB_2U_LIB.S9S_MB_2U(SCH_1):M_D_CPU0_SA_CA<5>
   70  M_D_CPU0_SA_CA<4>  CA4_A  @S9S_MB_2U_LIB.S9S_MB_2U(SCH_1):M_D_CPU0_SA_CA<4>
  213  M_D_CPU0_SA_CA<3>  CA3_A  @S9S_MB_2U_LIB.S9S_MB_2U(SCH_1):M_D_CPU0_SA_CA<3>
   68  M_D_CPU0_SA_CA<2>  CA2_A  @S9S_MB_2U_LIB.S9S_MB_2U(SCH_1):M_D_CPU0_SA_CA<2>
  211  M_D_CPU0_SA_CA<1>  CA1_A  @S9S_MB_2U_LIB.S9S_MB_2U(SCH_1):M_D_CPU0_SA_CA<1>
   66  M_D_CPU0_SA_CA<0>  CA0_A  @S9S_MB_2U_LIB.S9S_MB_2U(SCH_1):M_D_CPU0_SA_CA<0>
  217  M_D_CPU0_CLK_DP<0>   CK_P  @S9S_MB_2U_LIB.S9S_MB_2U(SCH_1):M_D_CPU0_CLK_DP<0>
  218  M_D_CPU0_CLK_DN<0>   CK_N  @S9S_MB_2U_LIB.S9S_MB_2U(SCH_1):M_D_CPU0_CLK_DN<0>
   62  M_D_CPU0_ALERT_N  ALERT_N  @S9S_MB_2U_LIB.S9S_MB_2U(SCH_1):M_D_CPU0_ALERT_N
    5  I3C_SPD_DDRABCD_CPU0_LVC1_SDA   HSDA  @S9S_MB_2U_LIB.S9S_MB_2U(SCH_1):I3C_SPD_DDRABCD_CPU0_LVC1_SDA
    4  I3C_SPD_DDRABCD_CPU0_LVC1_SCL   HSCL  @S9S_MB_2U_LIB.S9S_MB_2U(SCH_1):I3C_SPD_DDRABCD_CPU0_LVC1_SCL

SCONN288_ADR50001P003C01  I175  J8     [SCONN288_ADR50001P003C01-SCONNA]
  146  P12V_S3_AUX_CPU0_NVDIMM  VIN_BULK2  @S9S_MB_2U_LIB.S9S_MB_2U(SCH_1):P12V_S3_AUX_CPU0_NVDIMM
  145  P12V_S3_AUX_CPU0_NVDIMM  VIN_BULK1  @S9S_MB_2U_LIB.S9S_MB_2U(SCH_1):P12V_S3_AUX_CPU0_NVDIMM
    1  P12V_S3_AUX_CPU0_NVDIMM  VIN_BULK0  @S9S_MB_2U_LIB.S9S_MB_2U(SCH_1):P12V_S3_AUX_CPU0_NVDIMM
  288  GND            VSS126  @S9S_MB_2U_LIB.S9S_MB_2U(SCH_1):GND
  286  GND            VSS125  @S9S_MB_2U_LIB.S9S_MB_2U(SCH_1):GND
  284  GND            VSS124  @S9S_MB_2U_LIB.S9S_MB_2U(SCH_1):GND
  281  GND            VSS123  @S9S_MB_2U_LIB.S9S_MB_2U(SCH_1):GND
  279  GND            VSS122  @S9S_MB_2U_LIB.S9S_MB_2U(SCH_1):GND
  277  GND            VSS121  @S9S_MB_2U_LIB.S9S_MB_2U(SCH_1):GND
  275  GND            VSS120  @S9S_MB_2U_LIB.S9S_MB_2U(SCH_1):GND
  273  GND            VSS119  @S9S_MB_2U_LIB.S9S_MB_2U(SCH_1):GND
  270  GND            VSS118  @S9S_MB_2U_LIB.S9S_MB_2U(SCH_1):GND
  268  GND            VSS117  @S9S_MB_2U_LIB.S9S_MB_2U(SCH_1):GND
  266  GND            VSS116  @S9S_MB_2U_LIB.S9S_MB_2U(SCH_1):GND
  264  GND            VSS115  @S9S_MB_2U_LIB.S9S_MB_2U(SCH_1):GND
  262  GND            VSS114  @S9S_MB_2U_LIB.S9S_MB_2U(SCH_1):GND
  259  GND            VSS113  @S9S_MB_2U_LIB.S9S_MB_2U(SCH_1):GND
  257  GND            VSS112  @S9S_MB_2U_LIB.S9S_MB_2U(SCH_1):GND
  255  GND            VSS111  @S9S_MB_2U_LIB.S9S_MB_2U(SCH_1):GND
  253  GND            VSS110  @S9S_MB_2U_LIB.S9S_MB_2U(SCH_1):GND
  251  GND            VSS109  @S9S_MB_2U_LIB.S9S_MB_2U(SCH_1):GND
  248  GND            VSS108  @S9S_MB_2U_LIB.S9S_MB_2U(SCH_1):GND
  246  GND            VSS107  @S9S_MB_2U_LIB.S9S_MB_2U(SCH_1):GND
  244  GND            VSS106  @S9S_MB_2U_LIB.S9S_MB_2U(SCH_1):GND
  242  GND            VSS105  @S9S_MB_2U_LIB.S9S_MB_2U(SCH_1):GND
  240  GND            VSS104  @S9S_MB_2U_LIB.S9S_MB_2U(SCH_1):GND
  237  GND            VSS103  @S9S_MB_2U_LIB.S9S_MB_2U(SCH_1):GND
  235  GND            VSS102  @S9S_MB_2U_LIB.S9S_MB_2U(SCH_1):GND
  233  GND            VSS101  @S9S_MB_2U_LIB.S9S_MB_2U(SCH_1):GND
  230  GND            VSS100  @S9S_MB_2U_LIB.S9S_MB_2U(SCH_1):GND
  228  GND            VSS99  @S9S_MB_2U_LIB.S9S_MB_2U(SCH_1):GND
  226  GND            VSS98  @S9S_MB_2U_LIB.S9S_MB_2U(SCH_1):GND
  224  GND            VSS97  @S9S_MB_2U_LIB.S9S_MB_2U(SCH_1):GND
  222  GND            VSS96  @S9S_MB_2U_LIB.S9S_MB_2U(SCH_1):GND
  219  GND            VSS95  @S9S_MB_2U_LIB.S9S_MB_2U(SCH_1):GND
  216  GND            VSS94  @S9S_MB_2U_LIB.S9S_MB_2U(SCH_1):GND
  214  GND            VSS93  @S9S_MB_2U_LIB.S9S_MB_2U(SCH_1):GND
  212  GND            VSS92  @S9S_MB_2U_LIB.S9S_MB_2U(SCH_1):GND
  210  GND            VSS91  @S9S_MB_2U_LIB.S9S_MB_2U(SCH_1):GND
  208  GND            VSS90  @S9S_MB_2U_LIB.S9S_MB_2U(SCH_1):GND
  206  GND            VSS89  @S9S_MB_2U_LIB.S9S_MB_2U(SCH_1):GND
  204  GND            VSS88  @S9S_MB_2U_LIB.S9S_MB_2U(SCH_1):GND
  202  GND            VSS87  @S9S_MB_2U_LIB.S9S_MB_2U(SCH_1):GND
  199  GND            VSS86  @S9S_MB_2U_LIB.S9S_MB_2U(SCH_1):GND
  197  GND            VSS85  @S9S_MB_2U_LIB.S9S_MB_2U(SCH_1):GND
  195  GND            VSS84  @S9S_MB_2U_LIB.S9S_MB_2U(SCH_1):GND
  193  GND            VSS83  @S9S_MB_2U_LIB.S9S_MB_2U(SCH_1):GND
  191  GND            VSS82  @S9S_MB_2U_LIB.S9S_MB_2U(SCH_1):GND
  188  GND            VSS81  @S9S_MB_2U_LIB.S9S_MB_2U(SCH_1):GND
  186  GND            VSS80  @S9S_MB_2U_LIB.S9S_MB_2U(SCH_1):GND
  184  GND            VSS79  @S9S_MB_2U_LIB.S9S_MB_2U(SCH_1):GND
  182  GND            VSS78  @S9S_MB_2U_LIB.S9S_MB_2U(SCH_1):GND
  180  GND            VSS77  @S9S_MB_2U_LIB.S9S_MB_2U(SCH_1):GND
  177  GND            VSS76  @S9S_MB_2U_LIB.S9S_MB_2U(SCH_1):GND
  175  GND            VSS75  @S9S_MB_2U_LIB.S9S_MB_2U(SCH_1):GND
  173  GND            VSS74  @S9S_MB_2U_LIB.S9S_MB_2U(SCH_1):GND
  171  GND            VSS73  @S9S_MB_2U_LIB.S9S_MB_2U(SCH_1):GND
  169  GND            VSS72  @S9S_MB_2U_LIB.S9S_MB_2U(SCH_1):GND
  166  GND            VSS71  @S9S_MB_2U_LIB.S9S_MB_2U(SCH_1):GND
  164  GND            VSS70  @S9S_MB_2U_LIB.S9S_MB_2U(SCH_1):GND
  162  GND            VSS69  @S9S_MB_2U_LIB.S9S_MB_2U(SCH_1):GND
  160  GND            VSS68  @S9S_MB_2U_LIB.S9S_MB_2U(SCH_1):GND
  158  GND            VSS67  @S9S_MB_2U_LIB.S9S_MB_2U(SCH_1):GND
  155  GND            VSS66  @S9S_MB_2U_LIB.S9S_MB_2U(SCH_1):GND
  153  GND            VSS65  @S9S_MB_2U_LIB.S9S_MB_2U(SCH_1):GND
  151  GND            VSS64  @S9S_MB_2U_LIB.S9S_MB_2U(SCH_1):GND
  143  GND            VSS63  @S9S_MB_2U_LIB.S9S_MB_2U(SCH_1):GND
  141  GND            VSS62  @S9S_MB_2U_LIB.S9S_MB_2U(SCH_1):GND
  139  GND            VSS61  @S9S_MB_2U_LIB.S9S_MB_2U(SCH_1):GND
  136  GND            VSS60  @S9S_MB_2U_LIB.S9S_MB_2U(SCH_1):GND
  134  GND            VSS59  @S9S_MB_2U_LIB.S9S_MB_2U(SCH_1):GND
  132  GND            VSS58  @S9S_MB_2U_LIB.S9S_MB_2U(SCH_1):GND
  130  GND            VSS57  @S9S_MB_2U_LIB.S9S_MB_2U(SCH_1):GND
  128  GND            VSS56  @S9S_MB_2U_LIB.S9S_MB_2U(SCH_1):GND
  125  GND            VSS55  @S9S_MB_2U_LIB.S9S_MB_2U(SCH_1):GND
  123  GND            VSS54  @S9S_MB_2U_LIB.S9S_MB_2U(SCH_1):GND
  121  GND            VSS53  @S9S_MB_2U_LIB.S9S_MB_2U(SCH_1):GND
  119  GND            VSS52  @S9S_MB_2U_LIB.S9S_MB_2U(SCH_1):GND
  117  GND            VSS51  @S9S_MB_2U_LIB.S9S_MB_2U(SCH_1):GND
  114  GND            VSS50  @S9S_MB_2U_LIB.S9S_MB_2U(SCH_1):GND
  112  GND            VSS49  @S9S_MB_2U_LIB.S9S_MB_2U(SCH_1):GND
  110  GND            VSS48  @S9S_MB_2U_LIB.S9S_MB_2U(SCH_1):GND
  108  GND            VSS47  @S9S_MB_2U_LIB.S9S_MB_2U(SCH_1):GND
  106  GND            VSS46  @S9S_MB_2U_LIB.S9S_MB_2U(SCH_1):GND
  103  GND            VSS45  @S9S_MB_2U_LIB.S9S_MB_2U(SCH_1):GND
  101  GND            VSS44  @S9S_MB_2U_LIB.S9S_MB_2U(SCH_1):GND
   99  GND            VSS43  @S9S_MB_2U_LIB.S9S_MB_2U(SCH_1):GND
   97  GND            VSS42  @S9S_MB_2U_LIB.S9S_MB_2U(SCH_1):GND
   95  GND            VSS41  @S9S_MB_2U_LIB.S9S_MB_2U(SCH_1):GND
   92  GND            VSS40  @S9S_MB_2U_LIB.S9S_MB_2U(SCH_1):GND
   90  GND            VSS39  @S9S_MB_2U_LIB.S9S_MB_2U(SCH_1):GND
   88  GND            VSS38  @S9S_MB_2U_LIB.S9S_MB_2U(SCH_1):GND
   85  GND            VSS37  @S9S_MB_2U_LIB.S9S_MB_2U(SCH_1):GND
   83  GND            VSS36  @S9S_MB_2U_LIB.S9S_MB_2U(SCH_1):GND
   81  GND            VSS35  @S9S_MB_2U_LIB.S9S_MB_2U(SCH_1):GND
   79  GND            VSS34  @S9S_MB_2U_LIB.S9S_MB_2U(SCH_1):GND
   77  GND            VSS33  @S9S_MB_2U_LIB.S9S_MB_2U(SCH_1):GND
   75  GND            VSS32  @S9S_MB_2U_LIB.S9S_MB_2U(SCH_1):GND
   73  GND            VSS31  @S9S_MB_2U_LIB.S9S_MB_2U(SCH_1):GND
   71  GND            VSS30  @S9S_MB_2U_LIB.S9S_MB_2U(SCH_1):GND
   69  GND            VSS29  @S9S_MB_2U_LIB.S9S_MB_2U(SCH_1):GND
   67  GND            VSS28  @S9S_MB_2U_LIB.S9S_MB_2U(SCH_1):GND
   65  GND            VSS27  @S9S_MB_2U_LIB.S9S_MB_2U(SCH_1):GND
   63  GND            VSS26  @S9S_MB_2U_LIB.S9S_MB_2U(SCH_1):GND
   61  GND            VSS25  @S9S_MB_2U_LIB.S9S_MB_2U(SCH_1):GND
   59  GND            VSS24  @S9S_MB_2U_LIB.S9S_MB_2U(SCH_1):GND
   57  GND            VSS23  @S9S_MB_2U_LIB.S9S_MB_2U(SCH_1):GND
   54  GND            VSS22  @S9S_MB_2U_LIB.S9S_MB_2U(SCH_1):GND
   52  GND            VSS21  @S9S_MB_2U_LIB.S9S_MB_2U(SCH_1):GND
   50  GND            VSS20  @S9S_MB_2U_LIB.S9S_MB_2U(SCH_1):GND
   48  GND            VSS19  @S9S_MB_2U_LIB.S9S_MB_2U(SCH_1):GND
   46  GND            VSS18  @S9S_MB_2U_LIB.S9S_MB_2U(SCH_1):GND
   43  GND            VSS17  @S9S_MB_2U_LIB.S9S_MB_2U(SCH_1):GND
   41  GND            VSS16  @S9S_MB_2U_LIB.S9S_MB_2U(SCH_1):GND
   39  GND            VSS15  @S9S_MB_2U_LIB.S9S_MB_2U(SCH_1):GND
   37  GND            VSS14  @S9S_MB_2U_LIB.S9S_MB_2U(SCH_1):GND
   35  GND            VSS13  @S9S_MB_2U_LIB.S9S_MB_2U(SCH_1):GND
   32  GND            VSS12  @S9S_MB_2U_LIB.S9S_MB_2U(SCH_1):GND
   30  GND            VSS11  @S9S_MB_2U_LIB.S9S_MB_2U(SCH_1):GND
   28  GND            VSS10  @S9S_MB_2U_LIB.S9S_MB_2U(SCH_1):GND
   26  GND             VSS9  @S9S_MB_2U_LIB.S9S_MB_2U(SCH_1):GND
   24  GND             VSS8  @S9S_MB_2U_LIB.S9S_MB_2U(SCH_1):GND
   21  GND             VSS7  @S9S_MB_2U_LIB.S9S_MB_2U(SCH_1):GND
   19  GND             VSS6  @S9S_MB_2U_LIB.S9S_MB_2U(SCH_1):GND
   17  GND             VSS5  @S9S_MB_2U_LIB.S9S_MB_2U(SCH_1):GND
   15  GND             VSS4  @S9S_MB_2U_LIB.S9S_MB_2U(SCH_1):GND
   13  GND             VSS3  @S9S_MB_2U_LIB.S9S_MB_2U(SCH_1):GND
   10  GND             VSS2  @S9S_MB_2U_LIB.S9S_MB_2U(SCH_1):GND
    8  GND             VSS1  @S9S_MB_2U_LIB.S9S_MB_2U(SCH_1):GND
    6  GND             VSS0  @S9S_MB_2U_LIB.S9S_MB_2U(SCH_1):GND
   G3  GND               G3  @S9S_MB_2U_LIB.S9S_MB_2U(SCH_1):GND
   G2  GND               G2  @S9S_MB_2U_LIB.S9S_MB_2U(SCH_1):GND
   G1  GND               G1  @S9S_MB_2U_LIB.S9S_MB_2U(SCH_1):GND

SCONN288_ADR50001P003C01  I124  J8     [SCONN288_ADR50001P003C01-SCONNA]
   93  M_D_CPU0_SB_DQS_DP<9>  DQS9_B_P  @S9S_MB_2U_LIB.S9S_MB_2U(SCH_1):M_D_CPU0_SB_DQS_DP<9>
  283  M_D_CPU0_SB_DQS_DP<8>  DQS8_B_P  @S9S_MB_2U_LIB.S9S_MB_2U(SCH_1):M_D_CPU0_SB_DQS_DP<8>
  272  M_D_CPU0_SB_DQS_DP<7>  DQS7_B_P  @S9S_MB_2U_LIB.S9S_MB_2U(SCH_1):M_D_CPU0_SB_DQS_DP<7>
  261  M_D_CPU0_SB_DQS_DP<6>  DQS6_B_P  @S9S_MB_2U_LIB.S9S_MB_2U(SCH_1):M_D_CPU0_SB_DQS_DP<6>
  250  M_D_CPU0_SB_DQS_DP<5>  DQS5_B_P  @S9S_MB_2U_LIB.S9S_MB_2U(SCH_1):M_D_CPU0_SB_DQS_DP<5>
  239  M_D_CPU0_SB_DQS_DP<4>  DQS4_B_P  @S9S_MB_2U_LIB.S9S_MB_2U(SCH_1):M_D_CPU0_SB_DQS_DP<4>
  137  M_D_CPU0_SB_DQS_DP<3>  DQS3_B_P  @S9S_MB_2U_LIB.S9S_MB_2U(SCH_1):M_D_CPU0_SB_DQS_DP<3>
  126  M_D_CPU0_SB_DQS_DP<2>  DQS2_B_P  @S9S_MB_2U_LIB.S9S_MB_2U(SCH_1):M_D_CPU0_SB_DQS_DP<2>
  115  M_D_CPU0_SB_DQS_DP<1>  DQS1_B_P  @S9S_MB_2U_LIB.S9S_MB_2U(SCH_1):M_D_CPU0_SB_DQS_DP<1>
  104  M_D_CPU0_SB_DQS_DP<0>  DQS0_B_P  @S9S_MB_2U_LIB.S9S_MB_2U(SCH_1):M_D_CPU0_SB_DQS_DP<0>
   94  M_D_CPU0_SB_DQS_DN<9>  DQS9_B_N  @S9S_MB_2U_LIB.S9S_MB_2U(SCH_1):M_D_CPU0_SB_DQS_DN<9>
  282  M_D_CPU0_SB_DQS_DN<8>  DQS8_B_N  @S9S_MB_2U_LIB.S9S_MB_2U(SCH_1):M_D_CPU0_SB_DQS_DN<8>
  271  M_D_CPU0_SB_DQS_DN<7>  DQS7_B_N  @S9S_MB_2U_LIB.S9S_MB_2U(SCH_1):M_D_CPU0_SB_DQS_DN<7>
  260  M_D_CPU0_SB_DQS_DN<6>  DQS6_B_N  @S9S_MB_2U_LIB.S9S_MB_2U(SCH_1):M_D_CPU0_SB_DQS_DN<6>
  249  M_D_CPU0_SB_DQS_DN<5>  DQS5_B_N  @S9S_MB_2U_LIB.S9S_MB_2U(SCH_1):M_D_CPU0_SB_DQS_DN<5>
  238  M_D_CPU0_SB_DQS_DN<4>  DQS4_B_N  @S9S_MB_2U_LIB.S9S_MB_2U(SCH_1):M_D_CPU0_SB_DQS_DN<4>
  138  M_D_CPU0_SB_DQS_DN<3>  DQS3_B_N  @S9S_MB_2U_LIB.S9S_MB_2U(SCH_1):M_D_CPU0_SB_DQS_DN<3>
  127  M_D_CPU0_SB_DQS_DN<2>  DQS2_B_N  @S9S_MB_2U_LIB.S9S_MB_2U(SCH_1):M_D_CPU0_SB_DQS_DN<2>
  116  M_D_CPU0_SB_DQS_DN<1>  DQS1_B_N  @S9S_MB_2U_LIB.S9S_MB_2U(SCH_1):M_D_CPU0_SB_DQS_DN<1>
  105  M_D_CPU0_SB_DQS_DN<0>  DQS0_B_N  @S9S_MB_2U_LIB.S9S_MB_2U(SCH_1):M_D_CPU0_SB_DQS_DN<0>
  201  M_D_CPU0_SA_DQS_DP<9>  DQS9_A_P  @S9S_MB_2U_LIB.S9S_MB_2U(SCH_1):M_D_CPU0_SA_DQS_DP<9>
  190  M_D_CPU0_SA_DQS_DP<8>  DQS8_A_P  @S9S_MB_2U_LIB.S9S_MB_2U(SCH_1):M_D_CPU0_SA_DQS_DP<8>
  179  M_D_CPU0_SA_DQS_DP<7>  DQS7_A_P  @S9S_MB_2U_LIB.S9S_MB_2U(SCH_1):M_D_CPU0_SA_DQS_DP<7>
  168  M_D_CPU0_SA_DQS_DP<6>  DQS6_A_P  @S9S_MB_2U_LIB.S9S_MB_2U(SCH_1):M_D_CPU0_SA_DQS_DP<6>
  157  M_D_CPU0_SA_DQS_DP<5>  DQS5_A_P  @S9S_MB_2U_LIB.S9S_MB_2U(SCH_1):M_D_CPU0_SA_DQS_DP<5>
   55  M_D_CPU0_SA_DQS_DP<4>  DQS4_A_P  @S9S_MB_2U_LIB.S9S_MB_2U(SCH_1):M_D_CPU0_SA_DQS_DP<4>
   44  M_D_CPU0_SA_DQS_DP<3>  DQS3_A_P  @S9S_MB_2U_LIB.S9S_MB_2U(SCH_1):M_D_CPU0_SA_DQS_DP<3>
   33  M_D_CPU0_SA_DQS_DP<2>  DQS2_A_P  @S9S_MB_2U_LIB.S9S_MB_2U(SCH_1):M_D_CPU0_SA_DQS_DP<2>
   22  M_D_CPU0_SA_DQS_DP<1>  DQS1_A_P  @S9S_MB_2U_LIB.S9S_MB_2U(SCH_1):M_D_CPU0_SA_DQS_DP<1>
   11  M_D_CPU0_SA_DQS_DP<0>  DQS0_A_P  @S9S_MB_2U_LIB.S9S_MB_2U(SCH_1):M_D_CPU0_SA_DQS_DP<0>
  200  M_D_CPU0_SA_DQS_DN<9>  DQS9_A_N  @S9S_MB_2U_LIB.S9S_MB_2U(SCH_1):M_D_CPU0_SA_DQS_DN<9>
  189  M_D_CPU0_SA_DQS_DN<8>  DQS8_A_N  @S9S_MB_2U_LIB.S9S_MB_2U(SCH_1):M_D_CPU0_SA_DQS_DN<8>
  178  M_D_CPU0_SA_DQS_DN<7>  DQS7_A_N  @S9S_MB_2U_LIB.S9S_MB_2U(SCH_1):M_D_CPU0_SA_DQS_DN<7>
  167  M_D_CPU0_SA_DQS_DN<6>  DQS6_A_N  @S9S_MB_2U_LIB.S9S_MB_2U(SCH_1):M_D_CPU0_SA_DQS_DN<6>
  156  M_D_CPU0_SA_DQS_DN<5>  DQS5_A_N  @S9S_MB_2U_LIB.S9S_MB_2U(SCH_1):M_D_CPU0_SA_DQS_DN<5>
   56  M_D_CPU0_SA_DQS_DN<4>  DQS4_A_N  @S9S_MB_2U_LIB.S9S_MB_2U(SCH_1):M_D_CPU0_SA_DQS_DN<4>
   45  M_D_CPU0_SA_DQS_DN<3>  DQS3_A_N  @S9S_MB_2U_LIB.S9S_MB_2U(SCH_1):M_D_CPU0_SA_DQS_DN<3>
   34  M_D_CPU0_SA_DQS_DN<2>  DQS2_A_N  @S9S_MB_2U_LIB.S9S_MB_2U(SCH_1):M_D_CPU0_SA_DQS_DN<2>
   23  M_D_CPU0_SA_DQS_DN<1>  DQS1_A_N  @S9S_MB_2U_LIB.S9S_MB_2U(SCH_1):M_D_CPU0_SA_DQS_DN<1>
   12  M_D_CPU0_SA_DQS_DN<0>  DQS0_A_N  @S9S_MB_2U_LIB.S9S_MB_2U(SCH_1):M_D_CPU0_SA_DQS_DN<0>

SCONN288_ADR50001P003C01  I50  J8     [SCONN288_ADR50001P003C01-SCONNA]
  232  NC              RFU6  NC
  231  NC              RFU5  NC
  220  NC              RFU4  NC
  150  NC              RFU3  NC
  149  NC              RFU2  NC
  144  NC              RFU1  NC
    2  NC              RFU0  NC
  207  RST_M_CD_CPU0_FPGA_N  RESET_N  @S9S_MB_2U_LIB.S9S_MB_2U(SCH_1):RST_M_CD_CPU0_FPGA_N
  147  PWRGD_CHD_CPU0_DIMM2  PWR_GOOD||FAIL_N  @S9S_MB_2U_LIB.S9S_MB_2U(SCH_1):PWRGD_CHD_CPU0_DIMM2
  148  PD_CHD_CPU0_DIMM2_SAA    HAS  @S9S_MB_2U_LIB.S9S_MB_2U(SCH_1):PD_CHD_CPU0_DIMM2_SAA
    3  P3V3_AUX       VIN_MGMT  @S9S_MB_2U_LIB.S9S_MB_2U(SCH_1):P3V3_AUX
   87  M_D_CPU0_SB_RSP<1>  LBS||RSP_N_B  @S9S_MB_2U_LIB.S9S_MB_2U(SCH_1):M_D_CPU0_SB_RSP<1>
  227  M_D_CPU0_SB_PAR  PAR_B  @S9S_MB_2U_LIB.S9S_MB_2U(SCH_1):M_D_CPU0_SB_PAR
  113  M_D_CPU0_SB_DQ<9>  DQ_B9  @S9S_MB_2U_LIB.S9S_MB_2U(SCH_1):M_D_CPU0_SB_DQ<9>
  111  M_D_CPU0_SB_DQ<8>  DQ_B8  @S9S_MB_2U_LIB.S9S_MB_2U(SCH_1):M_D_CPU0_SB_DQ<8>
  254  M_D_CPU0_SB_DQ<7>  DQ_B7  @S9S_MB_2U_LIB.S9S_MB_2U(SCH_1):M_D_CPU0_SB_DQ<7>
  252  M_D_CPU0_SB_DQ<6>  DQ_B6  @S9S_MB_2U_LIB.S9S_MB_2U(SCH_1):M_D_CPU0_SB_DQ<6>
  109  M_D_CPU0_SB_DQ<5>  DQ_B5  @S9S_MB_2U_LIB.S9S_MB_2U(SCH_1):M_D_CPU0_SB_DQ<5>
  107  M_D_CPU0_SB_DQ<4>  DQ_B4  @S9S_MB_2U_LIB.S9S_MB_2U(SCH_1):M_D_CPU0_SB_DQ<4>
  247  M_D_CPU0_SB_DQ<3>  DQ_B3  @S9S_MB_2U_LIB.S9S_MB_2U(SCH_1):M_D_CPU0_SB_DQ<3>
  287  M_D_CPU0_SB_DQ<31>  DQ_B31  @S9S_MB_2U_LIB.S9S_MB_2U(SCH_1):M_D_CPU0_SB_DQ<31>
  285  M_D_CPU0_SB_DQ<30>  DQ_B30  @S9S_MB_2U_LIB.S9S_MB_2U(SCH_1):M_D_CPU0_SB_DQ<30>
  245  M_D_CPU0_SB_DQ<2>  DQ_B2  @S9S_MB_2U_LIB.S9S_MB_2U(SCH_1):M_D_CPU0_SB_DQ<2>
  142  M_D_CPU0_SB_DQ<29>  DQ_B29  @S9S_MB_2U_LIB.S9S_MB_2U(SCH_1):M_D_CPU0_SB_DQ<29>
  140  M_D_CPU0_SB_DQ<28>  DQ_B28  @S9S_MB_2U_LIB.S9S_MB_2U(SCH_1):M_D_CPU0_SB_DQ<28>
  280  M_D_CPU0_SB_DQ<27>  DQ_B27  @S9S_MB_2U_LIB.S9S_MB_2U(SCH_1):M_D_CPU0_SB_DQ<27>
  278  M_D_CPU0_SB_DQ<26>  DQ_B26  @S9S_MB_2U_LIB.S9S_MB_2U(SCH_1):M_D_CPU0_SB_DQ<26>
  135  M_D_CPU0_SB_DQ<25>  DQ_B25  @S9S_MB_2U_LIB.S9S_MB_2U(SCH_1):M_D_CPU0_SB_DQ<25>
  133  M_D_CPU0_SB_DQ<24>  DQ_B24  @S9S_MB_2U_LIB.S9S_MB_2U(SCH_1):M_D_CPU0_SB_DQ<24>
  276  M_D_CPU0_SB_DQ<23>  DQ_B23  @S9S_MB_2U_LIB.S9S_MB_2U(SCH_1):M_D_CPU0_SB_DQ<23>
  274  M_D_CPU0_SB_DQ<22>  DQ_B22  @S9S_MB_2U_LIB.S9S_MB_2U(SCH_1):M_D_CPU0_SB_DQ<22>
  131  M_D_CPU0_SB_DQ<21>  DQ_B21  @S9S_MB_2U_LIB.S9S_MB_2U(SCH_1):M_D_CPU0_SB_DQ<21>
  129  M_D_CPU0_SB_DQ<20>  DQ_B20  @S9S_MB_2U_LIB.S9S_MB_2U(SCH_1):M_D_CPU0_SB_DQ<20>
  102  M_D_CPU0_SB_DQ<1>  DQ_B1  @S9S_MB_2U_LIB.S9S_MB_2U(SCH_1):M_D_CPU0_SB_DQ<1>
  269  M_D_CPU0_SB_DQ<19>  DQ_B19  @S9S_MB_2U_LIB.S9S_MB_2U(SCH_1):M_D_CPU0_SB_DQ<19>
  267  M_D_CPU0_SB_DQ<18>  DQ_B18  @S9S_MB_2U_LIB.S9S_MB_2U(SCH_1):M_D_CPU0_SB_DQ<18>
  124  M_D_CPU0_SB_DQ<17>  DQ_B17  @S9S_MB_2U_LIB.S9S_MB_2U(SCH_1):M_D_CPU0_SB_DQ<17>
  122  M_D_CPU0_SB_DQ<16>  DQ_B16  @S9S_MB_2U_LIB.S9S_MB_2U(SCH_1):M_D_CPU0_SB_DQ<16>
  265  M_D_CPU0_SB_DQ<15>  DQ_B15  @S9S_MB_2U_LIB.S9S_MB_2U(SCH_1):M_D_CPU0_SB_DQ<15>
  263  M_D_CPU0_SB_DQ<14>  DQ_B14  @S9S_MB_2U_LIB.S9S_MB_2U(SCH_1):M_D_CPU0_SB_DQ<14>
  120  M_D_CPU0_SB_DQ<13>  DQ_B13  @S9S_MB_2U_LIB.S9S_MB_2U(SCH_1):M_D_CPU0_SB_DQ<13>
  118  M_D_CPU0_SB_DQ<12>  DQ_B12  @S9S_MB_2U_LIB.S9S_MB_2U(SCH_1):M_D_CPU0_SB_DQ<12>
  258  M_D_CPU0_SB_DQ<11>  DQ_B11  @S9S_MB_2U_LIB.S9S_MB_2U(SCH_1):M_D_CPU0_SB_DQ<11>
  256  M_D_CPU0_SB_DQ<10>  DQ_B10  @S9S_MB_2U_LIB.S9S_MB_2U(SCH_1):M_D_CPU0_SB_DQ<10>
  100  M_D_CPU0_SB_DQ<0>  DQ_B0  @S9S_MB_2U_LIB.S9S_MB_2U(SCH_1):M_D_CPU0_SB_DQ<0>
  229  M_D_CPU0_SB_CS_N<3>  CS1_N_B  @S9S_MB_2U_LIB.S9S_MB_2U(SCH_1):M_D_CPU0_SB_CS_N<3>
   84  M_D_CPU0_SB_CS_N<2>  CS0_N_B  @S9S_MB_2U_LIB.S9S_MB_2U(SCH_1):M_D_CPU0_SB_CS_N<2>
  236  M_D_CPU0_SB_CB<7>  CB_B7  @S9S_MB_2U_LIB.S9S_MB_2U(SCH_1):M_D_CPU0_SB_CB<7>
  234  M_D_CPU0_SB_CB<6>  CB_B6  @S9S_MB_2U_LIB.S9S_MB_2U(SCH_1):M_D_CPU0_SB_CB<6>
   91  M_D_CPU0_SB_CB<5>  CB_B5  @S9S_MB_2U_LIB.S9S_MB_2U(SCH_1):M_D_CPU0_SB_CB<5>
   89  M_D_CPU0_SB_CB<4>  CB_B4  @S9S_MB_2U_LIB.S9S_MB_2U(SCH_1):M_D_CPU0_SB_CB<4>
  243  M_D_CPU0_SB_CB<3>  CB_B3  @S9S_MB_2U_LIB.S9S_MB_2U(SCH_1):M_D_CPU0_SB_CB<3>
  241  M_D_CPU0_SB_CB<2>  CB_B2  @S9S_MB_2U_LIB.S9S_MB_2U(SCH_1):M_D_CPU0_SB_CB<2>
   98  M_D_CPU0_SB_CB<1>  CB_B1  @S9S_MB_2U_LIB.S9S_MB_2U(SCH_1):M_D_CPU0_SB_CB<1>
   96  M_D_CPU0_SB_CB<0>  CB_B0  @S9S_MB_2U_LIB.S9S_MB_2U(SCH_1):M_D_CPU0_SB_CB<0>
   82  M_D_CPU0_SB_CA<6>  CA6_B  @S9S_MB_2U_LIB.S9S_MB_2U(SCH_1):M_D_CPU0_SB_CA<6>
  225  M_D_CPU0_SB_CA<5>  CA5_B  @S9S_MB_2U_LIB.S9S_MB_2U(SCH_1):M_D_CPU0_SB_CA<5>
   80  M_D_CPU0_SB_CA<4>  CA4_B  @S9S_MB_2U_LIB.S9S_MB_2U(SCH_1):M_D_CPU0_SB_CA<4>
  223  M_D_CPU0_SB_CA<3>  CA3_B  @S9S_MB_2U_LIB.S9S_MB_2U(SCH_1):M_D_CPU0_SB_CA<3>
   78  M_D_CPU0_SB_CA<2>  CA2_B  @S9S_MB_2U_LIB.S9S_MB_2U(SCH_1):M_D_CPU0_SB_CA<2>
  221  M_D_CPU0_SB_CA<1>  CA1_B  @S9S_MB_2U_LIB.S9S_MB_2U(SCH_1):M_D_CPU0_SB_CA<1>
   76  M_D_CPU0_SB_CA<0>  CA0_B  @S9S_MB_2U_LIB.S9S_MB_2U(SCH_1):M_D_CPU0_SB_CA<0>
   86  M_D_CPU0_SA_RSP<1>  LBD||RSP_N_A  @S9S_MB_2U_LIB.S9S_MB_2U(SCH_1):M_D_CPU0_SA_RSP<1>
   74  M_D_CPU0_SA_PAR  PAR_A  @S9S_MB_2U_LIB.S9S_MB_2U(SCH_1):M_D_CPU0_SA_PAR
   20  M_D_CPU0_SA_DQ<9>  DQ_A9  @S9S_MB_2U_LIB.S9S_MB_2U(SCH_1):M_D_CPU0_SA_DQ<9>
   18  M_D_CPU0_SA_DQ<8>  DQ_A8  @S9S_MB_2U_LIB.S9S_MB_2U(SCH_1):M_D_CPU0_SA_DQ<8>
  161  M_D_CPU0_SA_DQ<7>  DQ_A7  @S9S_MB_2U_LIB.S9S_MB_2U(SCH_1):M_D_CPU0_SA_DQ<7>
  159  M_D_CPU0_SA_DQ<6>  DQ_A6  @S9S_MB_2U_LIB.S9S_MB_2U(SCH_1):M_D_CPU0_SA_DQ<6>
   16  M_D_CPU0_SA_DQ<5>  DQ_A5  @S9S_MB_2U_LIB.S9S_MB_2U(SCH_1):M_D_CPU0_SA_DQ<5>
   14  M_D_CPU0_SA_DQ<4>  DQ_A4  @S9S_MB_2U_LIB.S9S_MB_2U(SCH_1):M_D_CPU0_SA_DQ<4>
  154  M_D_CPU0_SA_DQ<3>  DQ_A3  @S9S_MB_2U_LIB.S9S_MB_2U(SCH_1):M_D_CPU0_SA_DQ<3>
  194  M_D_CPU0_SA_DQ<31>  DQ_A31  @S9S_MB_2U_LIB.S9S_MB_2U(SCH_1):M_D_CPU0_SA_DQ<31>
  192  M_D_CPU0_SA_DQ<30>  DQ_A30  @S9S_MB_2U_LIB.S9S_MB_2U(SCH_1):M_D_CPU0_SA_DQ<30>
  152  M_D_CPU0_SA_DQ<2>  DQ_A2  @S9S_MB_2U_LIB.S9S_MB_2U(SCH_1):M_D_CPU0_SA_DQ<2>
   49  M_D_CPU0_SA_DQ<29>  DQ_A29  @S9S_MB_2U_LIB.S9S_MB_2U(SCH_1):M_D_CPU0_SA_DQ<29>
   47  M_D_CPU0_SA_DQ<28>  DQ_A28  @S9S_MB_2U_LIB.S9S_MB_2U(SCH_1):M_D_CPU0_SA_DQ<28>
  187  M_D_CPU0_SA_DQ<27>  DQ_A27  @S9S_MB_2U_LIB.S9S_MB_2U(SCH_1):M_D_CPU0_SA_DQ<27>
  185  M_D_CPU0_SA_DQ<26>  DQ_A26  @S9S_MB_2U_LIB.S9S_MB_2U(SCH_1):M_D_CPU0_SA_DQ<26>
   42  M_D_CPU0_SA_DQ<25>  DQ_A25  @S9S_MB_2U_LIB.S9S_MB_2U(SCH_1):M_D_CPU0_SA_DQ<25>
   40  M_D_CPU0_SA_DQ<24>  DQ_A24  @S9S_MB_2U_LIB.S9S_MB_2U(SCH_1):M_D_CPU0_SA_DQ<24>
  183  M_D_CPU0_SA_DQ<23>  DQ_A23  @S9S_MB_2U_LIB.S9S_MB_2U(SCH_1):M_D_CPU0_SA_DQ<23>
  181  M_D_CPU0_SA_DQ<22>  DQ_A22  @S9S_MB_2U_LIB.S9S_MB_2U(SCH_1):M_D_CPU0_SA_DQ<22>
   38  M_D_CPU0_SA_DQ<21>  DQ_A21  @S9S_MB_2U_LIB.S9S_MB_2U(SCH_1):M_D_CPU0_SA_DQ<21>
   36  M_D_CPU0_SA_DQ<20>  DQ_A20  @S9S_MB_2U_LIB.S9S_MB_2U(SCH_1):M_D_CPU0_SA_DQ<20>
    9  M_D_CPU0_SA_DQ<1>  DQ_A1  @S9S_MB_2U_LIB.S9S_MB_2U(SCH_1):M_D_CPU0_SA_DQ<1>
  176  M_D_CPU0_SA_DQ<19>  DQ_A19  @S9S_MB_2U_LIB.S9S_MB_2U(SCH_1):M_D_CPU0_SA_DQ<19>
  174  M_D_CPU0_SA_DQ<18>  DQ_A18  @S9S_MB_2U_LIB.S9S_MB_2U(SCH_1):M_D_CPU0_SA_DQ<18>
   31  M_D_CPU0_SA_DQ<17>  DQ_A17  @S9S_MB_2U_LIB.S9S_MB_2U(SCH_1):M_D_CPU0_SA_DQ<17>
   29  M_D_CPU0_SA_DQ<16>  DQ_A16  @S9S_MB_2U_LIB.S9S_MB_2U(SCH_1):M_D_CPU0_SA_DQ<16>
  172  M_D_CPU0_SA_DQ<15>  DQ_A15  @S9S_MB_2U_LIB.S9S_MB_2U(SCH_1):M_D_CPU0_SA_DQ<15>
  170  M_D_CPU0_SA_DQ<14>  DQ_A14  @S9S_MB_2U_LIB.S9S_MB_2U(SCH_1):M_D_CPU0_SA_DQ<14>
   27  M_D_CPU0_SA_DQ<13>  DQ_A13  @S9S_MB_2U_LIB.S9S_MB_2U(SCH_1):M_D_CPU0_SA_DQ<13>
   25  M_D_CPU0_SA_DQ<12>  DQ_A12  @S9S_MB_2U_LIB.S9S_MB_2U(SCH_1):M_D_CPU0_SA_DQ<12>
  165  M_D_CPU0_SA_DQ<11>  DQ_A11  @S9S_MB_2U_LIB.S9S_MB_2U(SCH_1):M_D_CPU0_SA_DQ<11>
  163  M_D_CPU0_SA_DQ<10>  DQ_A10  @S9S_MB_2U_LIB.S9S_MB_2U(SCH_1):M_D_CPU0_SA_DQ<10>
    7  M_D_CPU0_SA_DQ<0>  DQ_A0  @S9S_MB_2U_LIB.S9S_MB_2U(SCH_1):M_D_CPU0_SA_DQ<0>
  209  M_D_CPU0_SA_CS_N<3>  CS1_N_A  @S9S_MB_2U_LIB.S9S_MB_2U(SCH_1):M_D_CPU0_SA_CS_N<3>
   64  M_D_CPU0_SA_CS_N<2>  CS0_N_A  @S9S_MB_2U_LIB.S9S_MB_2U(SCH_1):M_D_CPU0_SA_CS_N<2>
  205  M_D_CPU0_SA_CB<7>  CB_A7  @S9S_MB_2U_LIB.S9S_MB_2U(SCH_1):M_D_CPU0_SA_CB<7>
  203  M_D_CPU0_SA_CB<6>  CB_A6  @S9S_MB_2U_LIB.S9S_MB_2U(SCH_1):M_D_CPU0_SA_CB<6>
   60  M_D_CPU0_SA_CB<5>  CB_A5  @S9S_MB_2U_LIB.S9S_MB_2U(SCH_1):M_D_CPU0_SA_CB<5>
   58  M_D_CPU0_SA_CB<4>  CB_A4  @S9S_MB_2U_LIB.S9S_MB_2U(SCH_1):M_D_CPU0_SA_CB<4>
  198  M_D_CPU0_SA_CB<3>  CB_A3  @S9S_MB_2U_LIB.S9S_MB_2U(SCH_1):M_D_CPU0_SA_CB<3>
  196  M_D_CPU0_SA_CB<2>  CB_A2  @S9S_MB_2U_LIB.S9S_MB_2U(SCH_1):M_D_CPU0_SA_CB<2>
   53  M_D_CPU0_SA_CB<1>  CB_A1  @S9S_MB_2U_LIB.S9S_MB_2U(SCH_1):M_D_CPU0_SA_CB<1>
   51  M_D_CPU0_SA_CB<0>  CB_A0  @S9S_MB_2U_LIB.S9S_MB_2U(SCH_1):M_D_CPU0_SA_CB<0>
   72  M_D_CPU0_SA_CA<6>  CA6_A  @S9S_MB_2U_LIB.S9S_MB_2U(SCH_1):M_D_CPU0_SA_CA<6>
  215  M_D_CPU0_SA_CA<5>  CA5_A  @S9S_MB_2U_LIB.S9S_MB_2U(SCH_1):M_D_CPU0_SA_CA<5>
   70  M_D_CPU0_SA_CA<4>  CA4_A  @S9S_MB_2U_LIB.S9S_MB_2U(SCH_1):M_D_CPU0_SA_CA<4>
  213  M_D_CPU0_SA_CA<3>  CA3_A  @S9S_MB_2U_LIB.S9S_MB_2U(SCH_1):M_D_CPU0_SA_CA<3>
   68  M_D_CPU0_SA_CA<2>  CA2_A  @S9S_MB_2U_LIB.S9S_MB_2U(SCH_1):M_D_CPU0_SA_CA<2>
  211  M_D_CPU0_SA_CA<1>  CA1_A  @S9S_MB_2U_LIB.S9S_MB_2U(SCH_1):M_D_CPU0_SA_CA<1>
   66  M_D_CPU0_SA_CA<0>  CA0_A  @S9S_MB_2U_LIB.S9S_MB_2U(SCH_1):M_D_CPU0_SA_CA<0>
  217  M_D_CPU0_CLK_DP<1>   CK_P  @S9S_MB_2U_LIB.S9S_MB_2U(SCH_1):M_D_CPU0_CLK_DP<1>
  218  M_D_CPU0_CLK_DN<1>   CK_N  @S9S_MB_2U_LIB.S9S_MB_2U(SCH_1):M_D_CPU0_CLK_DN<1>
   62  M_D_CPU0_ALERT_N  ALERT_N  @S9S_MB_2U_LIB.S9S_MB_2U(SCH_1):M_D_CPU0_ALERT_N
    5  I3C_SPD_DDRABCD_CPU0_LVC1_SDA   HSDA  @S9S_MB_2U_LIB.S9S_MB_2U(SCH_1):I3C_SPD_DDRABCD_CPU0_LVC1_SDA
    4  I3C_SPD_DDRABCD_CPU0_LVC1_SCL   HSCL  @S9S_MB_2U_LIB.S9S_MB_2U(SCH_1):I3C_SPD_DDRABCD_CPU0_LVC1_SCL

SCONN288_ADR50001P013C01  I147  J9     [SCONN288_ADR50001P013C01-SCONNA]
  146  P12V_S3_AUX_CPU0_NVDIMM  VIN_BULK2  @S9S_MB_2U_LIB.S9S_MB_2U(SCH_1):P12V_S3_AUX_CPU0_NVDIMM
  145  P12V_S3_AUX_CPU0_NVDIMM  VIN_BULK1  @S9S_MB_2U_LIB.S9S_MB_2U(SCH_1):P12V_S3_AUX_CPU0_NVDIMM
    1  P12V_S3_AUX_CPU0_NVDIMM  VIN_BULK0  @S9S_MB_2U_LIB.S9S_MB_2U(SCH_1):P12V_S3_AUX_CPU0_NVDIMM
  288  GND            VSS126  @S9S_MB_2U_LIB.S9S_MB_2U(SCH_1):GND
  286  GND            VSS125  @S9S_MB_2U_LIB.S9S_MB_2U(SCH_1):GND
  284  GND            VSS124  @S9S_MB_2U_LIB.S9S_MB_2U(SCH_1):GND
  281  GND            VSS123  @S9S_MB_2U_LIB.S9S_MB_2U(SCH_1):GND
  279  GND            VSS122  @S9S_MB_2U_LIB.S9S_MB_2U(SCH_1):GND
  277  GND            VSS121  @S9S_MB_2U_LIB.S9S_MB_2U(SCH_1):GND
  275  GND            VSS120  @S9S_MB_2U_LIB.S9S_MB_2U(SCH_1):GND
  273  GND            VSS119  @S9S_MB_2U_LIB.S9S_MB_2U(SCH_1):GND
  270  GND            VSS118  @S9S_MB_2U_LIB.S9S_MB_2U(SCH_1):GND
  268  GND            VSS117  @S9S_MB_2U_LIB.S9S_MB_2U(SCH_1):GND
  266  GND            VSS116  @S9S_MB_2U_LIB.S9S_MB_2U(SCH_1):GND
  264  GND            VSS115  @S9S_MB_2U_LIB.S9S_MB_2U(SCH_1):GND
  262  GND            VSS114  @S9S_MB_2U_LIB.S9S_MB_2U(SCH_1):GND
  259  GND            VSS113  @S9S_MB_2U_LIB.S9S_MB_2U(SCH_1):GND
  257  GND            VSS112  @S9S_MB_2U_LIB.S9S_MB_2U(SCH_1):GND
  255  GND            VSS111  @S9S_MB_2U_LIB.S9S_MB_2U(SCH_1):GND
  253  GND            VSS110  @S9S_MB_2U_LIB.S9S_MB_2U(SCH_1):GND
  251  GND            VSS109  @S9S_MB_2U_LIB.S9S_MB_2U(SCH_1):GND
  248  GND            VSS108  @S9S_MB_2U_LIB.S9S_MB_2U(SCH_1):GND
  246  GND            VSS107  @S9S_MB_2U_LIB.S9S_MB_2U(SCH_1):GND
  244  GND            VSS106  @S9S_MB_2U_LIB.S9S_MB_2U(SCH_1):GND
  242  GND            VSS105  @S9S_MB_2U_LIB.S9S_MB_2U(SCH_1):GND
  240  GND            VSS104  @S9S_MB_2U_LIB.S9S_MB_2U(SCH_1):GND
  237  GND            VSS103  @S9S_MB_2U_LIB.S9S_MB_2U(SCH_1):GND
  235  GND            VSS102  @S9S_MB_2U_LIB.S9S_MB_2U(SCH_1):GND
  233  GND            VSS101  @S9S_MB_2U_LIB.S9S_MB_2U(SCH_1):GND
  230  GND            VSS100  @S9S_MB_2U_LIB.S9S_MB_2U(SCH_1):GND
  228  GND            VSS99  @S9S_MB_2U_LIB.S9S_MB_2U(SCH_1):GND
  226  GND            VSS98  @S9S_MB_2U_LIB.S9S_MB_2U(SCH_1):GND
  224  GND            VSS97  @S9S_MB_2U_LIB.S9S_MB_2U(SCH_1):GND
  222  GND            VSS96  @S9S_MB_2U_LIB.S9S_MB_2U(SCH_1):GND
  219  GND            VSS95  @S9S_MB_2U_LIB.S9S_MB_2U(SCH_1):GND
  216  GND            VSS94  @S9S_MB_2U_LIB.S9S_MB_2U(SCH_1):GND
  214  GND            VSS93  @S9S_MB_2U_LIB.S9S_MB_2U(SCH_1):GND
  212  GND            VSS92  @S9S_MB_2U_LIB.S9S_MB_2U(SCH_1):GND
  210  GND            VSS91  @S9S_MB_2U_LIB.S9S_MB_2U(SCH_1):GND
  208  GND            VSS90  @S9S_MB_2U_LIB.S9S_MB_2U(SCH_1):GND
  206  GND            VSS89  @S9S_MB_2U_LIB.S9S_MB_2U(SCH_1):GND
  204  GND            VSS88  @S9S_MB_2U_LIB.S9S_MB_2U(SCH_1):GND
  202  GND            VSS87  @S9S_MB_2U_LIB.S9S_MB_2U(SCH_1):GND
  199  GND            VSS86  @S9S_MB_2U_LIB.S9S_MB_2U(SCH_1):GND
  197  GND            VSS85  @S9S_MB_2U_LIB.S9S_MB_2U(SCH_1):GND
  195  GND            VSS84  @S9S_MB_2U_LIB.S9S_MB_2U(SCH_1):GND
  193  GND            VSS83  @S9S_MB_2U_LIB.S9S_MB_2U(SCH_1):GND
  191  GND            VSS82  @S9S_MB_2U_LIB.S9S_MB_2U(SCH_1):GND
  188  GND            VSS81  @S9S_MB_2U_LIB.S9S_MB_2U(SCH_1):GND
  186  GND            VSS80  @S9S_MB_2U_LIB.S9S_MB_2U(SCH_1):GND
  184  GND            VSS79  @S9S_MB_2U_LIB.S9S_MB_2U(SCH_1):GND
  182  GND            VSS78  @S9S_MB_2U_LIB.S9S_MB_2U(SCH_1):GND
  180  GND            VSS77  @S9S_MB_2U_LIB.S9S_MB_2U(SCH_1):GND
  177  GND            VSS76  @S9S_MB_2U_LIB.S9S_MB_2U(SCH_1):GND
  175  GND            VSS75  @S9S_MB_2U_LIB.S9S_MB_2U(SCH_1):GND
  173  GND            VSS74  @S9S_MB_2U_LIB.S9S_MB_2U(SCH_1):GND
  171  GND            VSS73  @S9S_MB_2U_LIB.S9S_MB_2U(SCH_1):GND
  169  GND            VSS72  @S9S_MB_2U_LIB.S9S_MB_2U(SCH_1):GND
  166  GND            VSS71  @S9S_MB_2U_LIB.S9S_MB_2U(SCH_1):GND
  164  GND            VSS70  @S9S_MB_2U_LIB.S9S_MB_2U(SCH_1):GND
  162  GND            VSS69  @S9S_MB_2U_LIB.S9S_MB_2U(SCH_1):GND
  160  GND            VSS68  @S9S_MB_2U_LIB.S9S_MB_2U(SCH_1):GND
  158  GND            VSS67  @S9S_MB_2U_LIB.S9S_MB_2U(SCH_1):GND
  155  GND            VSS66  @S9S_MB_2U_LIB.S9S_MB_2U(SCH_1):GND
  153  GND            VSS65  @S9S_MB_2U_LIB.S9S_MB_2U(SCH_1):GND
  151  GND            VSS64  @S9S_MB_2U_LIB.S9S_MB_2U(SCH_1):GND
  143  GND            VSS63  @S9S_MB_2U_LIB.S9S_MB_2U(SCH_1):GND
  141  GND            VSS62  @S9S_MB_2U_LIB.S9S_MB_2U(SCH_1):GND
  139  GND            VSS61  @S9S_MB_2U_LIB.S9S_MB_2U(SCH_1):GND
  136  GND            VSS60  @S9S_MB_2U_LIB.S9S_MB_2U(SCH_1):GND
  134  GND            VSS59  @S9S_MB_2U_LIB.S9S_MB_2U(SCH_1):GND
  132  GND            VSS58  @S9S_MB_2U_LIB.S9S_MB_2U(SCH_1):GND
  130  GND            VSS57  @S9S_MB_2U_LIB.S9S_MB_2U(SCH_1):GND
  128  GND            VSS56  @S9S_MB_2U_LIB.S9S_MB_2U(SCH_1):GND
  125  GND            VSS55  @S9S_MB_2U_LIB.S9S_MB_2U(SCH_1):GND
  123  GND            VSS54  @S9S_MB_2U_LIB.S9S_MB_2U(SCH_1):GND
  121  GND            VSS53  @S9S_MB_2U_LIB.S9S_MB_2U(SCH_1):GND
  119  GND            VSS52  @S9S_MB_2U_LIB.S9S_MB_2U(SCH_1):GND
  117  GND            VSS51  @S9S_MB_2U_LIB.S9S_MB_2U(SCH_1):GND
  114  GND            VSS50  @S9S_MB_2U_LIB.S9S_MB_2U(SCH_1):GND
  112  GND            VSS49  @S9S_MB_2U_LIB.S9S_MB_2U(SCH_1):GND
  110  GND            VSS48  @S9S_MB_2U_LIB.S9S_MB_2U(SCH_1):GND
  108  GND            VSS47  @S9S_MB_2U_LIB.S9S_MB_2U(SCH_1):GND
  106  GND            VSS46  @S9S_MB_2U_LIB.S9S_MB_2U(SCH_1):GND
  103  GND            VSS45  @S9S_MB_2U_LIB.S9S_MB_2U(SCH_1):GND
  101  GND            VSS44  @S9S_MB_2U_LIB.S9S_MB_2U(SCH_1):GND
   99  GND            VSS43  @S9S_MB_2U_LIB.S9S_MB_2U(SCH_1):GND
   97  GND            VSS42  @S9S_MB_2U_LIB.S9S_MB_2U(SCH_1):GND
   95  GND            VSS41  @S9S_MB_2U_LIB.S9S_MB_2U(SCH_1):GND
   92  GND            VSS40  @S9S_MB_2U_LIB.S9S_MB_2U(SCH_1):GND
   90  GND            VSS39  @S9S_MB_2U_LIB.S9S_MB_2U(SCH_1):GND
   88  GND            VSS38  @S9S_MB_2U_LIB.S9S_MB_2U(SCH_1):GND
   85  GND            VSS37  @S9S_MB_2U_LIB.S9S_MB_2U(SCH_1):GND
   83  GND            VSS36  @S9S_MB_2U_LIB.S9S_MB_2U(SCH_1):GND
   81  GND            VSS35  @S9S_MB_2U_LIB.S9S_MB_2U(SCH_1):GND
   79  GND            VSS34  @S9S_MB_2U_LIB.S9S_MB_2U(SCH_1):GND
   77  GND            VSS33  @S9S_MB_2U_LIB.S9S_MB_2U(SCH_1):GND
   75  GND            VSS32  @S9S_MB_2U_LIB.S9S_MB_2U(SCH_1):GND
   73  GND            VSS31  @S9S_MB_2U_LIB.S9S_MB_2U(SCH_1):GND
   71  GND            VSS30  @S9S_MB_2U_LIB.S9S_MB_2U(SCH_1):GND
   69  GND            VSS29  @S9S_MB_2U_LIB.S9S_MB_2U(SCH_1):GND
   67  GND            VSS28  @S9S_MB_2U_LIB.S9S_MB_2U(SCH_1):GND
   65  GND            VSS27  @S9S_MB_2U_LIB.S9S_MB_2U(SCH_1):GND
   63  GND            VSS26  @S9S_MB_2U_LIB.S9S_MB_2U(SCH_1):GND
   61  GND            VSS25  @S9S_MB_2U_LIB.S9S_MB_2U(SCH_1):GND
   59  GND            VSS24  @S9S_MB_2U_LIB.S9S_MB_2U(SCH_1):GND
   57  GND            VSS23  @S9S_MB_2U_LIB.S9S_MB_2U(SCH_1):GND
   54  GND            VSS22  @S9S_MB_2U_LIB.S9S_MB_2U(SCH_1):GND
   52  GND            VSS21  @S9S_MB_2U_LIB.S9S_MB_2U(SCH_1):GND
   50  GND            VSS20  @S9S_MB_2U_LIB.S9S_MB_2U(SCH_1):GND
   48  GND            VSS19  @S9S_MB_2U_LIB.S9S_MB_2U(SCH_1):GND
   46  GND            VSS18  @S9S_MB_2U_LIB.S9S_MB_2U(SCH_1):GND
   43  GND            VSS17  @S9S_MB_2U_LIB.S9S_MB_2U(SCH_1):GND
   41  GND            VSS16  @S9S_MB_2U_LIB.S9S_MB_2U(SCH_1):GND
   39  GND            VSS15  @S9S_MB_2U_LIB.S9S_MB_2U(SCH_1):GND
   37  GND            VSS14  @S9S_MB_2U_LIB.S9S_MB_2U(SCH_1):GND
   35  GND            VSS13  @S9S_MB_2U_LIB.S9S_MB_2U(SCH_1):GND
   32  GND            VSS12  @S9S_MB_2U_LIB.S9S_MB_2U(SCH_1):GND
   30  GND            VSS11  @S9S_MB_2U_LIB.S9S_MB_2U(SCH_1):GND
   28  GND            VSS10  @S9S_MB_2U_LIB.S9S_MB_2U(SCH_1):GND
   26  GND             VSS9  @S9S_MB_2U_LIB.S9S_MB_2U(SCH_1):GND
   24  GND             VSS8  @S9S_MB_2U_LIB.S9S_MB_2U(SCH_1):GND
   21  GND             VSS7  @S9S_MB_2U_LIB.S9S_MB_2U(SCH_1):GND
   19  GND             VSS6  @S9S_MB_2U_LIB.S9S_MB_2U(SCH_1):GND
   17  GND             VSS5  @S9S_MB_2U_LIB.S9S_MB_2U(SCH_1):GND
   15  GND             VSS4  @S9S_MB_2U_LIB.S9S_MB_2U(SCH_1):GND
   13  GND             VSS3  @S9S_MB_2U_LIB.S9S_MB_2U(SCH_1):GND
   10  GND             VSS2  @S9S_MB_2U_LIB.S9S_MB_2U(SCH_1):GND
    8  GND             VSS1  @S9S_MB_2U_LIB.S9S_MB_2U(SCH_1):GND
    6  GND             VSS0  @S9S_MB_2U_LIB.S9S_MB_2U(SCH_1):GND
   G3  GND               G3  @S9S_MB_2U_LIB.S9S_MB_2U(SCH_1):GND
   G2  GND               G2  @S9S_MB_2U_LIB.S9S_MB_2U(SCH_1):GND
   G1  GND               G1  @S9S_MB_2U_LIB.S9S_MB_2U(SCH_1):GND

SCONN288_ADR50001P013C01  I126  J9     [SCONN288_ADR50001P013C01-SCONNA]
   93  M_E_CPU0_SB_DQS_DP<9>  DQS9_B_P  @S9S_MB_2U_LIB.S9S_MB_2U(SCH_1):M_E_CPU0_SB_DQS_DP<9>
  283  M_E_CPU0_SB_DQS_DP<8>  DQS8_B_P  @S9S_MB_2U_LIB.S9S_MB_2U(SCH_1):M_E_CPU0_SB_DQS_DP<8>
  272  M_E_CPU0_SB_DQS_DP<7>  DQS7_B_P  @S9S_MB_2U_LIB.S9S_MB_2U(SCH_1):M_E_CPU0_SB_DQS_DP<7>
  261  M_E_CPU0_SB_DQS_DP<6>  DQS6_B_P  @S9S_MB_2U_LIB.S9S_MB_2U(SCH_1):M_E_CPU0_SB_DQS_DP<6>
  250  M_E_CPU0_SB_DQS_DP<5>  DQS5_B_P  @S9S_MB_2U_LIB.S9S_MB_2U(SCH_1):M_E_CPU0_SB_DQS_DP<5>
  239  M_E_CPU0_SB_DQS_DP<4>  DQS4_B_P  @S9S_MB_2U_LIB.S9S_MB_2U(SCH_1):M_E_CPU0_SB_DQS_DP<4>
  137  M_E_CPU0_SB_DQS_DP<3>  DQS3_B_P  @S9S_MB_2U_LIB.S9S_MB_2U(SCH_1):M_E_CPU0_SB_DQS_DP<3>
  126  M_E_CPU0_SB_DQS_DP<2>  DQS2_B_P  @S9S_MB_2U_LIB.S9S_MB_2U(SCH_1):M_E_CPU0_SB_DQS_DP<2>
  115  M_E_CPU0_SB_DQS_DP<1>  DQS1_B_P  @S9S_MB_2U_LIB.S9S_MB_2U(SCH_1):M_E_CPU0_SB_DQS_DP<1>
  104  M_E_CPU0_SB_DQS_DP<0>  DQS0_B_P  @S9S_MB_2U_LIB.S9S_MB_2U(SCH_1):M_E_CPU0_SB_DQS_DP<0>
   94  M_E_CPU0_SB_DQS_DN<9>  DQS9_B_N  @S9S_MB_2U_LIB.S9S_MB_2U(SCH_1):M_E_CPU0_SB_DQS_DN<9>
  282  M_E_CPU0_SB_DQS_DN<8>  DQS8_B_N  @S9S_MB_2U_LIB.S9S_MB_2U(SCH_1):M_E_CPU0_SB_DQS_DN<8>
  271  M_E_CPU0_SB_DQS_DN<7>  DQS7_B_N  @S9S_MB_2U_LIB.S9S_MB_2U(SCH_1):M_E_CPU0_SB_DQS_DN<7>
  260  M_E_CPU0_SB_DQS_DN<6>  DQS6_B_N  @S9S_MB_2U_LIB.S9S_MB_2U(SCH_1):M_E_CPU0_SB_DQS_DN<6>
  249  M_E_CPU0_SB_DQS_DN<5>  DQS5_B_N  @S9S_MB_2U_LIB.S9S_MB_2U(SCH_1):M_E_CPU0_SB_DQS_DN<5>
  238  M_E_CPU0_SB_DQS_DN<4>  DQS4_B_N  @S9S_MB_2U_LIB.S9S_MB_2U(SCH_1):M_E_CPU0_SB_DQS_DN<4>
  138  M_E_CPU0_SB_DQS_DN<3>  DQS3_B_N  @S9S_MB_2U_LIB.S9S_MB_2U(SCH_1):M_E_CPU0_SB_DQS_DN<3>
  127  M_E_CPU0_SB_DQS_DN<2>  DQS2_B_N  @S9S_MB_2U_LIB.S9S_MB_2U(SCH_1):M_E_CPU0_SB_DQS_DN<2>
  116  M_E_CPU0_SB_DQS_DN<1>  DQS1_B_N  @S9S_MB_2U_LIB.S9S_MB_2U(SCH_1):M_E_CPU0_SB_DQS_DN<1>
  105  M_E_CPU0_SB_DQS_DN<0>  DQS0_B_N  @S9S_MB_2U_LIB.S9S_MB_2U(SCH_1):M_E_CPU0_SB_DQS_DN<0>
  201  M_E_CPU0_SA_DQS_DP<9>  DQS9_A_P  @S9S_MB_2U_LIB.S9S_MB_2U(SCH_1):M_E_CPU0_SA_DQS_DP<9>
  190  M_E_CPU0_SA_DQS_DP<8>  DQS8_A_P  @S9S_MB_2U_LIB.S9S_MB_2U(SCH_1):M_E_CPU0_SA_DQS_DP<8>
  179  M_E_CPU0_SA_DQS_DP<7>  DQS7_A_P  @S9S_MB_2U_LIB.S9S_MB_2U(SCH_1):M_E_CPU0_SA_DQS_DP<7>
  168  M_E_CPU0_SA_DQS_DP<6>  DQS6_A_P  @S9S_MB_2U_LIB.S9S_MB_2U(SCH_1):M_E_CPU0_SA_DQS_DP<6>
  157  M_E_CPU0_SA_DQS_DP<5>  DQS5_A_P  @S9S_MB_2U_LIB.S9S_MB_2U(SCH_1):M_E_CPU0_SA_DQS_DP<5>
   55  M_E_CPU0_SA_DQS_DP<4>  DQS4_A_P  @S9S_MB_2U_LIB.S9S_MB_2U(SCH_1):M_E_CPU0_SA_DQS_DP<4>
   44  M_E_CPU0_SA_DQS_DP<3>  DQS3_A_P  @S9S_MB_2U_LIB.S9S_MB_2U(SCH_1):M_E_CPU0_SA_DQS_DP<3>
   33  M_E_CPU0_SA_DQS_DP<2>  DQS2_A_P  @S9S_MB_2U_LIB.S9S_MB_2U(SCH_1):M_E_CPU0_SA_DQS_DP<2>
   22  M_E_CPU0_SA_DQS_DP<1>  DQS1_A_P  @S9S_MB_2U_LIB.S9S_MB_2U(SCH_1):M_E_CPU0_SA_DQS_DP<1>
   11  M_E_CPU0_SA_DQS_DP<0>  DQS0_A_P  @S9S_MB_2U_LIB.S9S_MB_2U(SCH_1):M_E_CPU0_SA_DQS_DP<0>
  200  M_E_CPU0_SA_DQS_DN<9>  DQS9_A_N  @S9S_MB_2U_LIB.S9S_MB_2U(SCH_1):M_E_CPU0_SA_DQS_DN<9>
  189  M_E_CPU0_SA_DQS_DN<8>  DQS8_A_N  @S9S_MB_2U_LIB.S9S_MB_2U(SCH_1):M_E_CPU0_SA_DQS_DN<8>
  178  M_E_CPU0_SA_DQS_DN<7>  DQS7_A_N  @S9S_MB_2U_LIB.S9S_MB_2U(SCH_1):M_E_CPU0_SA_DQS_DN<7>
  167  M_E_CPU0_SA_DQS_DN<6>  DQS6_A_N  @S9S_MB_2U_LIB.S9S_MB_2U(SCH_1):M_E_CPU0_SA_DQS_DN<6>
  156  M_E_CPU0_SA_DQS_DN<5>  DQS5_A_N  @S9S_MB_2U_LIB.S9S_MB_2U(SCH_1):M_E_CPU0_SA_DQS_DN<5>
   56  M_E_CPU0_SA_DQS_DN<4>  DQS4_A_N  @S9S_MB_2U_LIB.S9S_MB_2U(SCH_1):M_E_CPU0_SA_DQS_DN<4>
   45  M_E_CPU0_SA_DQS_DN<3>  DQS3_A_N  @S9S_MB_2U_LIB.S9S_MB_2U(SCH_1):M_E_CPU0_SA_DQS_DN<3>
   34  M_E_CPU0_SA_DQS_DN<2>  DQS2_A_N  @S9S_MB_2U_LIB.S9S_MB_2U(SCH_1):M_E_CPU0_SA_DQS_DN<2>
   23  M_E_CPU0_SA_DQS_DN<1>  DQS1_A_N  @S9S_MB_2U_LIB.S9S_MB_2U(SCH_1):M_E_CPU0_SA_DQS_DN<1>
   12  M_E_CPU0_SA_DQS_DN<0>  DQS0_A_N  @S9S_MB_2U_LIB.S9S_MB_2U(SCH_1):M_E_CPU0_SA_DQS_DN<0>

SCONN288_ADR50001P013C01  I12  J9     [SCONN288_ADR50001P013C01-SCONNA]
  232  NC              RFU6  NC
  231  NC              RFU5  NC
  220  NC              RFU4  NC
  150  NC              RFU3  NC
  149  NC              RFU2  NC
  144  NC              RFU1  NC
    2  NC              RFU0  NC
  207  RST_M_EF_CPU0_FPGA_N  RESET_N  @S9S_MB_2U_LIB.S9S_MB_2U(SCH_1):RST_M_EF_CPU0_FPGA_N
  147  PWRGD_CHE_CPU0_DIMM1  PWR_GOOD||FAIL_N  @S9S_MB_2U_LIB.S9S_MB_2U(SCH_1):PWRGD_CHE_CPU0_DIMM1
  148  PD_CHE_CPU0_DIMM1_SAA    HAS  @S9S_MB_2U_LIB.S9S_MB_2U(SCH_1):PD_CHE_CPU0_DIMM1_SAA
    3  P3V3_AUX       VIN_MGMT  @S9S_MB_2U_LIB.S9S_MB_2U(SCH_1):P3V3_AUX
   87  M_E_CPU0_SB_RSP<0>  LBS||RSP_N_B  @S9S_MB_2U_LIB.S9S_MB_2U(SCH_1):M_E_CPU0_SB_RSP<0>
  227  M_E_CPU0_SB_PAR  PAR_B  @S9S_MB_2U_LIB.S9S_MB_2U(SCH_1):M_E_CPU0_SB_PAR
  113  M_E_CPU0_SB_DQ<9>  DQ_B9  @S9S_MB_2U_LIB.S9S_MB_2U(SCH_1):M_E_CPU0_SB_DQ<9>
  111  M_E_CPU0_SB_DQ<8>  DQ_B8  @S9S_MB_2U_LIB.S9S_MB_2U(SCH_1):M_E_CPU0_SB_DQ<8>
  254  M_E_CPU0_SB_DQ<7>  DQ_B7  @S9S_MB_2U_LIB.S9S_MB_2U(SCH_1):M_E_CPU0_SB_DQ<7>
  252  M_E_CPU0_SB_DQ<6>  DQ_B6  @S9S_MB_2U_LIB.S9S_MB_2U(SCH_1):M_E_CPU0_SB_DQ<6>
  109  M_E_CPU0_SB_DQ<5>  DQ_B5  @S9S_MB_2U_LIB.S9S_MB_2U(SCH_1):M_E_CPU0_SB_DQ<5>
  107  M_E_CPU0_SB_DQ<4>  DQ_B4  @S9S_MB_2U_LIB.S9S_MB_2U(SCH_1):M_E_CPU0_SB_DQ<4>
  247  M_E_CPU0_SB_DQ<3>  DQ_B3  @S9S_MB_2U_LIB.S9S_MB_2U(SCH_1):M_E_CPU0_SB_DQ<3>
  287  M_E_CPU0_SB_DQ<31>  DQ_B31  @S9S_MB_2U_LIB.S9S_MB_2U(SCH_1):M_E_CPU0_SB_DQ<31>
  285  M_E_CPU0_SB_DQ<30>  DQ_B30  @S9S_MB_2U_LIB.S9S_MB_2U(SCH_1):M_E_CPU0_SB_DQ<30>
  245  M_E_CPU0_SB_DQ<2>  DQ_B2  @S9S_MB_2U_LIB.S9S_MB_2U(SCH_1):M_E_CPU0_SB_DQ<2>
  142  M_E_CPU0_SB_DQ<29>  DQ_B29  @S9S_MB_2U_LIB.S9S_MB_2U(SCH_1):M_E_CPU0_SB_DQ<29>
  140  M_E_CPU0_SB_DQ<28>  DQ_B28  @S9S_MB_2U_LIB.S9S_MB_2U(SCH_1):M_E_CPU0_SB_DQ<28>
  280  M_E_CPU0_SB_DQ<27>  DQ_B27  @S9S_MB_2U_LIB.S9S_MB_2U(SCH_1):M_E_CPU0_SB_DQ<27>
  278  M_E_CPU0_SB_DQ<26>  DQ_B26  @S9S_MB_2U_LIB.S9S_MB_2U(SCH_1):M_E_CPU0_SB_DQ<26>
  135  M_E_CPU0_SB_DQ<25>  DQ_B25  @S9S_MB_2U_LIB.S9S_MB_2U(SCH_1):M_E_CPU0_SB_DQ<25>
  133  M_E_CPU0_SB_DQ<24>  DQ_B24  @S9S_MB_2U_LIB.S9S_MB_2U(SCH_1):M_E_CPU0_SB_DQ<24>
  276  M_E_CPU0_SB_DQ<23>  DQ_B23  @S9S_MB_2U_LIB.S9S_MB_2U(SCH_1):M_E_CPU0_SB_DQ<23>
  274  M_E_CPU0_SB_DQ<22>  DQ_B22  @S9S_MB_2U_LIB.S9S_MB_2U(SCH_1):M_E_CPU0_SB_DQ<22>
  131  M_E_CPU0_SB_DQ<21>  DQ_B21  @S9S_MB_2U_LIB.S9S_MB_2U(SCH_1):M_E_CPU0_SB_DQ<21>
  129  M_E_CPU0_SB_DQ<20>  DQ_B20  @S9S_MB_2U_LIB.S9S_MB_2U(SCH_1):M_E_CPU0_SB_DQ<20>
  102  M_E_CPU0_SB_DQ<1>  DQ_B1  @S9S_MB_2U_LIB.S9S_MB_2U(SCH_1):M_E_CPU0_SB_DQ<1>
  269  M_E_CPU0_SB_DQ<19>  DQ_B19  @S9S_MB_2U_LIB.S9S_MB_2U(SCH_1):M_E_CPU0_SB_DQ<19>
  267  M_E_CPU0_SB_DQ<18>  DQ_B18  @S9S_MB_2U_LIB.S9S_MB_2U(SCH_1):M_E_CPU0_SB_DQ<18>
  124  M_E_CPU0_SB_DQ<17>  DQ_B17  @S9S_MB_2U_LIB.S9S_MB_2U(SCH_1):M_E_CPU0_SB_DQ<17>
  122  M_E_CPU0_SB_DQ<16>  DQ_B16  @S9S_MB_2U_LIB.S9S_MB_2U(SCH_1):M_E_CPU0_SB_DQ<16>
  265  M_E_CPU0_SB_DQ<15>  DQ_B15  @S9S_MB_2U_LIB.S9S_MB_2U(SCH_1):M_E_CPU0_SB_DQ<15>
  263  M_E_CPU0_SB_DQ<14>  DQ_B14  @S9S_MB_2U_LIB.S9S_MB_2U(SCH_1):M_E_CPU0_SB_DQ<14>
  120  M_E_CPU0_SB_DQ<13>  DQ_B13  @S9S_MB_2U_LIB.S9S_MB_2U(SCH_1):M_E_CPU0_SB_DQ<13>
  118  M_E_CPU0_SB_DQ<12>  DQ_B12  @S9S_MB_2U_LIB.S9S_MB_2U(SCH_1):M_E_CPU0_SB_DQ<12>
  258  M_E_CPU0_SB_DQ<11>  DQ_B11  @S9S_MB_2U_LIB.S9S_MB_2U(SCH_1):M_E_CPU0_SB_DQ<11>
  256  M_E_CPU0_SB_DQ<10>  DQ_B10  @S9S_MB_2U_LIB.S9S_MB_2U(SCH_1):M_E_CPU0_SB_DQ<10>
  100  M_E_CPU0_SB_DQ<0>  DQ_B0  @S9S_MB_2U_LIB.S9S_MB_2U(SCH_1):M_E_CPU0_SB_DQ<0>
  229  M_E_CPU0_SB_CS_N<1>  CS1_N_B  @S9S_MB_2U_LIB.S9S_MB_2U(SCH_1):M_E_CPU0_SB_CS_N<1>
   84  M_E_CPU0_SB_CS_N<0>  CS0_N_B  @S9S_MB_2U_LIB.S9S_MB_2U(SCH_1):M_E_CPU0_SB_CS_N<0>
  236  M_E_CPU0_SB_CB<7>  CB_B7  @S9S_MB_2U_LIB.S9S_MB_2U(SCH_1):M_E_CPU0_SB_CB<7>
  234  M_E_CPU0_SB_CB<6>  CB_B6  @S9S_MB_2U_LIB.S9S_MB_2U(SCH_1):M_E_CPU0_SB_CB<6>
   91  M_E_CPU0_SB_CB<5>  CB_B5  @S9S_MB_2U_LIB.S9S_MB_2U(SCH_1):M_E_CPU0_SB_CB<5>
   89  M_E_CPU0_SB_CB<4>  CB_B4  @S9S_MB_2U_LIB.S9S_MB_2U(SCH_1):M_E_CPU0_SB_CB<4>
  243  M_E_CPU0_SB_CB<3>  CB_B3  @S9S_MB_2U_LIB.S9S_MB_2U(SCH_1):M_E_CPU0_SB_CB<3>
  241  M_E_CPU0_SB_CB<2>  CB_B2  @S9S_MB_2U_LIB.S9S_MB_2U(SCH_1):M_E_CPU0_SB_CB<2>
   98  M_E_CPU0_SB_CB<1>  CB_B1  @S9S_MB_2U_LIB.S9S_MB_2U(SCH_1):M_E_CPU0_SB_CB<1>
   96  M_E_CPU0_SB_CB<0>  CB_B0  @S9S_MB_2U_LIB.S9S_MB_2U(SCH_1):M_E_CPU0_SB_CB<0>
   82  M_E_CPU0_SB_CA<6>  CA6_B  @S9S_MB_2U_LIB.S9S_MB_2U(SCH_1):M_E_CPU0_SB_CA<6>
  225  M_E_CPU0_SB_CA<5>  CA5_B  @S9S_MB_2U_LIB.S9S_MB_2U(SCH_1):M_E_CPU0_SB_CA<5>
   80  M_E_CPU0_SB_CA<4>  CA4_B  @S9S_MB_2U_LIB.S9S_MB_2U(SCH_1):M_E_CPU0_SB_CA<4>
  223  M_E_CPU0_SB_CA<3>  CA3_B  @S9S_MB_2U_LIB.S9S_MB_2U(SCH_1):M_E_CPU0_SB_CA<3>
   78  M_E_CPU0_SB_CA<2>  CA2_B  @S9S_MB_2U_LIB.S9S_MB_2U(SCH_1):M_E_CPU0_SB_CA<2>
  221  M_E_CPU0_SB_CA<1>  CA1_B  @S9S_MB_2U_LIB.S9S_MB_2U(SCH_1):M_E_CPU0_SB_CA<1>
   76  M_E_CPU0_SB_CA<0>  CA0_B  @S9S_MB_2U_LIB.S9S_MB_2U(SCH_1):M_E_CPU0_SB_CA<0>
   86  M_E_CPU0_SA_RSP<0>  LBD||RSP_N_A  @S9S_MB_2U_LIB.S9S_MB_2U(SCH_1):M_E_CPU0_SA_RSP<0>
   74  M_E_CPU0_SA_PAR  PAR_A  @S9S_MB_2U_LIB.S9S_MB_2U(SCH_1):M_E_CPU0_SA_PAR
   20  M_E_CPU0_SA_DQ<9>  DQ_A9  @S9S_MB_2U_LIB.S9S_MB_2U(SCH_1):M_E_CPU0_SA_DQ<9>
   18  M_E_CPU0_SA_DQ<8>  DQ_A8  @S9S_MB_2U_LIB.S9S_MB_2U(SCH_1):M_E_CPU0_SA_DQ<8>
  161  M_E_CPU0_SA_DQ<7>  DQ_A7  @S9S_MB_2U_LIB.S9S_MB_2U(SCH_1):M_E_CPU0_SA_DQ<7>
  159  M_E_CPU0_SA_DQ<6>  DQ_A6  @S9S_MB_2U_LIB.S9S_MB_2U(SCH_1):M_E_CPU0_SA_DQ<6>
   16  M_E_CPU0_SA_DQ<5>  DQ_A5  @S9S_MB_2U_LIB.S9S_MB_2U(SCH_1):M_E_CPU0_SA_DQ<5>
   14  M_E_CPU0_SA_DQ<4>  DQ_A4  @S9S_MB_2U_LIB.S9S_MB_2U(SCH_1):M_E_CPU0_SA_DQ<4>
  154  M_E_CPU0_SA_DQ<3>  DQ_A3  @S9S_MB_2U_LIB.S9S_MB_2U(SCH_1):M_E_CPU0_SA_DQ<3>
  194  M_E_CPU0_SA_DQ<31>  DQ_A31  @S9S_MB_2U_LIB.S9S_MB_2U(SCH_1):M_E_CPU0_SA_DQ<31>
  192  M_E_CPU0_SA_DQ<30>  DQ_A30  @S9S_MB_2U_LIB.S9S_MB_2U(SCH_1):M_E_CPU0_SA_DQ<30>
  152  M_E_CPU0_SA_DQ<2>  DQ_A2  @S9S_MB_2U_LIB.S9S_MB_2U(SCH_1):M_E_CPU0_SA_DQ<2>
   49  M_E_CPU0_SA_DQ<29>  DQ_A29  @S9S_MB_2U_LIB.S9S_MB_2U(SCH_1):M_E_CPU0_SA_DQ<29>
   47  M_E_CPU0_SA_DQ<28>  DQ_A28  @S9S_MB_2U_LIB.S9S_MB_2U(SCH_1):M_E_CPU0_SA_DQ<28>
  187  M_E_CPU0_SA_DQ<27>  DQ_A27  @S9S_MB_2U_LIB.S9S_MB_2U(SCH_1):M_E_CPU0_SA_DQ<27>
  185  M_E_CPU0_SA_DQ<26>  DQ_A26  @S9S_MB_2U_LIB.S9S_MB_2U(SCH_1):M_E_CPU0_SA_DQ<26>
   42  M_E_CPU0_SA_DQ<25>  DQ_A25  @S9S_MB_2U_LIB.S9S_MB_2U(SCH_1):M_E_CPU0_SA_DQ<25>
   40  M_E_CPU0_SA_DQ<24>  DQ_A24  @S9S_MB_2U_LIB.S9S_MB_2U(SCH_1):M_E_CPU0_SA_DQ<24>
  183  M_E_CPU0_SA_DQ<23>  DQ_A23  @S9S_MB_2U_LIB.S9S_MB_2U(SCH_1):M_E_CPU0_SA_DQ<23>
  181  M_E_CPU0_SA_DQ<22>  DQ_A22  @S9S_MB_2U_LIB.S9S_MB_2U(SCH_1):M_E_CPU0_SA_DQ<22>
   38  M_E_CPU0_SA_DQ<21>  DQ_A21  @S9S_MB_2U_LIB.S9S_MB_2U(SCH_1):M_E_CPU0_SA_DQ<21>
   36  M_E_CPU0_SA_DQ<20>  DQ_A20  @S9S_MB_2U_LIB.S9S_MB_2U(SCH_1):M_E_CPU0_SA_DQ<20>
    9  M_E_CPU0_SA_DQ<1>  DQ_A1  @S9S_MB_2U_LIB.S9S_MB_2U(SCH_1):M_E_CPU0_SA_DQ<1>
  176  M_E_CPU0_SA_DQ<19>  DQ_A19  @S9S_MB_2U_LIB.S9S_MB_2U(SCH_1):M_E_CPU0_SA_DQ<19>
  174  M_E_CPU0_SA_DQ<18>  DQ_A18  @S9S_MB_2U_LIB.S9S_MB_2U(SCH_1):M_E_CPU0_SA_DQ<18>
   31  M_E_CPU0_SA_DQ<17>  DQ_A17  @S9S_MB_2U_LIB.S9S_MB_2U(SCH_1):M_E_CPU0_SA_DQ<17>
   29  M_E_CPU0_SA_DQ<16>  DQ_A16  @S9S_MB_2U_LIB.S9S_MB_2U(SCH_1):M_E_CPU0_SA_DQ<16>
  172  M_E_CPU0_SA_DQ<15>  DQ_A15  @S9S_MB_2U_LIB.S9S_MB_2U(SCH_1):M_E_CPU0_SA_DQ<15>
  170  M_E_CPU0_SA_DQ<14>  DQ_A14  @S9S_MB_2U_LIB.S9S_MB_2U(SCH_1):M_E_CPU0_SA_DQ<14>
   27  M_E_CPU0_SA_DQ<13>  DQ_A13  @S9S_MB_2U_LIB.S9S_MB_2U(SCH_1):M_E_CPU0_SA_DQ<13>
   25  M_E_CPU0_SA_DQ<12>  DQ_A12  @S9S_MB_2U_LIB.S9S_MB_2U(SCH_1):M_E_CPU0_SA_DQ<12>
  165  M_E_CPU0_SA_DQ<11>  DQ_A11  @S9S_MB_2U_LIB.S9S_MB_2U(SCH_1):M_E_CPU0_SA_DQ<11>
  163  M_E_CPU0_SA_DQ<10>  DQ_A10  @S9S_MB_2U_LIB.S9S_MB_2U(SCH_1):M_E_CPU0_SA_DQ<10>
    7  M_E_CPU0_SA_DQ<0>  DQ_A0  @S9S_MB_2U_LIB.S9S_MB_2U(SCH_1):M_E_CPU0_SA_DQ<0>
  209  M_E_CPU0_SA_CS_N<1>  CS1_N_A  @S9S_MB_2U_LIB.S9S_MB_2U(SCH_1):M_E_CPU0_SA_CS_N<1>
   64  M_E_CPU0_SA_CS_N<0>  CS0_N_A  @S9S_MB_2U_LIB.S9S_MB_2U(SCH_1):M_E_CPU0_SA_CS_N<0>
  205  M_E_CPU0_SA_CB<7>  CB_A7  @S9S_MB_2U_LIB.S9S_MB_2U(SCH_1):M_E_CPU0_SA_CB<7>
  203  M_E_CPU0_SA_CB<6>  CB_A6  @S9S_MB_2U_LIB.S9S_MB_2U(SCH_1):M_E_CPU0_SA_CB<6>
   60  M_E_CPU0_SA_CB<5>  CB_A5  @S9S_MB_2U_LIB.S9S_MB_2U(SCH_1):M_E_CPU0_SA_CB<5>
   58  M_E_CPU0_SA_CB<4>  CB_A4  @S9S_MB_2U_LIB.S9S_MB_2U(SCH_1):M_E_CPU0_SA_CB<4>
  198  M_E_CPU0_SA_CB<3>  CB_A3  @S9S_MB_2U_LIB.S9S_MB_2U(SCH_1):M_E_CPU0_SA_CB<3>
  196  M_E_CPU0_SA_CB<2>  CB_A2  @S9S_MB_2U_LIB.S9S_MB_2U(SCH_1):M_E_CPU0_SA_CB<2>
   53  M_E_CPU0_SA_CB<1>  CB_A1  @S9S_MB_2U_LIB.S9S_MB_2U(SCH_1):M_E_CPU0_SA_CB<1>
   51  M_E_CPU0_SA_CB<0>  CB_A0  @S9S_MB_2U_LIB.S9S_MB_2U(SCH_1):M_E_CPU0_SA_CB<0>
   72  M_E_CPU0_SA_CA<6>  CA6_A  @S9S_MB_2U_LIB.S9S_MB_2U(SCH_1):M_E_CPU0_SA_CA<6>
  215  M_E_CPU0_SA_CA<5>  CA5_A  @S9S_MB_2U_LIB.S9S_MB_2U(SCH_1):M_E_CPU0_SA_CA<5>
   70  M_E_CPU0_SA_CA<4>  CA4_A  @S9S_MB_2U_LIB.S9S_MB_2U(SCH_1):M_E_CPU0_SA_CA<4>
  213  M_E_CPU0_SA_CA<3>  CA3_A  @S9S_MB_2U_LIB.S9S_MB_2U(SCH_1):M_E_CPU0_SA_CA<3>
   68  M_E_CPU0_SA_CA<2>  CA2_A  @S9S_MB_2U_LIB.S9S_MB_2U(SCH_1):M_E_CPU0_SA_CA<2>
  211  M_E_CPU0_SA_CA<1>  CA1_A  @S9S_MB_2U_LIB.S9S_MB_2U(SCH_1):M_E_CPU0_SA_CA<1>
   66  M_E_CPU0_SA_CA<0>  CA0_A  @S9S_MB_2U_LIB.S9S_MB_2U(SCH_1):M_E_CPU0_SA_CA<0>
  217  M_E_CPU0_CLK_DP<0>   CK_P  @S9S_MB_2U_LIB.S9S_MB_2U(SCH_1):M_E_CPU0_CLK_DP<0>
  218  M_E_CPU0_CLK_DN<0>   CK_N  @S9S_MB_2U_LIB.S9S_MB_2U(SCH_1):M_E_CPU0_CLK_DN<0>
   62  M_E_CPU0_ALERT_N  ALERT_N  @S9S_MB_2U_LIB.S9S_MB_2U(SCH_1):M_E_CPU0_ALERT_N
    5  I3C_SPD_DDREFGH_CPU0_LVC1_SDA   HSDA  @S9S_MB_2U_LIB.S9S_MB_2U(SCH_1):I3C_SPD_DDREFGH_CPU0_LVC1_SDA
    4  I3C_SPD_DDREFGH_CPU0_LVC1_SCL   HSCL  @S9S_MB_2U_LIB.S9S_MB_2U(SCH_1):I3C_SPD_DDREFGH_CPU0_LVC1_SCL

SCONN288_ADR50001P003C01  I148  J10    [SCONN288_ADR50001P003C01-SCONNA]
  146  P12V_S3_AUX_CPU0_NVDIMM  VIN_BULK2  @S9S_MB_2U_LIB.S9S_MB_2U(SCH_1):P12V_S3_AUX_CPU0_NVDIMM
  145  P12V_S3_AUX_CPU0_NVDIMM  VIN_BULK1  @S9S_MB_2U_LIB.S9S_MB_2U(SCH_1):P12V_S3_AUX_CPU0_NVDIMM
    1  P12V_S3_AUX_CPU0_NVDIMM  VIN_BULK0  @S9S_MB_2U_LIB.S9S_MB_2U(SCH_1):P12V_S3_AUX_CPU0_NVDIMM
  288  GND            VSS126  @S9S_MB_2U_LIB.S9S_MB_2U(SCH_1):GND
  286  GND            VSS125  @S9S_MB_2U_LIB.S9S_MB_2U(SCH_1):GND
  284  GND            VSS124  @S9S_MB_2U_LIB.S9S_MB_2U(SCH_1):GND
  281  GND            VSS123  @S9S_MB_2U_LIB.S9S_MB_2U(SCH_1):GND
  279  GND            VSS122  @S9S_MB_2U_LIB.S9S_MB_2U(SCH_1):GND
  277  GND            VSS121  @S9S_MB_2U_LIB.S9S_MB_2U(SCH_1):GND
  275  GND            VSS120  @S9S_MB_2U_LIB.S9S_MB_2U(SCH_1):GND
  273  GND            VSS119  @S9S_MB_2U_LIB.S9S_MB_2U(SCH_1):GND
  270  GND            VSS118  @S9S_MB_2U_LIB.S9S_MB_2U(SCH_1):GND
  268  GND            VSS117  @S9S_MB_2U_LIB.S9S_MB_2U(SCH_1):GND
  266  GND            VSS116  @S9S_MB_2U_LIB.S9S_MB_2U(SCH_1):GND
  264  GND            VSS115  @S9S_MB_2U_LIB.S9S_MB_2U(SCH_1):GND
  262  GND            VSS114  @S9S_MB_2U_LIB.S9S_MB_2U(SCH_1):GND
  259  GND            VSS113  @S9S_MB_2U_LIB.S9S_MB_2U(SCH_1):GND
  257  GND            VSS112  @S9S_MB_2U_LIB.S9S_MB_2U(SCH_1):GND
  255  GND            VSS111  @S9S_MB_2U_LIB.S9S_MB_2U(SCH_1):GND
  253  GND            VSS110  @S9S_MB_2U_LIB.S9S_MB_2U(SCH_1):GND
  251  GND            VSS109  @S9S_MB_2U_LIB.S9S_MB_2U(SCH_1):GND
  248  GND            VSS108  @S9S_MB_2U_LIB.S9S_MB_2U(SCH_1):GND
  246  GND            VSS107  @S9S_MB_2U_LIB.S9S_MB_2U(SCH_1):GND
  244  GND            VSS106  @S9S_MB_2U_LIB.S9S_MB_2U(SCH_1):GND
  242  GND            VSS105  @S9S_MB_2U_LIB.S9S_MB_2U(SCH_1):GND
  240  GND            VSS104  @S9S_MB_2U_LIB.S9S_MB_2U(SCH_1):GND
  237  GND            VSS103  @S9S_MB_2U_LIB.S9S_MB_2U(SCH_1):GND
  235  GND            VSS102  @S9S_MB_2U_LIB.S9S_MB_2U(SCH_1):GND
  233  GND            VSS101  @S9S_MB_2U_LIB.S9S_MB_2U(SCH_1):GND
  230  GND            VSS100  @S9S_MB_2U_LIB.S9S_MB_2U(SCH_1):GND
  228  GND            VSS99  @S9S_MB_2U_LIB.S9S_MB_2U(SCH_1):GND
  226  GND            VSS98  @S9S_MB_2U_LIB.S9S_MB_2U(SCH_1):GND
  224  GND            VSS97  @S9S_MB_2U_LIB.S9S_MB_2U(SCH_1):GND
  222  GND            VSS96  @S9S_MB_2U_LIB.S9S_MB_2U(SCH_1):GND
  219  GND            VSS95  @S9S_MB_2U_LIB.S9S_MB_2U(SCH_1):GND
  216  GND            VSS94  @S9S_MB_2U_LIB.S9S_MB_2U(SCH_1):GND
  214  GND            VSS93  @S9S_MB_2U_LIB.S9S_MB_2U(SCH_1):GND
  212  GND            VSS92  @S9S_MB_2U_LIB.S9S_MB_2U(SCH_1):GND
  210  GND            VSS91  @S9S_MB_2U_LIB.S9S_MB_2U(SCH_1):GND
  208  GND            VSS90  @S9S_MB_2U_LIB.S9S_MB_2U(SCH_1):GND
  206  GND            VSS89  @S9S_MB_2U_LIB.S9S_MB_2U(SCH_1):GND
  204  GND            VSS88  @S9S_MB_2U_LIB.S9S_MB_2U(SCH_1):GND
  202  GND            VSS87  @S9S_MB_2U_LIB.S9S_MB_2U(SCH_1):GND
  199  GND            VSS86  @S9S_MB_2U_LIB.S9S_MB_2U(SCH_1):GND
  197  GND            VSS85  @S9S_MB_2U_LIB.S9S_MB_2U(SCH_1):GND
  195  GND            VSS84  @S9S_MB_2U_LIB.S9S_MB_2U(SCH_1):GND
  193  GND            VSS83  @S9S_MB_2U_LIB.S9S_MB_2U(SCH_1):GND
  191  GND            VSS82  @S9S_MB_2U_LIB.S9S_MB_2U(SCH_1):GND
  188  GND            VSS81  @S9S_MB_2U_LIB.S9S_MB_2U(SCH_1):GND
  186  GND            VSS80  @S9S_MB_2U_LIB.S9S_MB_2U(SCH_1):GND
  184  GND            VSS79  @S9S_MB_2U_LIB.S9S_MB_2U(SCH_1):GND
  182  GND            VSS78  @S9S_MB_2U_LIB.S9S_MB_2U(SCH_1):GND
  180  GND            VSS77  @S9S_MB_2U_LIB.S9S_MB_2U(SCH_1):GND
  177  GND            VSS76  @S9S_MB_2U_LIB.S9S_MB_2U(SCH_1):GND
  175  GND            VSS75  @S9S_MB_2U_LIB.S9S_MB_2U(SCH_1):GND
  173  GND            VSS74  @S9S_MB_2U_LIB.S9S_MB_2U(SCH_1):GND
  171  GND            VSS73  @S9S_MB_2U_LIB.S9S_MB_2U(SCH_1):GND
  169  GND            VSS72  @S9S_MB_2U_LIB.S9S_MB_2U(SCH_1):GND
  166  GND            VSS71  @S9S_MB_2U_LIB.S9S_MB_2U(SCH_1):GND
  164  GND            VSS70  @S9S_MB_2U_LIB.S9S_MB_2U(SCH_1):GND
  162  GND            VSS69  @S9S_MB_2U_LIB.S9S_MB_2U(SCH_1):GND
  160  GND            VSS68  @S9S_MB_2U_LIB.S9S_MB_2U(SCH_1):GND
  158  GND            VSS67  @S9S_MB_2U_LIB.S9S_MB_2U(SCH_1):GND
  155  GND            VSS66  @S9S_MB_2U_LIB.S9S_MB_2U(SCH_1):GND
  153  GND            VSS65  @S9S_MB_2U_LIB.S9S_MB_2U(SCH_1):GND
  151  GND            VSS64  @S9S_MB_2U_LIB.S9S_MB_2U(SCH_1):GND
  143  GND            VSS63  @S9S_MB_2U_LIB.S9S_MB_2U(SCH_1):GND
  141  GND            VSS62  @S9S_MB_2U_LIB.S9S_MB_2U(SCH_1):GND
  139  GND            VSS61  @S9S_MB_2U_LIB.S9S_MB_2U(SCH_1):GND
  136  GND            VSS60  @S9S_MB_2U_LIB.S9S_MB_2U(SCH_1):GND
  134  GND            VSS59  @S9S_MB_2U_LIB.S9S_MB_2U(SCH_1):GND
  132  GND            VSS58  @S9S_MB_2U_LIB.S9S_MB_2U(SCH_1):GND
  130  GND            VSS57  @S9S_MB_2U_LIB.S9S_MB_2U(SCH_1):GND
  128  GND            VSS56  @S9S_MB_2U_LIB.S9S_MB_2U(SCH_1):GND
  125  GND            VSS55  @S9S_MB_2U_LIB.S9S_MB_2U(SCH_1):GND
  123  GND            VSS54  @S9S_MB_2U_LIB.S9S_MB_2U(SCH_1):GND
  121  GND            VSS53  @S9S_MB_2U_LIB.S9S_MB_2U(SCH_1):GND
  119  GND            VSS52  @S9S_MB_2U_LIB.S9S_MB_2U(SCH_1):GND
  117  GND            VSS51  @S9S_MB_2U_LIB.S9S_MB_2U(SCH_1):GND
  114  GND            VSS50  @S9S_MB_2U_LIB.S9S_MB_2U(SCH_1):GND
  112  GND            VSS49  @S9S_MB_2U_LIB.S9S_MB_2U(SCH_1):GND
  110  GND            VSS48  @S9S_MB_2U_LIB.S9S_MB_2U(SCH_1):GND
  108  GND            VSS47  @S9S_MB_2U_LIB.S9S_MB_2U(SCH_1):GND
  106  GND            VSS46  @S9S_MB_2U_LIB.S9S_MB_2U(SCH_1):GND
  103  GND            VSS45  @S9S_MB_2U_LIB.S9S_MB_2U(SCH_1):GND
  101  GND            VSS44  @S9S_MB_2U_LIB.S9S_MB_2U(SCH_1):GND
   99  GND            VSS43  @S9S_MB_2U_LIB.S9S_MB_2U(SCH_1):GND
   97  GND            VSS42  @S9S_MB_2U_LIB.S9S_MB_2U(SCH_1):GND
   95  GND            VSS41  @S9S_MB_2U_LIB.S9S_MB_2U(SCH_1):GND
   92  GND            VSS40  @S9S_MB_2U_LIB.S9S_MB_2U(SCH_1):GND
   90  GND            VSS39  @S9S_MB_2U_LIB.S9S_MB_2U(SCH_1):GND
   88  GND            VSS38  @S9S_MB_2U_LIB.S9S_MB_2U(SCH_1):GND
   85  GND            VSS37  @S9S_MB_2U_LIB.S9S_MB_2U(SCH_1):GND
   83  GND            VSS36  @S9S_MB_2U_LIB.S9S_MB_2U(SCH_1):GND
   81  GND            VSS35  @S9S_MB_2U_LIB.S9S_MB_2U(SCH_1):GND
   79  GND            VSS34  @S9S_MB_2U_LIB.S9S_MB_2U(SCH_1):GND
   77  GND            VSS33  @S9S_MB_2U_LIB.S9S_MB_2U(SCH_1):GND
   75  GND            VSS32  @S9S_MB_2U_LIB.S9S_MB_2U(SCH_1):GND
   73  GND            VSS31  @S9S_MB_2U_LIB.S9S_MB_2U(SCH_1):GND
   71  GND            VSS30  @S9S_MB_2U_LIB.S9S_MB_2U(SCH_1):GND
   69  GND            VSS29  @S9S_MB_2U_LIB.S9S_MB_2U(SCH_1):GND
   67  GND            VSS28  @S9S_MB_2U_LIB.S9S_MB_2U(SCH_1):GND
   65  GND            VSS27  @S9S_MB_2U_LIB.S9S_MB_2U(SCH_1):GND
   63  GND            VSS26  @S9S_MB_2U_LIB.S9S_MB_2U(SCH_1):GND
   61  GND            VSS25  @S9S_MB_2U_LIB.S9S_MB_2U(SCH_1):GND
   59  GND            VSS24  @S9S_MB_2U_LIB.S9S_MB_2U(SCH_1):GND
   57  GND            VSS23  @S9S_MB_2U_LIB.S9S_MB_2U(SCH_1):GND
   54  GND            VSS22  @S9S_MB_2U_LIB.S9S_MB_2U(SCH_1):GND
   52  GND            VSS21  @S9S_MB_2U_LIB.S9S_MB_2U(SCH_1):GND
   50  GND            VSS20  @S9S_MB_2U_LIB.S9S_MB_2U(SCH_1):GND
   48  GND            VSS19  @S9S_MB_2U_LIB.S9S_MB_2U(SCH_1):GND
   46  GND            VSS18  @S9S_MB_2U_LIB.S9S_MB_2U(SCH_1):GND
   43  GND            VSS17  @S9S_MB_2U_LIB.S9S_MB_2U(SCH_1):GND
   41  GND            VSS16  @S9S_MB_2U_LIB.S9S_MB_2U(SCH_1):GND
   39  GND            VSS15  @S9S_MB_2U_LIB.S9S_MB_2U(SCH_1):GND
   37  GND            VSS14  @S9S_MB_2U_LIB.S9S_MB_2U(SCH_1):GND
   35  GND            VSS13  @S9S_MB_2U_LIB.S9S_MB_2U(SCH_1):GND
   32  GND            VSS12  @S9S_MB_2U_LIB.S9S_MB_2U(SCH_1):GND
   30  GND            VSS11  @S9S_MB_2U_LIB.S9S_MB_2U(SCH_1):GND
   28  GND            VSS10  @S9S_MB_2U_LIB.S9S_MB_2U(SCH_1):GND
   26  GND             VSS9  @S9S_MB_2U_LIB.S9S_MB_2U(SCH_1):GND
   24  GND             VSS8  @S9S_MB_2U_LIB.S9S_MB_2U(SCH_1):GND
   21  GND             VSS7  @S9S_MB_2U_LIB.S9S_MB_2U(SCH_1):GND
   19  GND             VSS6  @S9S_MB_2U_LIB.S9S_MB_2U(SCH_1):GND
   17  GND             VSS5  @S9S_MB_2U_LIB.S9S_MB_2U(SCH_1):GND
   15  GND             VSS4  @S9S_MB_2U_LIB.S9S_MB_2U(SCH_1):GND
   13  GND             VSS3  @S9S_MB_2U_LIB.S9S_MB_2U(SCH_1):GND
   10  GND             VSS2  @S9S_MB_2U_LIB.S9S_MB_2U(SCH_1):GND
    8  GND             VSS1  @S9S_MB_2U_LIB.S9S_MB_2U(SCH_1):GND
    6  GND             VSS0  @S9S_MB_2U_LIB.S9S_MB_2U(SCH_1):GND
   G3  GND               G3  @S9S_MB_2U_LIB.S9S_MB_2U(SCH_1):GND
   G2  GND               G2  @S9S_MB_2U_LIB.S9S_MB_2U(SCH_1):GND
   G1  GND               G1  @S9S_MB_2U_LIB.S9S_MB_2U(SCH_1):GND

SCONN288_ADR50001P003C01  I127  J10    [SCONN288_ADR50001P003C01-SCONNA]
   93  M_E_CPU0_SB_DQS_DP<9>  DQS9_B_P  @S9S_MB_2U_LIB.S9S_MB_2U(SCH_1):M_E_CPU0_SB_DQS_DP<9>
  283  M_E_CPU0_SB_DQS_DP<8>  DQS8_B_P  @S9S_MB_2U_LIB.S9S_MB_2U(SCH_1):M_E_CPU0_SB_DQS_DP<8>
  272  M_E_CPU0_SB_DQS_DP<7>  DQS7_B_P  @S9S_MB_2U_LIB.S9S_MB_2U(SCH_1):M_E_CPU0_SB_DQS_DP<7>
  261  M_E_CPU0_SB_DQS_DP<6>  DQS6_B_P  @S9S_MB_2U_LIB.S9S_MB_2U(SCH_1):M_E_CPU0_SB_DQS_DP<6>
  250  M_E_CPU0_SB_DQS_DP<5>  DQS5_B_P  @S9S_MB_2U_LIB.S9S_MB_2U(SCH_1):M_E_CPU0_SB_DQS_DP<5>
  239  M_E_CPU0_SB_DQS_DP<4>  DQS4_B_P  @S9S_MB_2U_LIB.S9S_MB_2U(SCH_1):M_E_CPU0_SB_DQS_DP<4>
  137  M_E_CPU0_SB_DQS_DP<3>  DQS3_B_P  @S9S_MB_2U_LIB.S9S_MB_2U(SCH_1):M_E_CPU0_SB_DQS_DP<3>
  126  M_E_CPU0_SB_DQS_DP<2>  DQS2_B_P  @S9S_MB_2U_LIB.S9S_MB_2U(SCH_1):M_E_CPU0_SB_DQS_DP<2>
  115  M_E_CPU0_SB_DQS_DP<1>  DQS1_B_P  @S9S_MB_2U_LIB.S9S_MB_2U(SCH_1):M_E_CPU0_SB_DQS_DP<1>
  104  M_E_CPU0_SB_DQS_DP<0>  DQS0_B_P  @S9S_MB_2U_LIB.S9S_MB_2U(SCH_1):M_E_CPU0_SB_DQS_DP<0>
   94  M_E_CPU0_SB_DQS_DN<9>  DQS9_B_N  @S9S_MB_2U_LIB.S9S_MB_2U(SCH_1):M_E_CPU0_SB_DQS_DN<9>
  282  M_E_CPU0_SB_DQS_DN<8>  DQS8_B_N  @S9S_MB_2U_LIB.S9S_MB_2U(SCH_1):M_E_CPU0_SB_DQS_DN<8>
  271  M_E_CPU0_SB_DQS_DN<7>  DQS7_B_N  @S9S_MB_2U_LIB.S9S_MB_2U(SCH_1):M_E_CPU0_SB_DQS_DN<7>
  260  M_E_CPU0_SB_DQS_DN<6>  DQS6_B_N  @S9S_MB_2U_LIB.S9S_MB_2U(SCH_1):M_E_CPU0_SB_DQS_DN<6>
  249  M_E_CPU0_SB_DQS_DN<5>  DQS5_B_N  @S9S_MB_2U_LIB.S9S_MB_2U(SCH_1):M_E_CPU0_SB_DQS_DN<5>
  238  M_E_CPU0_SB_DQS_DN<4>  DQS4_B_N  @S9S_MB_2U_LIB.S9S_MB_2U(SCH_1):M_E_CPU0_SB_DQS_DN<4>
  138  M_E_CPU0_SB_DQS_DN<3>  DQS3_B_N  @S9S_MB_2U_LIB.S9S_MB_2U(SCH_1):M_E_CPU0_SB_DQS_DN<3>
  127  M_E_CPU0_SB_DQS_DN<2>  DQS2_B_N  @S9S_MB_2U_LIB.S9S_MB_2U(SCH_1):M_E_CPU0_SB_DQS_DN<2>
  116  M_E_CPU0_SB_DQS_DN<1>  DQS1_B_N  @S9S_MB_2U_LIB.S9S_MB_2U(SCH_1):M_E_CPU0_SB_DQS_DN<1>
  105  M_E_CPU0_SB_DQS_DN<0>  DQS0_B_N  @S9S_MB_2U_LIB.S9S_MB_2U(SCH_1):M_E_CPU0_SB_DQS_DN<0>
  201  M_E_CPU0_SA_DQS_DP<9>  DQS9_A_P  @S9S_MB_2U_LIB.S9S_MB_2U(SCH_1):M_E_CPU0_SA_DQS_DP<9>
  190  M_E_CPU0_SA_DQS_DP<8>  DQS8_A_P  @S9S_MB_2U_LIB.S9S_MB_2U(SCH_1):M_E_CPU0_SA_DQS_DP<8>
  179  M_E_CPU0_SA_DQS_DP<7>  DQS7_A_P  @S9S_MB_2U_LIB.S9S_MB_2U(SCH_1):M_E_CPU0_SA_DQS_DP<7>
  168  M_E_CPU0_SA_DQS_DP<6>  DQS6_A_P  @S9S_MB_2U_LIB.S9S_MB_2U(SCH_1):M_E_CPU0_SA_DQS_DP<6>
  157  M_E_CPU0_SA_DQS_DP<5>  DQS5_A_P  @S9S_MB_2U_LIB.S9S_MB_2U(SCH_1):M_E_CPU0_SA_DQS_DP<5>
   55  M_E_CPU0_SA_DQS_DP<4>  DQS4_A_P  @S9S_MB_2U_LIB.S9S_MB_2U(SCH_1):M_E_CPU0_SA_DQS_DP<4>
   44  M_E_CPU0_SA_DQS_DP<3>  DQS3_A_P  @S9S_MB_2U_LIB.S9S_MB_2U(SCH_1):M_E_CPU0_SA_DQS_DP<3>
   33  M_E_CPU0_SA_DQS_DP<2>  DQS2_A_P  @S9S_MB_2U_LIB.S9S_MB_2U(SCH_1):M_E_CPU0_SA_DQS_DP<2>
   22  M_E_CPU0_SA_DQS_DP<1>  DQS1_A_P  @S9S_MB_2U_LIB.S9S_MB_2U(SCH_1):M_E_CPU0_SA_DQS_DP<1>
   11  M_E_CPU0_SA_DQS_DP<0>  DQS0_A_P  @S9S_MB_2U_LIB.S9S_MB_2U(SCH_1):M_E_CPU0_SA_DQS_DP<0>
  200  M_E_CPU0_SA_DQS_DN<9>  DQS9_A_N  @S9S_MB_2U_LIB.S9S_MB_2U(SCH_1):M_E_CPU0_SA_DQS_DN<9>
  189  M_E_CPU0_SA_DQS_DN<8>  DQS8_A_N  @S9S_MB_2U_LIB.S9S_MB_2U(SCH_1):M_E_CPU0_SA_DQS_DN<8>
  178  M_E_CPU0_SA_DQS_DN<7>  DQS7_A_N  @S9S_MB_2U_LIB.S9S_MB_2U(SCH_1):M_E_CPU0_SA_DQS_DN<7>
  167  M_E_CPU0_SA_DQS_DN<6>  DQS6_A_N  @S9S_MB_2U_LIB.S9S_MB_2U(SCH_1):M_E_CPU0_SA_DQS_DN<6>
  156  M_E_CPU0_SA_DQS_DN<5>  DQS5_A_N  @S9S_MB_2U_LIB.S9S_MB_2U(SCH_1):M_E_CPU0_SA_DQS_DN<5>
   56  M_E_CPU0_SA_DQS_DN<4>  DQS4_A_N  @S9S_MB_2U_LIB.S9S_MB_2U(SCH_1):M_E_CPU0_SA_DQS_DN<4>
   45  M_E_CPU0_SA_DQS_DN<3>  DQS3_A_N  @S9S_MB_2U_LIB.S9S_MB_2U(SCH_1):M_E_CPU0_SA_DQS_DN<3>
   34  M_E_CPU0_SA_DQS_DN<2>  DQS2_A_N  @S9S_MB_2U_LIB.S9S_MB_2U(SCH_1):M_E_CPU0_SA_DQS_DN<2>
   23  M_E_CPU0_SA_DQS_DN<1>  DQS1_A_N  @S9S_MB_2U_LIB.S9S_MB_2U(SCH_1):M_E_CPU0_SA_DQS_DN<1>
   12  M_E_CPU0_SA_DQS_DN<0>  DQS0_A_N  @S9S_MB_2U_LIB.S9S_MB_2U(SCH_1):M_E_CPU0_SA_DQS_DN<0>

SCONN288_ADR50001P003C01  I13  J10    [SCONN288_ADR50001P003C01-SCONNA]
  232  NC              RFU6  NC
  231  NC              RFU5  NC
  220  NC              RFU4  NC
  150  NC              RFU3  NC
  149  NC              RFU2  NC
  144  NC              RFU1  NC
    2  NC              RFU0  NC
  207  RST_M_EF_CPU0_FPGA_N  RESET_N  @S9S_MB_2U_LIB.S9S_MB_2U(SCH_1):RST_M_EF_CPU0_FPGA_N
  147  PWRGD_CHE_CPU0_DIMM2  PWR_GOOD||FAIL_N  @S9S_MB_2U_LIB.S9S_MB_2U(SCH_1):PWRGD_CHE_CPU0_DIMM2
  148  PD_CHE_CPU0_DIMM2_SAA    HAS  @S9S_MB_2U_LIB.S9S_MB_2U(SCH_1):PD_CHE_CPU0_DIMM2_SAA
    3  P3V3_AUX       VIN_MGMT  @S9S_MB_2U_LIB.S9S_MB_2U(SCH_1):P3V3_AUX
   87  M_E_CPU0_SB_RSP<1>  LBS||RSP_N_B  @S9S_MB_2U_LIB.S9S_MB_2U(SCH_1):M_E_CPU0_SB_RSP<1>
  227  M_E_CPU0_SB_PAR  PAR_B  @S9S_MB_2U_LIB.S9S_MB_2U(SCH_1):M_E_CPU0_SB_PAR
  113  M_E_CPU0_SB_DQ<9>  DQ_B9  @S9S_MB_2U_LIB.S9S_MB_2U(SCH_1):M_E_CPU0_SB_DQ<9>
  111  M_E_CPU0_SB_DQ<8>  DQ_B8  @S9S_MB_2U_LIB.S9S_MB_2U(SCH_1):M_E_CPU0_SB_DQ<8>
  254  M_E_CPU0_SB_DQ<7>  DQ_B7  @S9S_MB_2U_LIB.S9S_MB_2U(SCH_1):M_E_CPU0_SB_DQ<7>
  252  M_E_CPU0_SB_DQ<6>  DQ_B6  @S9S_MB_2U_LIB.S9S_MB_2U(SCH_1):M_E_CPU0_SB_DQ<6>
  109  M_E_CPU0_SB_DQ<5>  DQ_B5  @S9S_MB_2U_LIB.S9S_MB_2U(SCH_1):M_E_CPU0_SB_DQ<5>
  107  M_E_CPU0_SB_DQ<4>  DQ_B4  @S9S_MB_2U_LIB.S9S_MB_2U(SCH_1):M_E_CPU0_SB_DQ<4>
  247  M_E_CPU0_SB_DQ<3>  DQ_B3  @S9S_MB_2U_LIB.S9S_MB_2U(SCH_1):M_E_CPU0_SB_DQ<3>
  287  M_E_CPU0_SB_DQ<31>  DQ_B31  @S9S_MB_2U_LIB.S9S_MB_2U(SCH_1):M_E_CPU0_SB_DQ<31>
  285  M_E_CPU0_SB_DQ<30>  DQ_B30  @S9S_MB_2U_LIB.S9S_MB_2U(SCH_1):M_E_CPU0_SB_DQ<30>
  245  M_E_CPU0_SB_DQ<2>  DQ_B2  @S9S_MB_2U_LIB.S9S_MB_2U(SCH_1):M_E_CPU0_SB_DQ<2>
  142  M_E_CPU0_SB_DQ<29>  DQ_B29  @S9S_MB_2U_LIB.S9S_MB_2U(SCH_1):M_E_CPU0_SB_DQ<29>
  140  M_E_CPU0_SB_DQ<28>  DQ_B28  @S9S_MB_2U_LIB.S9S_MB_2U(SCH_1):M_E_CPU0_SB_DQ<28>
  280  M_E_CPU0_SB_DQ<27>  DQ_B27  @S9S_MB_2U_LIB.S9S_MB_2U(SCH_1):M_E_CPU0_SB_DQ<27>
  278  M_E_CPU0_SB_DQ<26>  DQ_B26  @S9S_MB_2U_LIB.S9S_MB_2U(SCH_1):M_E_CPU0_SB_DQ<26>
  135  M_E_CPU0_SB_DQ<25>  DQ_B25  @S9S_MB_2U_LIB.S9S_MB_2U(SCH_1):M_E_CPU0_SB_DQ<25>
  133  M_E_CPU0_SB_DQ<24>  DQ_B24  @S9S_MB_2U_LIB.S9S_MB_2U(SCH_1):M_E_CPU0_SB_DQ<24>
  276  M_E_CPU0_SB_DQ<23>  DQ_B23  @S9S_MB_2U_LIB.S9S_MB_2U(SCH_1):M_E_CPU0_SB_DQ<23>
  274  M_E_CPU0_SB_DQ<22>  DQ_B22  @S9S_MB_2U_LIB.S9S_MB_2U(SCH_1):M_E_CPU0_SB_DQ<22>
  131  M_E_CPU0_SB_DQ<21>  DQ_B21  @S9S_MB_2U_LIB.S9S_MB_2U(SCH_1):M_E_CPU0_SB_DQ<21>
  129  M_E_CPU0_SB_DQ<20>  DQ_B20  @S9S_MB_2U_LIB.S9S_MB_2U(SCH_1):M_E_CPU0_SB_DQ<20>
  102  M_E_CPU0_SB_DQ<1>  DQ_B1  @S9S_MB_2U_LIB.S9S_MB_2U(SCH_1):M_E_CPU0_SB_DQ<1>
  269  M_E_CPU0_SB_DQ<19>  DQ_B19  @S9S_MB_2U_LIB.S9S_MB_2U(SCH_1):M_E_CPU0_SB_DQ<19>
  267  M_E_CPU0_SB_DQ<18>  DQ_B18  @S9S_MB_2U_LIB.S9S_MB_2U(SCH_1):M_E_CPU0_SB_DQ<18>
  124  M_E_CPU0_SB_DQ<17>  DQ_B17  @S9S_MB_2U_LIB.S9S_MB_2U(SCH_1):M_E_CPU0_SB_DQ<17>
  122  M_E_CPU0_SB_DQ<16>  DQ_B16  @S9S_MB_2U_LIB.S9S_MB_2U(SCH_1):M_E_CPU0_SB_DQ<16>
  265  M_E_CPU0_SB_DQ<15>  DQ_B15  @S9S_MB_2U_LIB.S9S_MB_2U(SCH_1):M_E_CPU0_SB_DQ<15>
  263  M_E_CPU0_SB_DQ<14>  DQ_B14  @S9S_MB_2U_LIB.S9S_MB_2U(SCH_1):M_E_CPU0_SB_DQ<14>
  120  M_E_CPU0_SB_DQ<13>  DQ_B13  @S9S_MB_2U_LIB.S9S_MB_2U(SCH_1):M_E_CPU0_SB_DQ<13>
  118  M_E_CPU0_SB_DQ<12>  DQ_B12  @S9S_MB_2U_LIB.S9S_MB_2U(SCH_1):M_E_CPU0_SB_DQ<12>
  258  M_E_CPU0_SB_DQ<11>  DQ_B11  @S9S_MB_2U_LIB.S9S_MB_2U(SCH_1):M_E_CPU0_SB_DQ<11>
  256  M_E_CPU0_SB_DQ<10>  DQ_B10  @S9S_MB_2U_LIB.S9S_MB_2U(SCH_1):M_E_CPU0_SB_DQ<10>
  100  M_E_CPU0_SB_DQ<0>  DQ_B0  @S9S_MB_2U_LIB.S9S_MB_2U(SCH_1):M_E_CPU0_SB_DQ<0>
  229  M_E_CPU0_SB_CS_N<3>  CS1_N_B  @S9S_MB_2U_LIB.S9S_MB_2U(SCH_1):M_E_CPU0_SB_CS_N<3>
   84  M_E_CPU0_SB_CS_N<2>  CS0_N_B  @S9S_MB_2U_LIB.S9S_MB_2U(SCH_1):M_E_CPU0_SB_CS_N<2>
  236  M_E_CPU0_SB_CB<7>  CB_B7  @S9S_MB_2U_LIB.S9S_MB_2U(SCH_1):M_E_CPU0_SB_CB<7>
  234  M_E_CPU0_SB_CB<6>  CB_B6  @S9S_MB_2U_LIB.S9S_MB_2U(SCH_1):M_E_CPU0_SB_CB<6>
   91  M_E_CPU0_SB_CB<5>  CB_B5  @S9S_MB_2U_LIB.S9S_MB_2U(SCH_1):M_E_CPU0_SB_CB<5>
   89  M_E_CPU0_SB_CB<4>  CB_B4  @S9S_MB_2U_LIB.S9S_MB_2U(SCH_1):M_E_CPU0_SB_CB<4>
  243  M_E_CPU0_SB_CB<3>  CB_B3  @S9S_MB_2U_LIB.S9S_MB_2U(SCH_1):M_E_CPU0_SB_CB<3>
  241  M_E_CPU0_SB_CB<2>  CB_B2  @S9S_MB_2U_LIB.S9S_MB_2U(SCH_1):M_E_CPU0_SB_CB<2>
   98  M_E_CPU0_SB_CB<1>  CB_B1  @S9S_MB_2U_LIB.S9S_MB_2U(SCH_1):M_E_CPU0_SB_CB<1>
   96  M_E_CPU0_SB_CB<0>  CB_B0  @S9S_MB_2U_LIB.S9S_MB_2U(SCH_1):M_E_CPU0_SB_CB<0>
   82  M_E_CPU0_SB_CA<6>  CA6_B  @S9S_MB_2U_LIB.S9S_MB_2U(SCH_1):M_E_CPU0_SB_CA<6>
  225  M_E_CPU0_SB_CA<5>  CA5_B  @S9S_MB_2U_LIB.S9S_MB_2U(SCH_1):M_E_CPU0_SB_CA<5>
   80  M_E_CPU0_SB_CA<4>  CA4_B  @S9S_MB_2U_LIB.S9S_MB_2U(SCH_1):M_E_CPU0_SB_CA<4>
  223  M_E_CPU0_SB_CA<3>  CA3_B  @S9S_MB_2U_LIB.S9S_MB_2U(SCH_1):M_E_CPU0_SB_CA<3>
   78  M_E_CPU0_SB_CA<2>  CA2_B  @S9S_MB_2U_LIB.S9S_MB_2U(SCH_1):M_E_CPU0_SB_CA<2>
  221  M_E_CPU0_SB_CA<1>  CA1_B  @S9S_MB_2U_LIB.S9S_MB_2U(SCH_1):M_E_CPU0_SB_CA<1>
   76  M_E_CPU0_SB_CA<0>  CA0_B  @S9S_MB_2U_LIB.S9S_MB_2U(SCH_1):M_E_CPU0_SB_CA<0>
   86  M_E_CPU0_SA_RSP<1>  LBD||RSP_N_A  @S9S_MB_2U_LIB.S9S_MB_2U(SCH_1):M_E_CPU0_SA_RSP<1>
   74  M_E_CPU0_SA_PAR  PAR_A  @S9S_MB_2U_LIB.S9S_MB_2U(SCH_1):M_E_CPU0_SA_PAR
   20  M_E_CPU0_SA_DQ<9>  DQ_A9  @S9S_MB_2U_LIB.S9S_MB_2U(SCH_1):M_E_CPU0_SA_DQ<9>
   18  M_E_CPU0_SA_DQ<8>  DQ_A8  @S9S_MB_2U_LIB.S9S_MB_2U(SCH_1):M_E_CPU0_SA_DQ<8>
  161  M_E_CPU0_SA_DQ<7>  DQ_A7  @S9S_MB_2U_LIB.S9S_MB_2U(SCH_1):M_E_CPU0_SA_DQ<7>
  159  M_E_CPU0_SA_DQ<6>  DQ_A6  @S9S_MB_2U_LIB.S9S_MB_2U(SCH_1):M_E_CPU0_SA_DQ<6>
   16  M_E_CPU0_SA_DQ<5>  DQ_A5  @S9S_MB_2U_LIB.S9S_MB_2U(SCH_1):M_E_CPU0_SA_DQ<5>
   14  M_E_CPU0_SA_DQ<4>  DQ_A4  @S9S_MB_2U_LIB.S9S_MB_2U(SCH_1):M_E_CPU0_SA_DQ<4>
  154  M_E_CPU0_SA_DQ<3>  DQ_A3  @S9S_MB_2U_LIB.S9S_MB_2U(SCH_1):M_E_CPU0_SA_DQ<3>
  194  M_E_CPU0_SA_DQ<31>  DQ_A31  @S9S_MB_2U_LIB.S9S_MB_2U(SCH_1):M_E_CPU0_SA_DQ<31>
  192  M_E_CPU0_SA_DQ<30>  DQ_A30  @S9S_MB_2U_LIB.S9S_MB_2U(SCH_1):M_E_CPU0_SA_DQ<30>
  152  M_E_CPU0_SA_DQ<2>  DQ_A2  @S9S_MB_2U_LIB.S9S_MB_2U(SCH_1):M_E_CPU0_SA_DQ<2>
   49  M_E_CPU0_SA_DQ<29>  DQ_A29  @S9S_MB_2U_LIB.S9S_MB_2U(SCH_1):M_E_CPU0_SA_DQ<29>
   47  M_E_CPU0_SA_DQ<28>  DQ_A28  @S9S_MB_2U_LIB.S9S_MB_2U(SCH_1):M_E_CPU0_SA_DQ<28>
  187  M_E_CPU0_SA_DQ<27>  DQ_A27  @S9S_MB_2U_LIB.S9S_MB_2U(SCH_1):M_E_CPU0_SA_DQ<27>
  185  M_E_CPU0_SA_DQ<26>  DQ_A26  @S9S_MB_2U_LIB.S9S_MB_2U(SCH_1):M_E_CPU0_SA_DQ<26>
   42  M_E_CPU0_SA_DQ<25>  DQ_A25  @S9S_MB_2U_LIB.S9S_MB_2U(SCH_1):M_E_CPU0_SA_DQ<25>
   40  M_E_CPU0_SA_DQ<24>  DQ_A24  @S9S_MB_2U_LIB.S9S_MB_2U(SCH_1):M_E_CPU0_SA_DQ<24>
  183  M_E_CPU0_SA_DQ<23>  DQ_A23  @S9S_MB_2U_LIB.S9S_MB_2U(SCH_1):M_E_CPU0_SA_DQ<23>
  181  M_E_CPU0_SA_DQ<22>  DQ_A22  @S9S_MB_2U_LIB.S9S_MB_2U(SCH_1):M_E_CPU0_SA_DQ<22>
   38  M_E_CPU0_SA_DQ<21>  DQ_A21  @S9S_MB_2U_LIB.S9S_MB_2U(SCH_1):M_E_CPU0_SA_DQ<21>
   36  M_E_CPU0_SA_DQ<20>  DQ_A20  @S9S_MB_2U_LIB.S9S_MB_2U(SCH_1):M_E_CPU0_SA_DQ<20>
    9  M_E_CPU0_SA_DQ<1>  DQ_A1  @S9S_MB_2U_LIB.S9S_MB_2U(SCH_1):M_E_CPU0_SA_DQ<1>
  176  M_E_CPU0_SA_DQ<19>  DQ_A19  @S9S_MB_2U_LIB.S9S_MB_2U(SCH_1):M_E_CPU0_SA_DQ<19>
  174  M_E_CPU0_SA_DQ<18>  DQ_A18  @S9S_MB_2U_LIB.S9S_MB_2U(SCH_1):M_E_CPU0_SA_DQ<18>
   31  M_E_CPU0_SA_DQ<17>  DQ_A17  @S9S_MB_2U_LIB.S9S_MB_2U(SCH_1):M_E_CPU0_SA_DQ<17>
   29  M_E_CPU0_SA_DQ<16>  DQ_A16  @S9S_MB_2U_LIB.S9S_MB_2U(SCH_1):M_E_CPU0_SA_DQ<16>
  172  M_E_CPU0_SA_DQ<15>  DQ_A15  @S9S_MB_2U_LIB.S9S_MB_2U(SCH_1):M_E_CPU0_SA_DQ<15>
  170  M_E_CPU0_SA_DQ<14>  DQ_A14  @S9S_MB_2U_LIB.S9S_MB_2U(SCH_1):M_E_CPU0_SA_DQ<14>
   27  M_E_CPU0_SA_DQ<13>  DQ_A13  @S9S_MB_2U_LIB.S9S_MB_2U(SCH_1):M_E_CPU0_SA_DQ<13>
   25  M_E_CPU0_SA_DQ<12>  DQ_A12  @S9S_MB_2U_LIB.S9S_MB_2U(SCH_1):M_E_CPU0_SA_DQ<12>
  165  M_E_CPU0_SA_DQ<11>  DQ_A11  @S9S_MB_2U_LIB.S9S_MB_2U(SCH_1):M_E_CPU0_SA_DQ<11>
  163  M_E_CPU0_SA_DQ<10>  DQ_A10  @S9S_MB_2U_LIB.S9S_MB_2U(SCH_1):M_E_CPU0_SA_DQ<10>
    7  M_E_CPU0_SA_DQ<0>  DQ_A0  @S9S_MB_2U_LIB.S9S_MB_2U(SCH_1):M_E_CPU0_SA_DQ<0>
  209  M_E_CPU0_SA_CS_N<3>  CS1_N_A  @S9S_MB_2U_LIB.S9S_MB_2U(SCH_1):M_E_CPU0_SA_CS_N<3>
   64  M_E_CPU0_SA_CS_N<2>  CS0_N_A  @S9S_MB_2U_LIB.S9S_MB_2U(SCH_1):M_E_CPU0_SA_CS_N<2>
  205  M_E_CPU0_SA_CB<7>  CB_A7  @S9S_MB_2U_LIB.S9S_MB_2U(SCH_1):M_E_CPU0_SA_CB<7>
  203  M_E_CPU0_SA_CB<6>  CB_A6  @S9S_MB_2U_LIB.S9S_MB_2U(SCH_1):M_E_CPU0_SA_CB<6>
   60  M_E_CPU0_SA_CB<5>  CB_A5  @S9S_MB_2U_LIB.S9S_MB_2U(SCH_1):M_E_CPU0_SA_CB<5>
   58  M_E_CPU0_SA_CB<4>  CB_A4  @S9S_MB_2U_LIB.S9S_MB_2U(SCH_1):M_E_CPU0_SA_CB<4>
  198  M_E_CPU0_SA_CB<3>  CB_A3  @S9S_MB_2U_LIB.S9S_MB_2U(SCH_1):M_E_CPU0_SA_CB<3>
  196  M_E_CPU0_SA_CB<2>  CB_A2  @S9S_MB_2U_LIB.S9S_MB_2U(SCH_1):M_E_CPU0_SA_CB<2>
   53  M_E_CPU0_SA_CB<1>  CB_A1  @S9S_MB_2U_LIB.S9S_MB_2U(SCH_1):M_E_CPU0_SA_CB<1>
   51  M_E_CPU0_SA_CB<0>  CB_A0  @S9S_MB_2U_LIB.S9S_MB_2U(SCH_1):M_E_CPU0_SA_CB<0>
   72  M_E_CPU0_SA_CA<6>  CA6_A  @S9S_MB_2U_LIB.S9S_MB_2U(SCH_1):M_E_CPU0_SA_CA<6>
  215  M_E_CPU0_SA_CA<5>  CA5_A  @S9S_MB_2U_LIB.S9S_MB_2U(SCH_1):M_E_CPU0_SA_CA<5>
   70  M_E_CPU0_SA_CA<4>  CA4_A  @S9S_MB_2U_LIB.S9S_MB_2U(SCH_1):M_E_CPU0_SA_CA<4>
  213  M_E_CPU0_SA_CA<3>  CA3_A  @S9S_MB_2U_LIB.S9S_MB_2U(SCH_1):M_E_CPU0_SA_CA<3>
   68  M_E_CPU0_SA_CA<2>  CA2_A  @S9S_MB_2U_LIB.S9S_MB_2U(SCH_1):M_E_CPU0_SA_CA<2>
  211  M_E_CPU0_SA_CA<1>  CA1_A  @S9S_MB_2U_LIB.S9S_MB_2U(SCH_1):M_E_CPU0_SA_CA<1>
   66  M_E_CPU0_SA_CA<0>  CA0_A  @S9S_MB_2U_LIB.S9S_MB_2U(SCH_1):M_E_CPU0_SA_CA<0>
  217  M_E_CPU0_CLK_DP<1>   CK_P  @S9S_MB_2U_LIB.S9S_MB_2U(SCH_1):M_E_CPU0_CLK_DP<1>
  218  M_E_CPU0_CLK_DN<1>   CK_N  @S9S_MB_2U_LIB.S9S_MB_2U(SCH_1):M_E_CPU0_CLK_DN<1>
   62  M_E_CPU0_ALERT_N  ALERT_N  @S9S_MB_2U_LIB.S9S_MB_2U(SCH_1):M_E_CPU0_ALERT_N
    5  I3C_SPD_DDREFGH_CPU0_LVC1_SDA   HSDA  @S9S_MB_2U_LIB.S9S_MB_2U(SCH_1):I3C_SPD_DDREFGH_CPU0_LVC1_SDA
    4  I3C_SPD_DDREFGH_CPU0_LVC1_SCL   HSCL  @S9S_MB_2U_LIB.S9S_MB_2U(SCH_1):I3C_SPD_DDREFGH_CPU0_LVC1_SCL

SCONN288_ADR50001P013C01  I175  J11    [SCONN288_ADR50001P013C01-SCONNA]
  146  P12V_S3_AUX_CPU0_NVDIMM  VIN_BULK2  @S9S_MB_2U_LIB.S9S_MB_2U(SCH_1):P12V_S3_AUX_CPU0_NVDIMM
  145  P12V_S3_AUX_CPU0_NVDIMM  VIN_BULK1  @S9S_MB_2U_LIB.S9S_MB_2U(SCH_1):P12V_S3_AUX_CPU0_NVDIMM
    1  P12V_S3_AUX_CPU0_NVDIMM  VIN_BULK0  @S9S_MB_2U_LIB.S9S_MB_2U(SCH_1):P12V_S3_AUX_CPU0_NVDIMM
  288  GND            VSS126  @S9S_MB_2U_LIB.S9S_MB_2U(SCH_1):GND
  286  GND            VSS125  @S9S_MB_2U_LIB.S9S_MB_2U(SCH_1):GND
  284  GND            VSS124  @S9S_MB_2U_LIB.S9S_MB_2U(SCH_1):GND
  281  GND            VSS123  @S9S_MB_2U_LIB.S9S_MB_2U(SCH_1):GND
  279  GND            VSS122  @S9S_MB_2U_LIB.S9S_MB_2U(SCH_1):GND
  277  GND            VSS121  @S9S_MB_2U_LIB.S9S_MB_2U(SCH_1):GND
  275  GND            VSS120  @S9S_MB_2U_LIB.S9S_MB_2U(SCH_1):GND
  273  GND            VSS119  @S9S_MB_2U_LIB.S9S_MB_2U(SCH_1):GND
  270  GND            VSS118  @S9S_MB_2U_LIB.S9S_MB_2U(SCH_1):GND
  268  GND            VSS117  @S9S_MB_2U_LIB.S9S_MB_2U(SCH_1):GND
  266  GND            VSS116  @S9S_MB_2U_LIB.S9S_MB_2U(SCH_1):GND
  264  GND            VSS115  @S9S_MB_2U_LIB.S9S_MB_2U(SCH_1):GND
  262  GND            VSS114  @S9S_MB_2U_LIB.S9S_MB_2U(SCH_1):GND
  259  GND            VSS113  @S9S_MB_2U_LIB.S9S_MB_2U(SCH_1):GND
  257  GND            VSS112  @S9S_MB_2U_LIB.S9S_MB_2U(SCH_1):GND
  255  GND            VSS111  @S9S_MB_2U_LIB.S9S_MB_2U(SCH_1):GND
  253  GND            VSS110  @S9S_MB_2U_LIB.S9S_MB_2U(SCH_1):GND
  251  GND            VSS109  @S9S_MB_2U_LIB.S9S_MB_2U(SCH_1):GND
  248  GND            VSS108  @S9S_MB_2U_LIB.S9S_MB_2U(SCH_1):GND
  246  GND            VSS107  @S9S_MB_2U_LIB.S9S_MB_2U(SCH_1):GND
  244  GND            VSS106  @S9S_MB_2U_LIB.S9S_MB_2U(SCH_1):GND
  242  GND            VSS105  @S9S_MB_2U_LIB.S9S_MB_2U(SCH_1):GND
  240  GND            VSS104  @S9S_MB_2U_LIB.S9S_MB_2U(SCH_1):GND
  237  GND            VSS103  @S9S_MB_2U_LIB.S9S_MB_2U(SCH_1):GND
  235  GND            VSS102  @S9S_MB_2U_LIB.S9S_MB_2U(SCH_1):GND
  233  GND            VSS101  @S9S_MB_2U_LIB.S9S_MB_2U(SCH_1):GND
  230  GND            VSS100  @S9S_MB_2U_LIB.S9S_MB_2U(SCH_1):GND
  228  GND            VSS99  @S9S_MB_2U_LIB.S9S_MB_2U(SCH_1):GND
  226  GND            VSS98  @S9S_MB_2U_LIB.S9S_MB_2U(SCH_1):GND
  224  GND            VSS97  @S9S_MB_2U_LIB.S9S_MB_2U(SCH_1):GND
  222  GND            VSS96  @S9S_MB_2U_LIB.S9S_MB_2U(SCH_1):GND
  219  GND            VSS95  @S9S_MB_2U_LIB.S9S_MB_2U(SCH_1):GND
  216  GND            VSS94  @S9S_MB_2U_LIB.S9S_MB_2U(SCH_1):GND
  214  GND            VSS93  @S9S_MB_2U_LIB.S9S_MB_2U(SCH_1):GND
  212  GND            VSS92  @S9S_MB_2U_LIB.S9S_MB_2U(SCH_1):GND
  210  GND            VSS91  @S9S_MB_2U_LIB.S9S_MB_2U(SCH_1):GND
  208  GND            VSS90  @S9S_MB_2U_LIB.S9S_MB_2U(SCH_1):GND
  206  GND            VSS89  @S9S_MB_2U_LIB.S9S_MB_2U(SCH_1):GND
  204  GND            VSS88  @S9S_MB_2U_LIB.S9S_MB_2U(SCH_1):GND
  202  GND            VSS87  @S9S_MB_2U_LIB.S9S_MB_2U(SCH_1):GND
  199  GND            VSS86  @S9S_MB_2U_LIB.S9S_MB_2U(SCH_1):GND
  197  GND            VSS85  @S9S_MB_2U_LIB.S9S_MB_2U(SCH_1):GND
  195  GND            VSS84  @S9S_MB_2U_LIB.S9S_MB_2U(SCH_1):GND
  193  GND            VSS83  @S9S_MB_2U_LIB.S9S_MB_2U(SCH_1):GND
  191  GND            VSS82  @S9S_MB_2U_LIB.S9S_MB_2U(SCH_1):GND
  188  GND            VSS81  @S9S_MB_2U_LIB.S9S_MB_2U(SCH_1):GND
  186  GND            VSS80  @S9S_MB_2U_LIB.S9S_MB_2U(SCH_1):GND
  184  GND            VSS79  @S9S_MB_2U_LIB.S9S_MB_2U(SCH_1):GND
  182  GND            VSS78  @S9S_MB_2U_LIB.S9S_MB_2U(SCH_1):GND
  180  GND            VSS77  @S9S_MB_2U_LIB.S9S_MB_2U(SCH_1):GND
  177  GND            VSS76  @S9S_MB_2U_LIB.S9S_MB_2U(SCH_1):GND
  175  GND            VSS75  @S9S_MB_2U_LIB.S9S_MB_2U(SCH_1):GND
  173  GND            VSS74  @S9S_MB_2U_LIB.S9S_MB_2U(SCH_1):GND
  171  GND            VSS73  @S9S_MB_2U_LIB.S9S_MB_2U(SCH_1):GND
  169  GND            VSS72  @S9S_MB_2U_LIB.S9S_MB_2U(SCH_1):GND
  166  GND            VSS71  @S9S_MB_2U_LIB.S9S_MB_2U(SCH_1):GND
  164  GND            VSS70  @S9S_MB_2U_LIB.S9S_MB_2U(SCH_1):GND
  162  GND            VSS69  @S9S_MB_2U_LIB.S9S_MB_2U(SCH_1):GND
  160  GND            VSS68  @S9S_MB_2U_LIB.S9S_MB_2U(SCH_1):GND
  158  GND            VSS67  @S9S_MB_2U_LIB.S9S_MB_2U(SCH_1):GND
  155  GND            VSS66  @S9S_MB_2U_LIB.S9S_MB_2U(SCH_1):GND
  153  GND            VSS65  @S9S_MB_2U_LIB.S9S_MB_2U(SCH_1):GND
  151  GND            VSS64  @S9S_MB_2U_LIB.S9S_MB_2U(SCH_1):GND
  143  GND            VSS63  @S9S_MB_2U_LIB.S9S_MB_2U(SCH_1):GND
  141  GND            VSS62  @S9S_MB_2U_LIB.S9S_MB_2U(SCH_1):GND
  139  GND            VSS61  @S9S_MB_2U_LIB.S9S_MB_2U(SCH_1):GND
  136  GND            VSS60  @S9S_MB_2U_LIB.S9S_MB_2U(SCH_1):GND
  134  GND            VSS59  @S9S_MB_2U_LIB.S9S_MB_2U(SCH_1):GND
  132  GND            VSS58  @S9S_MB_2U_LIB.S9S_MB_2U(SCH_1):GND
  130  GND            VSS57  @S9S_MB_2U_LIB.S9S_MB_2U(SCH_1):GND
  128  GND            VSS56  @S9S_MB_2U_LIB.S9S_MB_2U(SCH_1):GND
  125  GND            VSS55  @S9S_MB_2U_LIB.S9S_MB_2U(SCH_1):GND
  123  GND            VSS54  @S9S_MB_2U_LIB.S9S_MB_2U(SCH_1):GND
  121  GND            VSS53  @S9S_MB_2U_LIB.S9S_MB_2U(SCH_1):GND
  119  GND            VSS52  @S9S_MB_2U_LIB.S9S_MB_2U(SCH_1):GND
  117  GND            VSS51  @S9S_MB_2U_LIB.S9S_MB_2U(SCH_1):GND
  114  GND            VSS50  @S9S_MB_2U_LIB.S9S_MB_2U(SCH_1):GND
  112  GND            VSS49  @S9S_MB_2U_LIB.S9S_MB_2U(SCH_1):GND
  110  GND            VSS48  @S9S_MB_2U_LIB.S9S_MB_2U(SCH_1):GND
  108  GND            VSS47  @S9S_MB_2U_LIB.S9S_MB_2U(SCH_1):GND
  106  GND            VSS46  @S9S_MB_2U_LIB.S9S_MB_2U(SCH_1):GND
  103  GND            VSS45  @S9S_MB_2U_LIB.S9S_MB_2U(SCH_1):GND
  101  GND            VSS44  @S9S_MB_2U_LIB.S9S_MB_2U(SCH_1):GND
   99  GND            VSS43  @S9S_MB_2U_LIB.S9S_MB_2U(SCH_1):GND
   97  GND            VSS42  @S9S_MB_2U_LIB.S9S_MB_2U(SCH_1):GND
   95  GND            VSS41  @S9S_MB_2U_LIB.S9S_MB_2U(SCH_1):GND
   92  GND            VSS40  @S9S_MB_2U_LIB.S9S_MB_2U(SCH_1):GND
   90  GND            VSS39  @S9S_MB_2U_LIB.S9S_MB_2U(SCH_1):GND
   88  GND            VSS38  @S9S_MB_2U_LIB.S9S_MB_2U(SCH_1):GND
   85  GND            VSS37  @S9S_MB_2U_LIB.S9S_MB_2U(SCH_1):GND
   83  GND            VSS36  @S9S_MB_2U_LIB.S9S_MB_2U(SCH_1):GND
   81  GND            VSS35  @S9S_MB_2U_LIB.S9S_MB_2U(SCH_1):GND
   79  GND            VSS34  @S9S_MB_2U_LIB.S9S_MB_2U(SCH_1):GND
   77  GND            VSS33  @S9S_MB_2U_LIB.S9S_MB_2U(SCH_1):GND
   75  GND            VSS32  @S9S_MB_2U_LIB.S9S_MB_2U(SCH_1):GND
   73  GND            VSS31  @S9S_MB_2U_LIB.S9S_MB_2U(SCH_1):GND
   71  GND            VSS30  @S9S_MB_2U_LIB.S9S_MB_2U(SCH_1):GND
   69  GND            VSS29  @S9S_MB_2U_LIB.S9S_MB_2U(SCH_1):GND
   67  GND            VSS28  @S9S_MB_2U_LIB.S9S_MB_2U(SCH_1):GND
   65  GND            VSS27  @S9S_MB_2U_LIB.S9S_MB_2U(SCH_1):GND
   63  GND            VSS26  @S9S_MB_2U_LIB.S9S_MB_2U(SCH_1):GND
   61  GND            VSS25  @S9S_MB_2U_LIB.S9S_MB_2U(SCH_1):GND
   59  GND            VSS24  @S9S_MB_2U_LIB.S9S_MB_2U(SCH_1):GND
   57  GND            VSS23  @S9S_MB_2U_LIB.S9S_MB_2U(SCH_1):GND
   54  GND            VSS22  @S9S_MB_2U_LIB.S9S_MB_2U(SCH_1):GND
   52  GND            VSS21  @S9S_MB_2U_LIB.S9S_MB_2U(SCH_1):GND
   50  GND            VSS20  @S9S_MB_2U_LIB.S9S_MB_2U(SCH_1):GND
   48  GND            VSS19  @S9S_MB_2U_LIB.S9S_MB_2U(SCH_1):GND
   46  GND            VSS18  @S9S_MB_2U_LIB.S9S_MB_2U(SCH_1):GND
   43  GND            VSS17  @S9S_MB_2U_LIB.S9S_MB_2U(SCH_1):GND
   41  GND            VSS16  @S9S_MB_2U_LIB.S9S_MB_2U(SCH_1):GND
   39  GND            VSS15  @S9S_MB_2U_LIB.S9S_MB_2U(SCH_1):GND
   37  GND            VSS14  @S9S_MB_2U_LIB.S9S_MB_2U(SCH_1):GND
   35  GND            VSS13  @S9S_MB_2U_LIB.S9S_MB_2U(SCH_1):GND
   32  GND            VSS12  @S9S_MB_2U_LIB.S9S_MB_2U(SCH_1):GND
   30  GND            VSS11  @S9S_MB_2U_LIB.S9S_MB_2U(SCH_1):GND
   28  GND            VSS10  @S9S_MB_2U_LIB.S9S_MB_2U(SCH_1):GND
   26  GND             VSS9  @S9S_MB_2U_LIB.S9S_MB_2U(SCH_1):GND
   24  GND             VSS8  @S9S_MB_2U_LIB.S9S_MB_2U(SCH_1):GND
   21  GND             VSS7  @S9S_MB_2U_LIB.S9S_MB_2U(SCH_1):GND
   19  GND             VSS6  @S9S_MB_2U_LIB.S9S_MB_2U(SCH_1):GND
   17  GND             VSS5  @S9S_MB_2U_LIB.S9S_MB_2U(SCH_1):GND
   15  GND             VSS4  @S9S_MB_2U_LIB.S9S_MB_2U(SCH_1):GND
   13  GND             VSS3  @S9S_MB_2U_LIB.S9S_MB_2U(SCH_1):GND
   10  GND             VSS2  @S9S_MB_2U_LIB.S9S_MB_2U(SCH_1):GND
    8  GND             VSS1  @S9S_MB_2U_LIB.S9S_MB_2U(SCH_1):GND
    6  GND             VSS0  @S9S_MB_2U_LIB.S9S_MB_2U(SCH_1):GND
   G3  GND               G3  @S9S_MB_2U_LIB.S9S_MB_2U(SCH_1):GND
   G2  GND               G2  @S9S_MB_2U_LIB.S9S_MB_2U(SCH_1):GND
   G1  GND               G1  @S9S_MB_2U_LIB.S9S_MB_2U(SCH_1):GND

SCONN288_ADR50001P013C01  I126  J11    [SCONN288_ADR50001P013C01-SCONNA]
   93  M_F_CPU0_SB_DQS_DP<9>  DQS9_B_P  @S9S_MB_2U_LIB.S9S_MB_2U(SCH_1):M_F_CPU0_SB_DQS_DP<9>
  283  M_F_CPU0_SB_DQS_DP<8>  DQS8_B_P  @S9S_MB_2U_LIB.S9S_MB_2U(SCH_1):M_F_CPU0_SB_DQS_DP<8>
  272  M_F_CPU0_SB_DQS_DP<7>  DQS7_B_P  @S9S_MB_2U_LIB.S9S_MB_2U(SCH_1):M_F_CPU0_SB_DQS_DP<7>
  261  M_F_CPU0_SB_DQS_DP<6>  DQS6_B_P  @S9S_MB_2U_LIB.S9S_MB_2U(SCH_1):M_F_CPU0_SB_DQS_DP<6>
  250  M_F_CPU0_SB_DQS_DP<5>  DQS5_B_P  @S9S_MB_2U_LIB.S9S_MB_2U(SCH_1):M_F_CPU0_SB_DQS_DP<5>
  239  M_F_CPU0_SB_DQS_DP<4>  DQS4_B_P  @S9S_MB_2U_LIB.S9S_MB_2U(SCH_1):M_F_CPU0_SB_DQS_DP<4>
  137  M_F_CPU0_SB_DQS_DP<3>  DQS3_B_P  @S9S_MB_2U_LIB.S9S_MB_2U(SCH_1):M_F_CPU0_SB_DQS_DP<3>
  126  M_F_CPU0_SB_DQS_DP<2>  DQS2_B_P  @S9S_MB_2U_LIB.S9S_MB_2U(SCH_1):M_F_CPU0_SB_DQS_DP<2>
  115  M_F_CPU0_SB_DQS_DP<1>  DQS1_B_P  @S9S_MB_2U_LIB.S9S_MB_2U(SCH_1):M_F_CPU0_SB_DQS_DP<1>
  104  M_F_CPU0_SB_DQS_DP<0>  DQS0_B_P  @S9S_MB_2U_LIB.S9S_MB_2U(SCH_1):M_F_CPU0_SB_DQS_DP<0>
   94  M_F_CPU0_SB_DQS_DN<9>  DQS9_B_N  @S9S_MB_2U_LIB.S9S_MB_2U(SCH_1):M_F_CPU0_SB_DQS_DN<9>
  282  M_F_CPU0_SB_DQS_DN<8>  DQS8_B_N  @S9S_MB_2U_LIB.S9S_MB_2U(SCH_1):M_F_CPU0_SB_DQS_DN<8>
  271  M_F_CPU0_SB_DQS_DN<7>  DQS7_B_N  @S9S_MB_2U_LIB.S9S_MB_2U(SCH_1):M_F_CPU0_SB_DQS_DN<7>
  260  M_F_CPU0_SB_DQS_DN<6>  DQS6_B_N  @S9S_MB_2U_LIB.S9S_MB_2U(SCH_1):M_F_CPU0_SB_DQS_DN<6>
  249  M_F_CPU0_SB_DQS_DN<5>  DQS5_B_N  @S9S_MB_2U_LIB.S9S_MB_2U(SCH_1):M_F_CPU0_SB_DQS_DN<5>
  238  M_F_CPU0_SB_DQS_DN<4>  DQS4_B_N  @S9S_MB_2U_LIB.S9S_MB_2U(SCH_1):M_F_CPU0_SB_DQS_DN<4>
  138  M_F_CPU0_SB_DQS_DN<3>  DQS3_B_N  @S9S_MB_2U_LIB.S9S_MB_2U(SCH_1):M_F_CPU0_SB_DQS_DN<3>
  127  M_F_CPU0_SB_DQS_DN<2>  DQS2_B_N  @S9S_MB_2U_LIB.S9S_MB_2U(SCH_1):M_F_CPU0_SB_DQS_DN<2>
  116  M_F_CPU0_SB_DQS_DN<1>  DQS1_B_N  @S9S_MB_2U_LIB.S9S_MB_2U(SCH_1):M_F_CPU0_SB_DQS_DN<1>
  105  M_F_CPU0_SB_DQS_DN<0>  DQS0_B_N  @S9S_MB_2U_LIB.S9S_MB_2U(SCH_1):M_F_CPU0_SB_DQS_DN<0>
  201  M_F_CPU0_SA_DQS_DP<9>  DQS9_A_P  @S9S_MB_2U_LIB.S9S_MB_2U(SCH_1):M_F_CPU0_SA_DQS_DP<9>
  190  M_F_CPU0_SA_DQS_DP<8>  DQS8_A_P  @S9S_MB_2U_LIB.S9S_MB_2U(SCH_1):M_F_CPU0_SA_DQS_DP<8>
  179  M_F_CPU0_SA_DQS_DP<7>  DQS7_A_P  @S9S_MB_2U_LIB.S9S_MB_2U(SCH_1):M_F_CPU0_SA_DQS_DP<7>
  168  M_F_CPU0_SA_DQS_DP<6>  DQS6_A_P  @S9S_MB_2U_LIB.S9S_MB_2U(SCH_1):M_F_CPU0_SA_DQS_DP<6>
  157  M_F_CPU0_SA_DQS_DP<5>  DQS5_A_P  @S9S_MB_2U_LIB.S9S_MB_2U(SCH_1):M_F_CPU0_SA_DQS_DP<5>
   55  M_F_CPU0_SA_DQS_DP<4>  DQS4_A_P  @S9S_MB_2U_LIB.S9S_MB_2U(SCH_1):M_F_CPU0_SA_DQS_DP<4>
   44  M_F_CPU0_SA_DQS_DP<3>  DQS3_A_P  @S9S_MB_2U_LIB.S9S_MB_2U(SCH_1):M_F_CPU0_SA_DQS_DP<3>
   33  M_F_CPU0_SA_DQS_DP<2>  DQS2_A_P  @S9S_MB_2U_LIB.S9S_MB_2U(SCH_1):M_F_CPU0_SA_DQS_DP<2>
   22  M_F_CPU0_SA_DQS_DP<1>  DQS1_A_P  @S9S_MB_2U_LIB.S9S_MB_2U(SCH_1):M_F_CPU0_SA_DQS_DP<1>
   11  M_F_CPU0_SA_DQS_DP<0>  DQS0_A_P  @S9S_MB_2U_LIB.S9S_MB_2U(SCH_1):M_F_CPU0_SA_DQS_DP<0>
  200  M_F_CPU0_SA_DQS_DN<9>  DQS9_A_N  @S9S_MB_2U_LIB.S9S_MB_2U(SCH_1):M_F_CPU0_SA_DQS_DN<9>
  189  M_F_CPU0_SA_DQS_DN<8>  DQS8_A_N  @S9S_MB_2U_LIB.S9S_MB_2U(SCH_1):M_F_CPU0_SA_DQS_DN<8>
  178  M_F_CPU0_SA_DQS_DN<7>  DQS7_A_N  @S9S_MB_2U_LIB.S9S_MB_2U(SCH_1):M_F_CPU0_SA_DQS_DN<7>
  167  M_F_CPU0_SA_DQS_DN<6>  DQS6_A_N  @S9S_MB_2U_LIB.S9S_MB_2U(SCH_1):M_F_CPU0_SA_DQS_DN<6>
  156  M_F_CPU0_SA_DQS_DN<5>  DQS5_A_N  @S9S_MB_2U_LIB.S9S_MB_2U(SCH_1):M_F_CPU0_SA_DQS_DN<5>
   56  M_F_CPU0_SA_DQS_DN<4>  DQS4_A_N  @S9S_MB_2U_LIB.S9S_MB_2U(SCH_1):M_F_CPU0_SA_DQS_DN<4>
   45  M_F_CPU0_SA_DQS_DN<3>  DQS3_A_N  @S9S_MB_2U_LIB.S9S_MB_2U(SCH_1):M_F_CPU0_SA_DQS_DN<3>
   34  M_F_CPU0_SA_DQS_DN<2>  DQS2_A_N  @S9S_MB_2U_LIB.S9S_MB_2U(SCH_1):M_F_CPU0_SA_DQS_DN<2>
   23  M_F_CPU0_SA_DQS_DN<1>  DQS1_A_N  @S9S_MB_2U_LIB.S9S_MB_2U(SCH_1):M_F_CPU0_SA_DQS_DN<1>
   12  M_F_CPU0_SA_DQS_DN<0>  DQS0_A_N  @S9S_MB_2U_LIB.S9S_MB_2U(SCH_1):M_F_CPU0_SA_DQS_DN<0>

SCONN288_ADR50001P013C01  I25  J11    [SCONN288_ADR50001P013C01-SCONNA]
  232  NC              RFU6  NC
  231  NC              RFU5  NC
  220  NC              RFU4  NC
  150  NC              RFU3  NC
  149  NC              RFU2  NC
  144  NC              RFU1  NC
    2  NC              RFU0  NC
  207  RST_M_EF_CPU0_FPGA_N  RESET_N  @S9S_MB_2U_LIB.S9S_MB_2U(SCH_1):RST_M_EF_CPU0_FPGA_N
  147  PWRGD_CHF_CPU0_DIMM1  PWR_GOOD||FAIL_N  @S9S_MB_2U_LIB.S9S_MB_2U(SCH_1):PWRGD_CHF_CPU0_DIMM1
  148  PD_CHF_CPU0_DIMM1_SAA    HAS  @S9S_MB_2U_LIB.S9S_MB_2U(SCH_1):PD_CHF_CPU0_DIMM1_SAA
    3  P3V3_AUX       VIN_MGMT  @S9S_MB_2U_LIB.S9S_MB_2U(SCH_1):P3V3_AUX
   87  M_F_CPU0_SB_RSP<0>  LBS||RSP_N_B  @S9S_MB_2U_LIB.S9S_MB_2U(SCH_1):M_F_CPU0_SB_RSP<0>
  227  M_F_CPU0_SB_PAR  PAR_B  @S9S_MB_2U_LIB.S9S_MB_2U(SCH_1):M_F_CPU0_SB_PAR
  113  M_F_CPU0_SB_DQ<9>  DQ_B9  @S9S_MB_2U_LIB.S9S_MB_2U(SCH_1):M_F_CPU0_SB_DQ<9>
  111  M_F_CPU0_SB_DQ<8>  DQ_B8  @S9S_MB_2U_LIB.S9S_MB_2U(SCH_1):M_F_CPU0_SB_DQ<8>
  254  M_F_CPU0_SB_DQ<7>  DQ_B7  @S9S_MB_2U_LIB.S9S_MB_2U(SCH_1):M_F_CPU0_SB_DQ<7>
  252  M_F_CPU0_SB_DQ<6>  DQ_B6  @S9S_MB_2U_LIB.S9S_MB_2U(SCH_1):M_F_CPU0_SB_DQ<6>
  109  M_F_CPU0_SB_DQ<5>  DQ_B5  @S9S_MB_2U_LIB.S9S_MB_2U(SCH_1):M_F_CPU0_SB_DQ<5>
  107  M_F_CPU0_SB_DQ<4>  DQ_B4  @S9S_MB_2U_LIB.S9S_MB_2U(SCH_1):M_F_CPU0_SB_DQ<4>
  247  M_F_CPU0_SB_DQ<3>  DQ_B3  @S9S_MB_2U_LIB.S9S_MB_2U(SCH_1):M_F_CPU0_SB_DQ<3>
  287  M_F_CPU0_SB_DQ<31>  DQ_B31  @S9S_MB_2U_LIB.S9S_MB_2U(SCH_1):M_F_CPU0_SB_DQ<31>
  285  M_F_CPU0_SB_DQ<30>  DQ_B30  @S9S_MB_2U_LIB.S9S_MB_2U(SCH_1):M_F_CPU0_SB_DQ<30>
  245  M_F_CPU0_SB_DQ<2>  DQ_B2  @S9S_MB_2U_LIB.S9S_MB_2U(SCH_1):M_F_CPU0_SB_DQ<2>
  142  M_F_CPU0_SB_DQ<29>  DQ_B29  @S9S_MB_2U_LIB.S9S_MB_2U(SCH_1):M_F_CPU0_SB_DQ<29>
  140  M_F_CPU0_SB_DQ<28>  DQ_B28  @S9S_MB_2U_LIB.S9S_MB_2U(SCH_1):M_F_CPU0_SB_DQ<28>
  280  M_F_CPU0_SB_DQ<27>  DQ_B27  @S9S_MB_2U_LIB.S9S_MB_2U(SCH_1):M_F_CPU0_SB_DQ<27>
  278  M_F_CPU0_SB_DQ<26>  DQ_B26  @S9S_MB_2U_LIB.S9S_MB_2U(SCH_1):M_F_CPU0_SB_DQ<26>
  135  M_F_CPU0_SB_DQ<25>  DQ_B25  @S9S_MB_2U_LIB.S9S_MB_2U(SCH_1):M_F_CPU0_SB_DQ<25>
  133  M_F_CPU0_SB_DQ<24>  DQ_B24  @S9S_MB_2U_LIB.S9S_MB_2U(SCH_1):M_F_CPU0_SB_DQ<24>
  276  M_F_CPU0_SB_DQ<23>  DQ_B23  @S9S_MB_2U_LIB.S9S_MB_2U(SCH_1):M_F_CPU0_SB_DQ<23>
  274  M_F_CPU0_SB_DQ<22>  DQ_B22  @S9S_MB_2U_LIB.S9S_MB_2U(SCH_1):M_F_CPU0_SB_DQ<22>
  131  M_F_CPU0_SB_DQ<21>  DQ_B21  @S9S_MB_2U_LIB.S9S_MB_2U(SCH_1):M_F_CPU0_SB_DQ<21>
  129  M_F_CPU0_SB_DQ<20>  DQ_B20  @S9S_MB_2U_LIB.S9S_MB_2U(SCH_1):M_F_CPU0_SB_DQ<20>
  102  M_F_CPU0_SB_DQ<1>  DQ_B1  @S9S_MB_2U_LIB.S9S_MB_2U(SCH_1):M_F_CPU0_SB_DQ<1>
  269  M_F_CPU0_SB_DQ<19>  DQ_B19  @S9S_MB_2U_LIB.S9S_MB_2U(SCH_1):M_F_CPU0_SB_DQ<19>
  267  M_F_CPU0_SB_DQ<18>  DQ_B18  @S9S_MB_2U_LIB.S9S_MB_2U(SCH_1):M_F_CPU0_SB_DQ<18>
  124  M_F_CPU0_SB_DQ<17>  DQ_B17  @S9S_MB_2U_LIB.S9S_MB_2U(SCH_1):M_F_CPU0_SB_DQ<17>
  122  M_F_CPU0_SB_DQ<16>  DQ_B16  @S9S_MB_2U_LIB.S9S_MB_2U(SCH_1):M_F_CPU0_SB_DQ<16>
  265  M_F_CPU0_SB_DQ<15>  DQ_B15  @S9S_MB_2U_LIB.S9S_MB_2U(SCH_1):M_F_CPU0_SB_DQ<15>
  263  M_F_CPU0_SB_DQ<14>  DQ_B14  @S9S_MB_2U_LIB.S9S_MB_2U(SCH_1):M_F_CPU0_SB_DQ<14>
  120  M_F_CPU0_SB_DQ<13>  DQ_B13  @S9S_MB_2U_LIB.S9S_MB_2U(SCH_1):M_F_CPU0_SB_DQ<13>
  118  M_F_CPU0_SB_DQ<12>  DQ_B12  @S9S_MB_2U_LIB.S9S_MB_2U(SCH_1):M_F_CPU0_SB_DQ<12>
  258  M_F_CPU0_SB_DQ<11>  DQ_B11  @S9S_MB_2U_LIB.S9S_MB_2U(SCH_1):M_F_CPU0_SB_DQ<11>
  256  M_F_CPU0_SB_DQ<10>  DQ_B10  @S9S_MB_2U_LIB.S9S_MB_2U(SCH_1):M_F_CPU0_SB_DQ<10>
  100  M_F_CPU0_SB_DQ<0>  DQ_B0  @S9S_MB_2U_LIB.S9S_MB_2U(SCH_1):M_F_CPU0_SB_DQ<0>
  229  M_F_CPU0_SB_CS_N<1>  CS1_N_B  @S9S_MB_2U_LIB.S9S_MB_2U(SCH_1):M_F_CPU0_SB_CS_N<1>
   84  M_F_CPU0_SB_CS_N<0>  CS0_N_B  @S9S_MB_2U_LIB.S9S_MB_2U(SCH_1):M_F_CPU0_SB_CS_N<0>
  236  M_F_CPU0_SB_CB<7>  CB_B7  @S9S_MB_2U_LIB.S9S_MB_2U(SCH_1):M_F_CPU0_SB_CB<7>
  234  M_F_CPU0_SB_CB<6>  CB_B6  @S9S_MB_2U_LIB.S9S_MB_2U(SCH_1):M_F_CPU0_SB_CB<6>
   91  M_F_CPU0_SB_CB<5>  CB_B5  @S9S_MB_2U_LIB.S9S_MB_2U(SCH_1):M_F_CPU0_SB_CB<5>
   89  M_F_CPU0_SB_CB<4>  CB_B4  @S9S_MB_2U_LIB.S9S_MB_2U(SCH_1):M_F_CPU0_SB_CB<4>
  243  M_F_CPU0_SB_CB<3>  CB_B3  @S9S_MB_2U_LIB.S9S_MB_2U(SCH_1):M_F_CPU0_SB_CB<3>
  241  M_F_CPU0_SB_CB<2>  CB_B2  @S9S_MB_2U_LIB.S9S_MB_2U(SCH_1):M_F_CPU0_SB_CB<2>
   98  M_F_CPU0_SB_CB<1>  CB_B1  @S9S_MB_2U_LIB.S9S_MB_2U(SCH_1):M_F_CPU0_SB_CB<1>
   96  M_F_CPU0_SB_CB<0>  CB_B0  @S9S_MB_2U_LIB.S9S_MB_2U(SCH_1):M_F_CPU0_SB_CB<0>
   82  M_F_CPU0_SB_CA<6>  CA6_B  @S9S_MB_2U_LIB.S9S_MB_2U(SCH_1):M_F_CPU0_SB_CA<6>
  225  M_F_CPU0_SB_CA<5>  CA5_B  @S9S_MB_2U_LIB.S9S_MB_2U(SCH_1):M_F_CPU0_SB_CA<5>
   80  M_F_CPU0_SB_CA<4>  CA4_B  @S9S_MB_2U_LIB.S9S_MB_2U(SCH_1):M_F_CPU0_SB_CA<4>
  223  M_F_CPU0_SB_CA<3>  CA3_B  @S9S_MB_2U_LIB.S9S_MB_2U(SCH_1):M_F_CPU0_SB_CA<3>
   78  M_F_CPU0_SB_CA<2>  CA2_B  @S9S_MB_2U_LIB.S9S_MB_2U(SCH_1):M_F_CPU0_SB_CA<2>
  221  M_F_CPU0_SB_CA<1>  CA1_B  @S9S_MB_2U_LIB.S9S_MB_2U(SCH_1):M_F_CPU0_SB_CA<1>
   76  M_F_CPU0_SB_CA<0>  CA0_B  @S9S_MB_2U_LIB.S9S_MB_2U(SCH_1):M_F_CPU0_SB_CA<0>
   86  M_F_CPU0_SA_RSP<0>  LBD||RSP_N_A  @S9S_MB_2U_LIB.S9S_MB_2U(SCH_1):M_F_CPU0_SA_RSP<0>
   74  M_F_CPU0_SA_PAR  PAR_A  @S9S_MB_2U_LIB.S9S_MB_2U(SCH_1):M_F_CPU0_SA_PAR
   20  M_F_CPU0_SA_DQ<9>  DQ_A9  @S9S_MB_2U_LIB.S9S_MB_2U(SCH_1):M_F_CPU0_SA_DQ<9>
   18  M_F_CPU0_SA_DQ<8>  DQ_A8  @S9S_MB_2U_LIB.S9S_MB_2U(SCH_1):M_F_CPU0_SA_DQ<8>
  161  M_F_CPU0_SA_DQ<7>  DQ_A7  @S9S_MB_2U_LIB.S9S_MB_2U(SCH_1):M_F_CPU0_SA_DQ<7>
  159  M_F_CPU0_SA_DQ<6>  DQ_A6  @S9S_MB_2U_LIB.S9S_MB_2U(SCH_1):M_F_CPU0_SA_DQ<6>
   16  M_F_CPU0_SA_DQ<5>  DQ_A5  @S9S_MB_2U_LIB.S9S_MB_2U(SCH_1):M_F_CPU0_SA_DQ<5>
   14  M_F_CPU0_SA_DQ<4>  DQ_A4  @S9S_MB_2U_LIB.S9S_MB_2U(SCH_1):M_F_CPU0_SA_DQ<4>
  154  M_F_CPU0_SA_DQ<3>  DQ_A3  @S9S_MB_2U_LIB.S9S_MB_2U(SCH_1):M_F_CPU0_SA_DQ<3>
  194  M_F_CPU0_SA_DQ<31>  DQ_A31  @S9S_MB_2U_LIB.S9S_MB_2U(SCH_1):M_F_CPU0_SA_DQ<31>
  192  M_F_CPU0_SA_DQ<30>  DQ_A30  @S9S_MB_2U_LIB.S9S_MB_2U(SCH_1):M_F_CPU0_SA_DQ<30>
  152  M_F_CPU0_SA_DQ<2>  DQ_A2  @S9S_MB_2U_LIB.S9S_MB_2U(SCH_1):M_F_CPU0_SA_DQ<2>
   49  M_F_CPU0_SA_DQ<29>  DQ_A29  @S9S_MB_2U_LIB.S9S_MB_2U(SCH_1):M_F_CPU0_SA_DQ<29>
   47  M_F_CPU0_SA_DQ<28>  DQ_A28  @S9S_MB_2U_LIB.S9S_MB_2U(SCH_1):M_F_CPU0_SA_DQ<28>
  187  M_F_CPU0_SA_DQ<27>  DQ_A27  @S9S_MB_2U_LIB.S9S_MB_2U(SCH_1):M_F_CPU0_SA_DQ<27>
  185  M_F_CPU0_SA_DQ<26>  DQ_A26  @S9S_MB_2U_LIB.S9S_MB_2U(SCH_1):M_F_CPU0_SA_DQ<26>
   42  M_F_CPU0_SA_DQ<25>  DQ_A25  @S9S_MB_2U_LIB.S9S_MB_2U(SCH_1):M_F_CPU0_SA_DQ<25>
   40  M_F_CPU0_SA_DQ<24>  DQ_A24  @S9S_MB_2U_LIB.S9S_MB_2U(SCH_1):M_F_CPU0_SA_DQ<24>
  183  M_F_CPU0_SA_DQ<23>  DQ_A23  @S9S_MB_2U_LIB.S9S_MB_2U(SCH_1):M_F_CPU0_SA_DQ<23>
  181  M_F_CPU0_SA_DQ<22>  DQ_A22  @S9S_MB_2U_LIB.S9S_MB_2U(SCH_1):M_F_CPU0_SA_DQ<22>
   38  M_F_CPU0_SA_DQ<21>  DQ_A21  @S9S_MB_2U_LIB.S9S_MB_2U(SCH_1):M_F_CPU0_SA_DQ<21>
   36  M_F_CPU0_SA_DQ<20>  DQ_A20  @S9S_MB_2U_LIB.S9S_MB_2U(SCH_1):M_F_CPU0_SA_DQ<20>
    9  M_F_CPU0_SA_DQ<1>  DQ_A1  @S9S_MB_2U_LIB.S9S_MB_2U(SCH_1):M_F_CPU0_SA_DQ<1>
  176  M_F_CPU0_SA_DQ<19>  DQ_A19  @S9S_MB_2U_LIB.S9S_MB_2U(SCH_1):M_F_CPU0_SA_DQ<19>
  174  M_F_CPU0_SA_DQ<18>  DQ_A18  @S9S_MB_2U_LIB.S9S_MB_2U(SCH_1):M_F_CPU0_SA_DQ<18>
   31  M_F_CPU0_SA_DQ<17>  DQ_A17  @S9S_MB_2U_LIB.S9S_MB_2U(SCH_1):M_F_CPU0_SA_DQ<17>
   29  M_F_CPU0_SA_DQ<16>  DQ_A16  @S9S_MB_2U_LIB.S9S_MB_2U(SCH_1):M_F_CPU0_SA_DQ<16>
  172  M_F_CPU0_SA_DQ<15>  DQ_A15  @S9S_MB_2U_LIB.S9S_MB_2U(SCH_1):M_F_CPU0_SA_DQ<15>
  170  M_F_CPU0_SA_DQ<14>  DQ_A14  @S9S_MB_2U_LIB.S9S_MB_2U(SCH_1):M_F_CPU0_SA_DQ<14>
   27  M_F_CPU0_SA_DQ<13>  DQ_A13  @S9S_MB_2U_LIB.S9S_MB_2U(SCH_1):M_F_CPU0_SA_DQ<13>
   25  M_F_CPU0_SA_DQ<12>  DQ_A12  @S9S_MB_2U_LIB.S9S_MB_2U(SCH_1):M_F_CPU0_SA_DQ<12>
  165  M_F_CPU0_SA_DQ<11>  DQ_A11  @S9S_MB_2U_LIB.S9S_MB_2U(SCH_1):M_F_CPU0_SA_DQ<11>
  163  M_F_CPU0_SA_DQ<10>  DQ_A10  @S9S_MB_2U_LIB.S9S_MB_2U(SCH_1):M_F_CPU0_SA_DQ<10>
    7  M_F_CPU0_SA_DQ<0>  DQ_A0  @S9S_MB_2U_LIB.S9S_MB_2U(SCH_1):M_F_CPU0_SA_DQ<0>
  209  M_F_CPU0_SA_CS_N<1>  CS1_N_A  @S9S_MB_2U_LIB.S9S_MB_2U(SCH_1):M_F_CPU0_SA_CS_N<1>
   64  M_F_CPU0_SA_CS_N<0>  CS0_N_A  @S9S_MB_2U_LIB.S9S_MB_2U(SCH_1):M_F_CPU0_SA_CS_N<0>
  205  M_F_CPU0_SA_CB<7>  CB_A7  @S9S_MB_2U_LIB.S9S_MB_2U(SCH_1):M_F_CPU0_SA_CB<7>
  203  M_F_CPU0_SA_CB<6>  CB_A6  @S9S_MB_2U_LIB.S9S_MB_2U(SCH_1):M_F_CPU0_SA_CB<6>
   60  M_F_CPU0_SA_CB<5>  CB_A5  @S9S_MB_2U_LIB.S9S_MB_2U(SCH_1):M_F_CPU0_SA_CB<5>
   58  M_F_CPU0_SA_CB<4>  CB_A4  @S9S_MB_2U_LIB.S9S_MB_2U(SCH_1):M_F_CPU0_SA_CB<4>
  198  M_F_CPU0_SA_CB<3>  CB_A3  @S9S_MB_2U_LIB.S9S_MB_2U(SCH_1):M_F_CPU0_SA_CB<3>
  196  M_F_CPU0_SA_CB<2>  CB_A2  @S9S_MB_2U_LIB.S9S_MB_2U(SCH_1):M_F_CPU0_SA_CB<2>
   53  M_F_CPU0_SA_CB<1>  CB_A1  @S9S_MB_2U_LIB.S9S_MB_2U(SCH_1):M_F_CPU0_SA_CB<1>
   51  M_F_CPU0_SA_CB<0>  CB_A0  @S9S_MB_2U_LIB.S9S_MB_2U(SCH_1):M_F_CPU0_SA_CB<0>
   72  M_F_CPU0_SA_CA<6>  CA6_A  @S9S_MB_2U_LIB.S9S_MB_2U(SCH_1):M_F_CPU0_SA_CA<6>
  215  M_F_CPU0_SA_CA<5>  CA5_A  @S9S_MB_2U_LIB.S9S_MB_2U(SCH_1):M_F_CPU0_SA_CA<5>
   70  M_F_CPU0_SA_CA<4>  CA4_A  @S9S_MB_2U_LIB.S9S_MB_2U(SCH_1):M_F_CPU0_SA_CA<4>
  213  M_F_CPU0_SA_CA<3>  CA3_A  @S9S_MB_2U_LIB.S9S_MB_2U(SCH_1):M_F_CPU0_SA_CA<3>
   68  M_F_CPU0_SA_CA<2>  CA2_A  @S9S_MB_2U_LIB.S9S_MB_2U(SCH_1):M_F_CPU0_SA_CA<2>
  211  M_F_CPU0_SA_CA<1>  CA1_A  @S9S_MB_2U_LIB.S9S_MB_2U(SCH_1):M_F_CPU0_SA_CA<1>
   66  M_F_CPU0_SA_CA<0>  CA0_A  @S9S_MB_2U_LIB.S9S_MB_2U(SCH_1):M_F_CPU0_SA_CA<0>
  217  M_F_CPU0_CLK_DP<0>   CK_P  @S9S_MB_2U_LIB.S9S_MB_2U(SCH_1):M_F_CPU0_CLK_DP<0>
  218  M_F_CPU0_CLK_DN<0>   CK_N  @S9S_MB_2U_LIB.S9S_MB_2U(SCH_1):M_F_CPU0_CLK_DN<0>
   62  M_F_CPU0_ALERT_N  ALERT_N  @S9S_MB_2U_LIB.S9S_MB_2U(SCH_1):M_F_CPU0_ALERT_N
    5  I3C_SPD_DDREFGH_CPU0_LVC1_SDA   HSDA  @S9S_MB_2U_LIB.S9S_MB_2U(SCH_1):I3C_SPD_DDREFGH_CPU0_LVC1_SDA
    4  I3C_SPD_DDREFGH_CPU0_LVC1_SCL   HSCL  @S9S_MB_2U_LIB.S9S_MB_2U(SCH_1):I3C_SPD_DDREFGH_CPU0_LVC1_SCL

SCONN288_ADR50001P003C01  I175  J12    [SCONN288_ADR50001P003C01-SCONNA]
  146  P12V_S3_AUX_CPU0_NVDIMM  VIN_BULK2  @S9S_MB_2U_LIB.S9S_MB_2U(SCH_1):P12V_S3_AUX_CPU0_NVDIMM
  145  P12V_S3_AUX_CPU0_NVDIMM  VIN_BULK1  @S9S_MB_2U_LIB.S9S_MB_2U(SCH_1):P12V_S3_AUX_CPU0_NVDIMM
    1  P12V_S3_AUX_CPU0_NVDIMM  VIN_BULK0  @S9S_MB_2U_LIB.S9S_MB_2U(SCH_1):P12V_S3_AUX_CPU0_NVDIMM
  288  GND            VSS126  @S9S_MB_2U_LIB.S9S_MB_2U(SCH_1):GND
  286  GND            VSS125  @S9S_MB_2U_LIB.S9S_MB_2U(SCH_1):GND
  284  GND            VSS124  @S9S_MB_2U_LIB.S9S_MB_2U(SCH_1):GND
  281  GND            VSS123  @S9S_MB_2U_LIB.S9S_MB_2U(SCH_1):GND
  279  GND            VSS122  @S9S_MB_2U_LIB.S9S_MB_2U(SCH_1):GND
  277  GND            VSS121  @S9S_MB_2U_LIB.S9S_MB_2U(SCH_1):GND
  275  GND            VSS120  @S9S_MB_2U_LIB.S9S_MB_2U(SCH_1):GND
  273  GND            VSS119  @S9S_MB_2U_LIB.S9S_MB_2U(SCH_1):GND
  270  GND            VSS118  @S9S_MB_2U_LIB.S9S_MB_2U(SCH_1):GND
  268  GND            VSS117  @S9S_MB_2U_LIB.S9S_MB_2U(SCH_1):GND
  266  GND            VSS116  @S9S_MB_2U_LIB.S9S_MB_2U(SCH_1):GND
  264  GND            VSS115  @S9S_MB_2U_LIB.S9S_MB_2U(SCH_1):GND
  262  GND            VSS114  @S9S_MB_2U_LIB.S9S_MB_2U(SCH_1):GND
  259  GND            VSS113  @S9S_MB_2U_LIB.S9S_MB_2U(SCH_1):GND
  257  GND            VSS112  @S9S_MB_2U_LIB.S9S_MB_2U(SCH_1):GND
  255  GND            VSS111  @S9S_MB_2U_LIB.S9S_MB_2U(SCH_1):GND
  253  GND            VSS110  @S9S_MB_2U_LIB.S9S_MB_2U(SCH_1):GND
  251  GND            VSS109  @S9S_MB_2U_LIB.S9S_MB_2U(SCH_1):GND
  248  GND            VSS108  @S9S_MB_2U_LIB.S9S_MB_2U(SCH_1):GND
  246  GND            VSS107  @S9S_MB_2U_LIB.S9S_MB_2U(SCH_1):GND
  244  GND            VSS106  @S9S_MB_2U_LIB.S9S_MB_2U(SCH_1):GND
  242  GND            VSS105  @S9S_MB_2U_LIB.S9S_MB_2U(SCH_1):GND
  240  GND            VSS104  @S9S_MB_2U_LIB.S9S_MB_2U(SCH_1):GND
  237  GND            VSS103  @S9S_MB_2U_LIB.S9S_MB_2U(SCH_1):GND
  235  GND            VSS102  @S9S_MB_2U_LIB.S9S_MB_2U(SCH_1):GND
  233  GND            VSS101  @S9S_MB_2U_LIB.S9S_MB_2U(SCH_1):GND
  230  GND            VSS100  @S9S_MB_2U_LIB.S9S_MB_2U(SCH_1):GND
  228  GND            VSS99  @S9S_MB_2U_LIB.S9S_MB_2U(SCH_1):GND
  226  GND            VSS98  @S9S_MB_2U_LIB.S9S_MB_2U(SCH_1):GND
  224  GND            VSS97  @S9S_MB_2U_LIB.S9S_MB_2U(SCH_1):GND
  222  GND            VSS96  @S9S_MB_2U_LIB.S9S_MB_2U(SCH_1):GND
  219  GND            VSS95  @S9S_MB_2U_LIB.S9S_MB_2U(SCH_1):GND
  216  GND            VSS94  @S9S_MB_2U_LIB.S9S_MB_2U(SCH_1):GND
  214  GND            VSS93  @S9S_MB_2U_LIB.S9S_MB_2U(SCH_1):GND
  212  GND            VSS92  @S9S_MB_2U_LIB.S9S_MB_2U(SCH_1):GND
  210  GND            VSS91  @S9S_MB_2U_LIB.S9S_MB_2U(SCH_1):GND
  208  GND            VSS90  @S9S_MB_2U_LIB.S9S_MB_2U(SCH_1):GND
  206  GND            VSS89  @S9S_MB_2U_LIB.S9S_MB_2U(SCH_1):GND
  204  GND            VSS88  @S9S_MB_2U_LIB.S9S_MB_2U(SCH_1):GND
  202  GND            VSS87  @S9S_MB_2U_LIB.S9S_MB_2U(SCH_1):GND
  199  GND            VSS86  @S9S_MB_2U_LIB.S9S_MB_2U(SCH_1):GND
  197  GND            VSS85  @S9S_MB_2U_LIB.S9S_MB_2U(SCH_1):GND
  195  GND            VSS84  @S9S_MB_2U_LIB.S9S_MB_2U(SCH_1):GND
  193  GND            VSS83  @S9S_MB_2U_LIB.S9S_MB_2U(SCH_1):GND
  191  GND            VSS82  @S9S_MB_2U_LIB.S9S_MB_2U(SCH_1):GND
  188  GND            VSS81  @S9S_MB_2U_LIB.S9S_MB_2U(SCH_1):GND
  186  GND            VSS80  @S9S_MB_2U_LIB.S9S_MB_2U(SCH_1):GND
  184  GND            VSS79  @S9S_MB_2U_LIB.S9S_MB_2U(SCH_1):GND
  182  GND            VSS78  @S9S_MB_2U_LIB.S9S_MB_2U(SCH_1):GND
  180  GND            VSS77  @S9S_MB_2U_LIB.S9S_MB_2U(SCH_1):GND
  177  GND            VSS76  @S9S_MB_2U_LIB.S9S_MB_2U(SCH_1):GND
  175  GND            VSS75  @S9S_MB_2U_LIB.S9S_MB_2U(SCH_1):GND
  173  GND            VSS74  @S9S_MB_2U_LIB.S9S_MB_2U(SCH_1):GND
  171  GND            VSS73  @S9S_MB_2U_LIB.S9S_MB_2U(SCH_1):GND
  169  GND            VSS72  @S9S_MB_2U_LIB.S9S_MB_2U(SCH_1):GND
  166  GND            VSS71  @S9S_MB_2U_LIB.S9S_MB_2U(SCH_1):GND
  164  GND            VSS70  @S9S_MB_2U_LIB.S9S_MB_2U(SCH_1):GND
  162  GND            VSS69  @S9S_MB_2U_LIB.S9S_MB_2U(SCH_1):GND
  160  GND            VSS68  @S9S_MB_2U_LIB.S9S_MB_2U(SCH_1):GND
  158  GND            VSS67  @S9S_MB_2U_LIB.S9S_MB_2U(SCH_1):GND
  155  GND            VSS66  @S9S_MB_2U_LIB.S9S_MB_2U(SCH_1):GND
  153  GND            VSS65  @S9S_MB_2U_LIB.S9S_MB_2U(SCH_1):GND
  151  GND            VSS64  @S9S_MB_2U_LIB.S9S_MB_2U(SCH_1):GND
  143  GND            VSS63  @S9S_MB_2U_LIB.S9S_MB_2U(SCH_1):GND
  141  GND            VSS62  @S9S_MB_2U_LIB.S9S_MB_2U(SCH_1):GND
  139  GND            VSS61  @S9S_MB_2U_LIB.S9S_MB_2U(SCH_1):GND
  136  GND            VSS60  @S9S_MB_2U_LIB.S9S_MB_2U(SCH_1):GND
  134  GND            VSS59  @S9S_MB_2U_LIB.S9S_MB_2U(SCH_1):GND
  132  GND            VSS58  @S9S_MB_2U_LIB.S9S_MB_2U(SCH_1):GND
  130  GND            VSS57  @S9S_MB_2U_LIB.S9S_MB_2U(SCH_1):GND
  128  GND            VSS56  @S9S_MB_2U_LIB.S9S_MB_2U(SCH_1):GND
  125  GND            VSS55  @S9S_MB_2U_LIB.S9S_MB_2U(SCH_1):GND
  123  GND            VSS54  @S9S_MB_2U_LIB.S9S_MB_2U(SCH_1):GND
  121  GND            VSS53  @S9S_MB_2U_LIB.S9S_MB_2U(SCH_1):GND
  119  GND            VSS52  @S9S_MB_2U_LIB.S9S_MB_2U(SCH_1):GND
  117  GND            VSS51  @S9S_MB_2U_LIB.S9S_MB_2U(SCH_1):GND
  114  GND            VSS50  @S9S_MB_2U_LIB.S9S_MB_2U(SCH_1):GND
  112  GND            VSS49  @S9S_MB_2U_LIB.S9S_MB_2U(SCH_1):GND
  110  GND            VSS48  @S9S_MB_2U_LIB.S9S_MB_2U(SCH_1):GND
  108  GND            VSS47  @S9S_MB_2U_LIB.S9S_MB_2U(SCH_1):GND
  106  GND            VSS46  @S9S_MB_2U_LIB.S9S_MB_2U(SCH_1):GND
  103  GND            VSS45  @S9S_MB_2U_LIB.S9S_MB_2U(SCH_1):GND
  101  GND            VSS44  @S9S_MB_2U_LIB.S9S_MB_2U(SCH_1):GND
   99  GND            VSS43  @S9S_MB_2U_LIB.S9S_MB_2U(SCH_1):GND
   97  GND            VSS42  @S9S_MB_2U_LIB.S9S_MB_2U(SCH_1):GND
   95  GND            VSS41  @S9S_MB_2U_LIB.S9S_MB_2U(SCH_1):GND
   92  GND            VSS40  @S9S_MB_2U_LIB.S9S_MB_2U(SCH_1):GND
   90  GND            VSS39  @S9S_MB_2U_LIB.S9S_MB_2U(SCH_1):GND
   88  GND            VSS38  @S9S_MB_2U_LIB.S9S_MB_2U(SCH_1):GND
   85  GND            VSS37  @S9S_MB_2U_LIB.S9S_MB_2U(SCH_1):GND
   83  GND            VSS36  @S9S_MB_2U_LIB.S9S_MB_2U(SCH_1):GND
   81  GND            VSS35  @S9S_MB_2U_LIB.S9S_MB_2U(SCH_1):GND
   79  GND            VSS34  @S9S_MB_2U_LIB.S9S_MB_2U(SCH_1):GND
   77  GND            VSS33  @S9S_MB_2U_LIB.S9S_MB_2U(SCH_1):GND
   75  GND            VSS32  @S9S_MB_2U_LIB.S9S_MB_2U(SCH_1):GND
   73  GND            VSS31  @S9S_MB_2U_LIB.S9S_MB_2U(SCH_1):GND
   71  GND            VSS30  @S9S_MB_2U_LIB.S9S_MB_2U(SCH_1):GND
   69  GND            VSS29  @S9S_MB_2U_LIB.S9S_MB_2U(SCH_1):GND
   67  GND            VSS28  @S9S_MB_2U_LIB.S9S_MB_2U(SCH_1):GND
   65  GND            VSS27  @S9S_MB_2U_LIB.S9S_MB_2U(SCH_1):GND
   63  GND            VSS26  @S9S_MB_2U_LIB.S9S_MB_2U(SCH_1):GND
   61  GND            VSS25  @S9S_MB_2U_LIB.S9S_MB_2U(SCH_1):GND
   59  GND            VSS24  @S9S_MB_2U_LIB.S9S_MB_2U(SCH_1):GND
   57  GND            VSS23  @S9S_MB_2U_LIB.S9S_MB_2U(SCH_1):GND
   54  GND            VSS22  @S9S_MB_2U_LIB.S9S_MB_2U(SCH_1):GND
   52  GND            VSS21  @S9S_MB_2U_LIB.S9S_MB_2U(SCH_1):GND
   50  GND            VSS20  @S9S_MB_2U_LIB.S9S_MB_2U(SCH_1):GND
   48  GND            VSS19  @S9S_MB_2U_LIB.S9S_MB_2U(SCH_1):GND
   46  GND            VSS18  @S9S_MB_2U_LIB.S9S_MB_2U(SCH_1):GND
   43  GND            VSS17  @S9S_MB_2U_LIB.S9S_MB_2U(SCH_1):GND
   41  GND            VSS16  @S9S_MB_2U_LIB.S9S_MB_2U(SCH_1):GND
   39  GND            VSS15  @S9S_MB_2U_LIB.S9S_MB_2U(SCH_1):GND
   37  GND            VSS14  @S9S_MB_2U_LIB.S9S_MB_2U(SCH_1):GND
   35  GND            VSS13  @S9S_MB_2U_LIB.S9S_MB_2U(SCH_1):GND
   32  GND            VSS12  @S9S_MB_2U_LIB.S9S_MB_2U(SCH_1):GND
   30  GND            VSS11  @S9S_MB_2U_LIB.S9S_MB_2U(SCH_1):GND
   28  GND            VSS10  @S9S_MB_2U_LIB.S9S_MB_2U(SCH_1):GND
   26  GND             VSS9  @S9S_MB_2U_LIB.S9S_MB_2U(SCH_1):GND
   24  GND             VSS8  @S9S_MB_2U_LIB.S9S_MB_2U(SCH_1):GND
   21  GND             VSS7  @S9S_MB_2U_LIB.S9S_MB_2U(SCH_1):GND
   19  GND             VSS6  @S9S_MB_2U_LIB.S9S_MB_2U(SCH_1):GND
   17  GND             VSS5  @S9S_MB_2U_LIB.S9S_MB_2U(SCH_1):GND
   15  GND             VSS4  @S9S_MB_2U_LIB.S9S_MB_2U(SCH_1):GND
   13  GND             VSS3  @S9S_MB_2U_LIB.S9S_MB_2U(SCH_1):GND
   10  GND             VSS2  @S9S_MB_2U_LIB.S9S_MB_2U(SCH_1):GND
    8  GND             VSS1  @S9S_MB_2U_LIB.S9S_MB_2U(SCH_1):GND
    6  GND             VSS0  @S9S_MB_2U_LIB.S9S_MB_2U(SCH_1):GND
   G3  GND               G3  @S9S_MB_2U_LIB.S9S_MB_2U(SCH_1):GND
   G2  GND               G2  @S9S_MB_2U_LIB.S9S_MB_2U(SCH_1):GND
   G1  GND               G1  @S9S_MB_2U_LIB.S9S_MB_2U(SCH_1):GND

SCONN288_ADR50001P003C01  I125  J12    [SCONN288_ADR50001P003C01-SCONNA]
   93  M_F_CPU0_SB_DQS_DP<9>  DQS9_B_P  @S9S_MB_2U_LIB.S9S_MB_2U(SCH_1):M_F_CPU0_SB_DQS_DP<9>
  283  M_F_CPU0_SB_DQS_DP<8>  DQS8_B_P  @S9S_MB_2U_LIB.S9S_MB_2U(SCH_1):M_F_CPU0_SB_DQS_DP<8>
  272  M_F_CPU0_SB_DQS_DP<7>  DQS7_B_P  @S9S_MB_2U_LIB.S9S_MB_2U(SCH_1):M_F_CPU0_SB_DQS_DP<7>
  261  M_F_CPU0_SB_DQS_DP<6>  DQS6_B_P  @S9S_MB_2U_LIB.S9S_MB_2U(SCH_1):M_F_CPU0_SB_DQS_DP<6>
  250  M_F_CPU0_SB_DQS_DP<5>  DQS5_B_P  @S9S_MB_2U_LIB.S9S_MB_2U(SCH_1):M_F_CPU0_SB_DQS_DP<5>
  239  M_F_CPU0_SB_DQS_DP<4>  DQS4_B_P  @S9S_MB_2U_LIB.S9S_MB_2U(SCH_1):M_F_CPU0_SB_DQS_DP<4>
  137  M_F_CPU0_SB_DQS_DP<3>  DQS3_B_P  @S9S_MB_2U_LIB.S9S_MB_2U(SCH_1):M_F_CPU0_SB_DQS_DP<3>
  126  M_F_CPU0_SB_DQS_DP<2>  DQS2_B_P  @S9S_MB_2U_LIB.S9S_MB_2U(SCH_1):M_F_CPU0_SB_DQS_DP<2>
  115  M_F_CPU0_SB_DQS_DP<1>  DQS1_B_P  @S9S_MB_2U_LIB.S9S_MB_2U(SCH_1):M_F_CPU0_SB_DQS_DP<1>
  104  M_F_CPU0_SB_DQS_DP<0>  DQS0_B_P  @S9S_MB_2U_LIB.S9S_MB_2U(SCH_1):M_F_CPU0_SB_DQS_DP<0>
   94  M_F_CPU0_SB_DQS_DN<9>  DQS9_B_N  @S9S_MB_2U_LIB.S9S_MB_2U(SCH_1):M_F_CPU0_SB_DQS_DN<9>
  282  M_F_CPU0_SB_DQS_DN<8>  DQS8_B_N  @S9S_MB_2U_LIB.S9S_MB_2U(SCH_1):M_F_CPU0_SB_DQS_DN<8>
  271  M_F_CPU0_SB_DQS_DN<7>  DQS7_B_N  @S9S_MB_2U_LIB.S9S_MB_2U(SCH_1):M_F_CPU0_SB_DQS_DN<7>
  260  M_F_CPU0_SB_DQS_DN<6>  DQS6_B_N  @S9S_MB_2U_LIB.S9S_MB_2U(SCH_1):M_F_CPU0_SB_DQS_DN<6>
  249  M_F_CPU0_SB_DQS_DN<5>  DQS5_B_N  @S9S_MB_2U_LIB.S9S_MB_2U(SCH_1):M_F_CPU0_SB_DQS_DN<5>
  238  M_F_CPU0_SB_DQS_DN<4>  DQS4_B_N  @S9S_MB_2U_LIB.S9S_MB_2U(SCH_1):M_F_CPU0_SB_DQS_DN<4>
  138  M_F_CPU0_SB_DQS_DN<3>  DQS3_B_N  @S9S_MB_2U_LIB.S9S_MB_2U(SCH_1):M_F_CPU0_SB_DQS_DN<3>
  127  M_F_CPU0_SB_DQS_DN<2>  DQS2_B_N  @S9S_MB_2U_LIB.S9S_MB_2U(SCH_1):M_F_CPU0_SB_DQS_DN<2>
  116  M_F_CPU0_SB_DQS_DN<1>  DQS1_B_N  @S9S_MB_2U_LIB.S9S_MB_2U(SCH_1):M_F_CPU0_SB_DQS_DN<1>
  105  M_F_CPU0_SB_DQS_DN<0>  DQS0_B_N  @S9S_MB_2U_LIB.S9S_MB_2U(SCH_1):M_F_CPU0_SB_DQS_DN<0>
  201  M_F_CPU0_SA_DQS_DP<9>  DQS9_A_P  @S9S_MB_2U_LIB.S9S_MB_2U(SCH_1):M_F_CPU0_SA_DQS_DP<9>
  190  M_F_CPU0_SA_DQS_DP<8>  DQS8_A_P  @S9S_MB_2U_LIB.S9S_MB_2U(SCH_1):M_F_CPU0_SA_DQS_DP<8>
  179  M_F_CPU0_SA_DQS_DP<7>  DQS7_A_P  @S9S_MB_2U_LIB.S9S_MB_2U(SCH_1):M_F_CPU0_SA_DQS_DP<7>
  168  M_F_CPU0_SA_DQS_DP<6>  DQS6_A_P  @S9S_MB_2U_LIB.S9S_MB_2U(SCH_1):M_F_CPU0_SA_DQS_DP<6>
  157  M_F_CPU0_SA_DQS_DP<5>  DQS5_A_P  @S9S_MB_2U_LIB.S9S_MB_2U(SCH_1):M_F_CPU0_SA_DQS_DP<5>
   55  M_F_CPU0_SA_DQS_DP<4>  DQS4_A_P  @S9S_MB_2U_LIB.S9S_MB_2U(SCH_1):M_F_CPU0_SA_DQS_DP<4>
   44  M_F_CPU0_SA_DQS_DP<3>  DQS3_A_P  @S9S_MB_2U_LIB.S9S_MB_2U(SCH_1):M_F_CPU0_SA_DQS_DP<3>
   33  M_F_CPU0_SA_DQS_DP<2>  DQS2_A_P  @S9S_MB_2U_LIB.S9S_MB_2U(SCH_1):M_F_CPU0_SA_DQS_DP<2>
   22  M_F_CPU0_SA_DQS_DP<1>  DQS1_A_P  @S9S_MB_2U_LIB.S9S_MB_2U(SCH_1):M_F_CPU0_SA_DQS_DP<1>
   11  M_F_CPU0_SA_DQS_DP<0>  DQS0_A_P  @S9S_MB_2U_LIB.S9S_MB_2U(SCH_1):M_F_CPU0_SA_DQS_DP<0>
  200  M_F_CPU0_SA_DQS_DN<9>  DQS9_A_N  @S9S_MB_2U_LIB.S9S_MB_2U(SCH_1):M_F_CPU0_SA_DQS_DN<9>
  189  M_F_CPU0_SA_DQS_DN<8>  DQS8_A_N  @S9S_MB_2U_LIB.S9S_MB_2U(SCH_1):M_F_CPU0_SA_DQS_DN<8>
  178  M_F_CPU0_SA_DQS_DN<7>  DQS7_A_N  @S9S_MB_2U_LIB.S9S_MB_2U(SCH_1):M_F_CPU0_SA_DQS_DN<7>
  167  M_F_CPU0_SA_DQS_DN<6>  DQS6_A_N  @S9S_MB_2U_LIB.S9S_MB_2U(SCH_1):M_F_CPU0_SA_DQS_DN<6>
  156  M_F_CPU0_SA_DQS_DN<5>  DQS5_A_N  @S9S_MB_2U_LIB.S9S_MB_2U(SCH_1):M_F_CPU0_SA_DQS_DN<5>
   56  M_F_CPU0_SA_DQS_DN<4>  DQS4_A_N  @S9S_MB_2U_LIB.S9S_MB_2U(SCH_1):M_F_CPU0_SA_DQS_DN<4>
   45  M_F_CPU0_SA_DQS_DN<3>  DQS3_A_N  @S9S_MB_2U_LIB.S9S_MB_2U(SCH_1):M_F_CPU0_SA_DQS_DN<3>
   34  M_F_CPU0_SA_DQS_DN<2>  DQS2_A_N  @S9S_MB_2U_LIB.S9S_MB_2U(SCH_1):M_F_CPU0_SA_DQS_DN<2>
   23  M_F_CPU0_SA_DQS_DN<1>  DQS1_A_N  @S9S_MB_2U_LIB.S9S_MB_2U(SCH_1):M_F_CPU0_SA_DQS_DN<1>
   12  M_F_CPU0_SA_DQS_DN<0>  DQS0_A_N  @S9S_MB_2U_LIB.S9S_MB_2U(SCH_1):M_F_CPU0_SA_DQS_DN<0>

SCONN288_ADR50001P003C01  I24  J12    [SCONN288_ADR50001P003C01-SCONNA]
  232  NC              RFU6  NC
  231  NC              RFU5  NC
  220  NC              RFU4  NC
  150  NC              RFU3  NC
  149  NC              RFU2  NC
  144  NC              RFU1  NC
    2  NC              RFU0  NC
  207  RST_M_EF_CPU0_FPGA_N  RESET_N  @S9S_MB_2U_LIB.S9S_MB_2U(SCH_1):RST_M_EF_CPU0_FPGA_N
  147  PWRGD_CHF_CPU0_DIMM2  PWR_GOOD||FAIL_N  @S9S_MB_2U_LIB.S9S_MB_2U(SCH_1):PWRGD_CHF_CPU0_DIMM2
  148  PD_CHF_CPU0_DIMM2_SAA    HAS  @S9S_MB_2U_LIB.S9S_MB_2U(SCH_1):PD_CHF_CPU0_DIMM2_SAA
    3  P3V3_AUX       VIN_MGMT  @S9S_MB_2U_LIB.S9S_MB_2U(SCH_1):P3V3_AUX
   87  M_F_CPU0_SB_RSP<1>  LBS||RSP_N_B  @S9S_MB_2U_LIB.S9S_MB_2U(SCH_1):M_F_CPU0_SB_RSP<1>
  227  M_F_CPU0_SB_PAR  PAR_B  @S9S_MB_2U_LIB.S9S_MB_2U(SCH_1):M_F_CPU0_SB_PAR
  113  M_F_CPU0_SB_DQ<9>  DQ_B9  @S9S_MB_2U_LIB.S9S_MB_2U(SCH_1):M_F_CPU0_SB_DQ<9>
  111  M_F_CPU0_SB_DQ<8>  DQ_B8  @S9S_MB_2U_LIB.S9S_MB_2U(SCH_1):M_F_CPU0_SB_DQ<8>
  254  M_F_CPU0_SB_DQ<7>  DQ_B7  @S9S_MB_2U_LIB.S9S_MB_2U(SCH_1):M_F_CPU0_SB_DQ<7>
  252  M_F_CPU0_SB_DQ<6>  DQ_B6  @S9S_MB_2U_LIB.S9S_MB_2U(SCH_1):M_F_CPU0_SB_DQ<6>
  109  M_F_CPU0_SB_DQ<5>  DQ_B5  @S9S_MB_2U_LIB.S9S_MB_2U(SCH_1):M_F_CPU0_SB_DQ<5>
  107  M_F_CPU0_SB_DQ<4>  DQ_B4  @S9S_MB_2U_LIB.S9S_MB_2U(SCH_1):M_F_CPU0_SB_DQ<4>
  247  M_F_CPU0_SB_DQ<3>  DQ_B3  @S9S_MB_2U_LIB.S9S_MB_2U(SCH_1):M_F_CPU0_SB_DQ<3>
  287  M_F_CPU0_SB_DQ<31>  DQ_B31  @S9S_MB_2U_LIB.S9S_MB_2U(SCH_1):M_F_CPU0_SB_DQ<31>
  285  M_F_CPU0_SB_DQ<30>  DQ_B30  @S9S_MB_2U_LIB.S9S_MB_2U(SCH_1):M_F_CPU0_SB_DQ<30>
  245  M_F_CPU0_SB_DQ<2>  DQ_B2  @S9S_MB_2U_LIB.S9S_MB_2U(SCH_1):M_F_CPU0_SB_DQ<2>
  142  M_F_CPU0_SB_DQ<29>  DQ_B29  @S9S_MB_2U_LIB.S9S_MB_2U(SCH_1):M_F_CPU0_SB_DQ<29>
  140  M_F_CPU0_SB_DQ<28>  DQ_B28  @S9S_MB_2U_LIB.S9S_MB_2U(SCH_1):M_F_CPU0_SB_DQ<28>
  280  M_F_CPU0_SB_DQ<27>  DQ_B27  @S9S_MB_2U_LIB.S9S_MB_2U(SCH_1):M_F_CPU0_SB_DQ<27>
  278  M_F_CPU0_SB_DQ<26>  DQ_B26  @S9S_MB_2U_LIB.S9S_MB_2U(SCH_1):M_F_CPU0_SB_DQ<26>
  135  M_F_CPU0_SB_DQ<25>  DQ_B25  @S9S_MB_2U_LIB.S9S_MB_2U(SCH_1):M_F_CPU0_SB_DQ<25>
  133  M_F_CPU0_SB_DQ<24>  DQ_B24  @S9S_MB_2U_LIB.S9S_MB_2U(SCH_1):M_F_CPU0_SB_DQ<24>
  276  M_F_CPU0_SB_DQ<23>  DQ_B23  @S9S_MB_2U_LIB.S9S_MB_2U(SCH_1):M_F_CPU0_SB_DQ<23>
  274  M_F_CPU0_SB_DQ<22>  DQ_B22  @S9S_MB_2U_LIB.S9S_MB_2U(SCH_1):M_F_CPU0_SB_DQ<22>
  131  M_F_CPU0_SB_DQ<21>  DQ_B21  @S9S_MB_2U_LIB.S9S_MB_2U(SCH_1):M_F_CPU0_SB_DQ<21>
  129  M_F_CPU0_SB_DQ<20>  DQ_B20  @S9S_MB_2U_LIB.S9S_MB_2U(SCH_1):M_F_CPU0_SB_DQ<20>
  102  M_F_CPU0_SB_DQ<1>  DQ_B1  @S9S_MB_2U_LIB.S9S_MB_2U(SCH_1):M_F_CPU0_SB_DQ<1>
  269  M_F_CPU0_SB_DQ<19>  DQ_B19  @S9S_MB_2U_LIB.S9S_MB_2U(SCH_1):M_F_CPU0_SB_DQ<19>
  267  M_F_CPU0_SB_DQ<18>  DQ_B18  @S9S_MB_2U_LIB.S9S_MB_2U(SCH_1):M_F_CPU0_SB_DQ<18>
  124  M_F_CPU0_SB_DQ<17>  DQ_B17  @S9S_MB_2U_LIB.S9S_MB_2U(SCH_1):M_F_CPU0_SB_DQ<17>
  122  M_F_CPU0_SB_DQ<16>  DQ_B16  @S9S_MB_2U_LIB.S9S_MB_2U(SCH_1):M_F_CPU0_SB_DQ<16>
  265  M_F_CPU0_SB_DQ<15>  DQ_B15  @S9S_MB_2U_LIB.S9S_MB_2U(SCH_1):M_F_CPU0_SB_DQ<15>
  263  M_F_CPU0_SB_DQ<14>  DQ_B14  @S9S_MB_2U_LIB.S9S_MB_2U(SCH_1):M_F_CPU0_SB_DQ<14>
  120  M_F_CPU0_SB_DQ<13>  DQ_B13  @S9S_MB_2U_LIB.S9S_MB_2U(SCH_1):M_F_CPU0_SB_DQ<13>
  118  M_F_CPU0_SB_DQ<12>  DQ_B12  @S9S_MB_2U_LIB.S9S_MB_2U(SCH_1):M_F_CPU0_SB_DQ<12>
  258  M_F_CPU0_SB_DQ<11>  DQ_B11  @S9S_MB_2U_LIB.S9S_MB_2U(SCH_1):M_F_CPU0_SB_DQ<11>
  256  M_F_CPU0_SB_DQ<10>  DQ_B10  @S9S_MB_2U_LIB.S9S_MB_2U(SCH_1):M_F_CPU0_SB_DQ<10>
  100  M_F_CPU0_SB_DQ<0>  DQ_B0  @S9S_MB_2U_LIB.S9S_MB_2U(SCH_1):M_F_CPU0_SB_DQ<0>
  229  M_F_CPU0_SB_CS_N<3>  CS1_N_B  @S9S_MB_2U_LIB.S9S_MB_2U(SCH_1):M_F_CPU0_SB_CS_N<3>
   84  M_F_CPU0_SB_CS_N<2>  CS0_N_B  @S9S_MB_2U_LIB.S9S_MB_2U(SCH_1):M_F_CPU0_SB_CS_N<2>
  236  M_F_CPU0_SB_CB<7>  CB_B7  @S9S_MB_2U_LIB.S9S_MB_2U(SCH_1):M_F_CPU0_SB_CB<7>
  234  M_F_CPU0_SB_CB<6>  CB_B6  @S9S_MB_2U_LIB.S9S_MB_2U(SCH_1):M_F_CPU0_SB_CB<6>
   91  M_F_CPU0_SB_CB<5>  CB_B5  @S9S_MB_2U_LIB.S9S_MB_2U(SCH_1):M_F_CPU0_SB_CB<5>
   89  M_F_CPU0_SB_CB<4>  CB_B4  @S9S_MB_2U_LIB.S9S_MB_2U(SCH_1):M_F_CPU0_SB_CB<4>
  243  M_F_CPU0_SB_CB<3>  CB_B3  @S9S_MB_2U_LIB.S9S_MB_2U(SCH_1):M_F_CPU0_SB_CB<3>
  241  M_F_CPU0_SB_CB<2>  CB_B2  @S9S_MB_2U_LIB.S9S_MB_2U(SCH_1):M_F_CPU0_SB_CB<2>
   98  M_F_CPU0_SB_CB<1>  CB_B1  @S9S_MB_2U_LIB.S9S_MB_2U(SCH_1):M_F_CPU0_SB_CB<1>
   96  M_F_CPU0_SB_CB<0>  CB_B0  @S9S_MB_2U_LIB.S9S_MB_2U(SCH_1):M_F_CPU0_SB_CB<0>
   82  M_F_CPU0_SB_CA<6>  CA6_B  @S9S_MB_2U_LIB.S9S_MB_2U(SCH_1):M_F_CPU0_SB_CA<6>
  225  M_F_CPU0_SB_CA<5>  CA5_B  @S9S_MB_2U_LIB.S9S_MB_2U(SCH_1):M_F_CPU0_SB_CA<5>
   80  M_F_CPU0_SB_CA<4>  CA4_B  @S9S_MB_2U_LIB.S9S_MB_2U(SCH_1):M_F_CPU0_SB_CA<4>
  223  M_F_CPU0_SB_CA<3>  CA3_B  @S9S_MB_2U_LIB.S9S_MB_2U(SCH_1):M_F_CPU0_SB_CA<3>
   78  M_F_CPU0_SB_CA<2>  CA2_B  @S9S_MB_2U_LIB.S9S_MB_2U(SCH_1):M_F_CPU0_SB_CA<2>
  221  M_F_CPU0_SB_CA<1>  CA1_B  @S9S_MB_2U_LIB.S9S_MB_2U(SCH_1):M_F_CPU0_SB_CA<1>
   76  M_F_CPU0_SB_CA<0>  CA0_B  @S9S_MB_2U_LIB.S9S_MB_2U(SCH_1):M_F_CPU0_SB_CA<0>
   86  M_F_CPU0_SA_RSP<1>  LBD||RSP_N_A  @S9S_MB_2U_LIB.S9S_MB_2U(SCH_1):M_F_CPU0_SA_RSP<1>
   74  M_F_CPU0_SA_PAR  PAR_A  @S9S_MB_2U_LIB.S9S_MB_2U(SCH_1):M_F_CPU0_SA_PAR
   20  M_F_CPU0_SA_DQ<9>  DQ_A9  @S9S_MB_2U_LIB.S9S_MB_2U(SCH_1):M_F_CPU0_SA_DQ<9>
   18  M_F_CPU0_SA_DQ<8>  DQ_A8  @S9S_MB_2U_LIB.S9S_MB_2U(SCH_1):M_F_CPU0_SA_DQ<8>
  161  M_F_CPU0_SA_DQ<7>  DQ_A7  @S9S_MB_2U_LIB.S9S_MB_2U(SCH_1):M_F_CPU0_SA_DQ<7>
  159  M_F_CPU0_SA_DQ<6>  DQ_A6  @S9S_MB_2U_LIB.S9S_MB_2U(SCH_1):M_F_CPU0_SA_DQ<6>
   16  M_F_CPU0_SA_DQ<5>  DQ_A5  @S9S_MB_2U_LIB.S9S_MB_2U(SCH_1):M_F_CPU0_SA_DQ<5>
   14  M_F_CPU0_SA_DQ<4>  DQ_A4  @S9S_MB_2U_LIB.S9S_MB_2U(SCH_1):M_F_CPU0_SA_DQ<4>
  154  M_F_CPU0_SA_DQ<3>  DQ_A3  @S9S_MB_2U_LIB.S9S_MB_2U(SCH_1):M_F_CPU0_SA_DQ<3>
  194  M_F_CPU0_SA_DQ<31>  DQ_A31  @S9S_MB_2U_LIB.S9S_MB_2U(SCH_1):M_F_CPU0_SA_DQ<31>
  192  M_F_CPU0_SA_DQ<30>  DQ_A30  @S9S_MB_2U_LIB.S9S_MB_2U(SCH_1):M_F_CPU0_SA_DQ<30>
  152  M_F_CPU0_SA_DQ<2>  DQ_A2  @S9S_MB_2U_LIB.S9S_MB_2U(SCH_1):M_F_CPU0_SA_DQ<2>
   49  M_F_CPU0_SA_DQ<29>  DQ_A29  @S9S_MB_2U_LIB.S9S_MB_2U(SCH_1):M_F_CPU0_SA_DQ<29>
   47  M_F_CPU0_SA_DQ<28>  DQ_A28  @S9S_MB_2U_LIB.S9S_MB_2U(SCH_1):M_F_CPU0_SA_DQ<28>
  187  M_F_CPU0_SA_DQ<27>  DQ_A27  @S9S_MB_2U_LIB.S9S_MB_2U(SCH_1):M_F_CPU0_SA_DQ<27>
  185  M_F_CPU0_SA_DQ<26>  DQ_A26  @S9S_MB_2U_LIB.S9S_MB_2U(SCH_1):M_F_CPU0_SA_DQ<26>
   42  M_F_CPU0_SA_DQ<25>  DQ_A25  @S9S_MB_2U_LIB.S9S_MB_2U(SCH_1):M_F_CPU0_SA_DQ<25>
   40  M_F_CPU0_SA_DQ<24>  DQ_A24  @S9S_MB_2U_LIB.S9S_MB_2U(SCH_1):M_F_CPU0_SA_DQ<24>
  183  M_F_CPU0_SA_DQ<23>  DQ_A23  @S9S_MB_2U_LIB.S9S_MB_2U(SCH_1):M_F_CPU0_SA_DQ<23>
  181  M_F_CPU0_SA_DQ<22>  DQ_A22  @S9S_MB_2U_LIB.S9S_MB_2U(SCH_1):M_F_CPU0_SA_DQ<22>
   38  M_F_CPU0_SA_DQ<21>  DQ_A21  @S9S_MB_2U_LIB.S9S_MB_2U(SCH_1):M_F_CPU0_SA_DQ<21>
   36  M_F_CPU0_SA_DQ<20>  DQ_A20  @S9S_MB_2U_LIB.S9S_MB_2U(SCH_1):M_F_CPU0_SA_DQ<20>
    9  M_F_CPU0_SA_DQ<1>  DQ_A1  @S9S_MB_2U_LIB.S9S_MB_2U(SCH_1):M_F_CPU0_SA_DQ<1>
  176  M_F_CPU0_SA_DQ<19>  DQ_A19  @S9S_MB_2U_LIB.S9S_MB_2U(SCH_1):M_F_CPU0_SA_DQ<19>
  174  M_F_CPU0_SA_DQ<18>  DQ_A18  @S9S_MB_2U_LIB.S9S_MB_2U(SCH_1):M_F_CPU0_SA_DQ<18>
   31  M_F_CPU0_SA_DQ<17>  DQ_A17  @S9S_MB_2U_LIB.S9S_MB_2U(SCH_1):M_F_CPU0_SA_DQ<17>
   29  M_F_CPU0_SA_DQ<16>  DQ_A16  @S9S_MB_2U_LIB.S9S_MB_2U(SCH_1):M_F_CPU0_SA_DQ<16>
  172  M_F_CPU0_SA_DQ<15>  DQ_A15  @S9S_MB_2U_LIB.S9S_MB_2U(SCH_1):M_F_CPU0_SA_DQ<15>
  170  M_F_CPU0_SA_DQ<14>  DQ_A14  @S9S_MB_2U_LIB.S9S_MB_2U(SCH_1):M_F_CPU0_SA_DQ<14>
   27  M_F_CPU0_SA_DQ<13>  DQ_A13  @S9S_MB_2U_LIB.S9S_MB_2U(SCH_1):M_F_CPU0_SA_DQ<13>
   25  M_F_CPU0_SA_DQ<12>  DQ_A12  @S9S_MB_2U_LIB.S9S_MB_2U(SCH_1):M_F_CPU0_SA_DQ<12>
  165  M_F_CPU0_SA_DQ<11>  DQ_A11  @S9S_MB_2U_LIB.S9S_MB_2U(SCH_1):M_F_CPU0_SA_DQ<11>
  163  M_F_CPU0_SA_DQ<10>  DQ_A10  @S9S_MB_2U_LIB.S9S_MB_2U(SCH_1):M_F_CPU0_SA_DQ<10>
    7  M_F_CPU0_SA_DQ<0>  DQ_A0  @S9S_MB_2U_LIB.S9S_MB_2U(SCH_1):M_F_CPU0_SA_DQ<0>
  209  M_F_CPU0_SA_CS_N<3>  CS1_N_A  @S9S_MB_2U_LIB.S9S_MB_2U(SCH_1):M_F_CPU0_SA_CS_N<3>
   64  M_F_CPU0_SA_CS_N<2>  CS0_N_A  @S9S_MB_2U_LIB.S9S_MB_2U(SCH_1):M_F_CPU0_SA_CS_N<2>
  205  M_F_CPU0_SA_CB<7>  CB_A7  @S9S_MB_2U_LIB.S9S_MB_2U(SCH_1):M_F_CPU0_SA_CB<7>
  203  M_F_CPU0_SA_CB<6>  CB_A6  @S9S_MB_2U_LIB.S9S_MB_2U(SCH_1):M_F_CPU0_SA_CB<6>
   60  M_F_CPU0_SA_CB<5>  CB_A5  @S9S_MB_2U_LIB.S9S_MB_2U(SCH_1):M_F_CPU0_SA_CB<5>
   58  M_F_CPU0_SA_CB<4>  CB_A4  @S9S_MB_2U_LIB.S9S_MB_2U(SCH_1):M_F_CPU0_SA_CB<4>
  198  M_F_CPU0_SA_CB<3>  CB_A3  @S9S_MB_2U_LIB.S9S_MB_2U(SCH_1):M_F_CPU0_SA_CB<3>
  196  M_F_CPU0_SA_CB<2>  CB_A2  @S9S_MB_2U_LIB.S9S_MB_2U(SCH_1):M_F_CPU0_SA_CB<2>
   53  M_F_CPU0_SA_CB<1>  CB_A1  @S9S_MB_2U_LIB.S9S_MB_2U(SCH_1):M_F_CPU0_SA_CB<1>
   51  M_F_CPU0_SA_CB<0>  CB_A0  @S9S_MB_2U_LIB.S9S_MB_2U(SCH_1):M_F_CPU0_SA_CB<0>
   72  M_F_CPU0_SA_CA<6>  CA6_A  @S9S_MB_2U_LIB.S9S_MB_2U(SCH_1):M_F_CPU0_SA_CA<6>
  215  M_F_CPU0_SA_CA<5>  CA5_A  @S9S_MB_2U_LIB.S9S_MB_2U(SCH_1):M_F_CPU0_SA_CA<5>
   70  M_F_CPU0_SA_CA<4>  CA4_A  @S9S_MB_2U_LIB.S9S_MB_2U(SCH_1):M_F_CPU0_SA_CA<4>
  213  M_F_CPU0_SA_CA<3>  CA3_A  @S9S_MB_2U_LIB.S9S_MB_2U(SCH_1):M_F_CPU0_SA_CA<3>
   68  M_F_CPU0_SA_CA<2>  CA2_A  @S9S_MB_2U_LIB.S9S_MB_2U(SCH_1):M_F_CPU0_SA_CA<2>
  211  M_F_CPU0_SA_CA<1>  CA1_A  @S9S_MB_2U_LIB.S9S_MB_2U(SCH_1):M_F_CPU0_SA_CA<1>
   66  M_F_CPU0_SA_CA<0>  CA0_A  @S9S_MB_2U_LIB.S9S_MB_2U(SCH_1):M_F_CPU0_SA_CA<0>
  217  M_F_CPU0_CLK_DP<1>   CK_P  @S9S_MB_2U_LIB.S9S_MB_2U(SCH_1):M_F_CPU0_CLK_DP<1>
  218  M_F_CPU0_CLK_DN<1>   CK_N  @S9S_MB_2U_LIB.S9S_MB_2U(SCH_1):M_F_CPU0_CLK_DN<1>
   62  M_F_CPU0_ALERT_N  ALERT_N  @S9S_MB_2U_LIB.S9S_MB_2U(SCH_1):M_F_CPU0_ALERT_N
    5  I3C_SPD_DDREFGH_CPU0_LVC1_SDA   HSDA  @S9S_MB_2U_LIB.S9S_MB_2U(SCH_1):I3C_SPD_DDREFGH_CPU0_LVC1_SDA
    4  I3C_SPD_DDREFGH_CPU0_LVC1_SCL   HSCL  @S9S_MB_2U_LIB.S9S_MB_2U(SCH_1):I3C_SPD_DDREFGH_CPU0_LVC1_SCL

SCONN288_ADR50001P013C01  I164  J13    [SCONN288_ADR50001P013C01-SCONNA]
  146  P12V_S3_AUX_CPU0_NVDIMM  VIN_BULK2  @S9S_MB_2U_LIB.S9S_MB_2U(SCH_1):P12V_S3_AUX_CPU0_NVDIMM
  145  P12V_S3_AUX_CPU0_NVDIMM  VIN_BULK1  @S9S_MB_2U_LIB.S9S_MB_2U(SCH_1):P12V_S3_AUX_CPU0_NVDIMM
    1  P12V_S3_AUX_CPU0_NVDIMM  VIN_BULK0  @S9S_MB_2U_LIB.S9S_MB_2U(SCH_1):P12V_S3_AUX_CPU0_NVDIMM
  288  GND            VSS126  @S9S_MB_2U_LIB.S9S_MB_2U(SCH_1):GND
  286  GND            VSS125  @S9S_MB_2U_LIB.S9S_MB_2U(SCH_1):GND
  284  GND            VSS124  @S9S_MB_2U_LIB.S9S_MB_2U(SCH_1):GND
  281  GND            VSS123  @S9S_MB_2U_LIB.S9S_MB_2U(SCH_1):GND
  279  GND            VSS122  @S9S_MB_2U_LIB.S9S_MB_2U(SCH_1):GND
  277  GND            VSS121  @S9S_MB_2U_LIB.S9S_MB_2U(SCH_1):GND
  275  GND            VSS120  @S9S_MB_2U_LIB.S9S_MB_2U(SCH_1):GND
  273  GND            VSS119  @S9S_MB_2U_LIB.S9S_MB_2U(SCH_1):GND
  270  GND            VSS118  @S9S_MB_2U_LIB.S9S_MB_2U(SCH_1):GND
  268  GND            VSS117  @S9S_MB_2U_LIB.S9S_MB_2U(SCH_1):GND
  266  GND            VSS116  @S9S_MB_2U_LIB.S9S_MB_2U(SCH_1):GND
  264  GND            VSS115  @S9S_MB_2U_LIB.S9S_MB_2U(SCH_1):GND
  262  GND            VSS114  @S9S_MB_2U_LIB.S9S_MB_2U(SCH_1):GND
  259  GND            VSS113  @S9S_MB_2U_LIB.S9S_MB_2U(SCH_1):GND
  257  GND            VSS112  @S9S_MB_2U_LIB.S9S_MB_2U(SCH_1):GND
  255  GND            VSS111  @S9S_MB_2U_LIB.S9S_MB_2U(SCH_1):GND
  253  GND            VSS110  @S9S_MB_2U_LIB.S9S_MB_2U(SCH_1):GND
  251  GND            VSS109  @S9S_MB_2U_LIB.S9S_MB_2U(SCH_1):GND
  248  GND            VSS108  @S9S_MB_2U_LIB.S9S_MB_2U(SCH_1):GND
  246  GND            VSS107  @S9S_MB_2U_LIB.S9S_MB_2U(SCH_1):GND
  244  GND            VSS106  @S9S_MB_2U_LIB.S9S_MB_2U(SCH_1):GND
  242  GND            VSS105  @S9S_MB_2U_LIB.S9S_MB_2U(SCH_1):GND
  240  GND            VSS104  @S9S_MB_2U_LIB.S9S_MB_2U(SCH_1):GND
  237  GND            VSS103  @S9S_MB_2U_LIB.S9S_MB_2U(SCH_1):GND
  235  GND            VSS102  @S9S_MB_2U_LIB.S9S_MB_2U(SCH_1):GND
  233  GND            VSS101  @S9S_MB_2U_LIB.S9S_MB_2U(SCH_1):GND
  230  GND            VSS100  @S9S_MB_2U_LIB.S9S_MB_2U(SCH_1):GND
  228  GND            VSS99  @S9S_MB_2U_LIB.S9S_MB_2U(SCH_1):GND
  226  GND            VSS98  @S9S_MB_2U_LIB.S9S_MB_2U(SCH_1):GND
  224  GND            VSS97  @S9S_MB_2U_LIB.S9S_MB_2U(SCH_1):GND
  222  GND            VSS96  @S9S_MB_2U_LIB.S9S_MB_2U(SCH_1):GND
  219  GND            VSS95  @S9S_MB_2U_LIB.S9S_MB_2U(SCH_1):GND
  216  GND            VSS94  @S9S_MB_2U_LIB.S9S_MB_2U(SCH_1):GND
  214  GND            VSS93  @S9S_MB_2U_LIB.S9S_MB_2U(SCH_1):GND
  212  GND            VSS92  @S9S_MB_2U_LIB.S9S_MB_2U(SCH_1):GND
  210  GND            VSS91  @S9S_MB_2U_LIB.S9S_MB_2U(SCH_1):GND
  208  GND            VSS90  @S9S_MB_2U_LIB.S9S_MB_2U(SCH_1):GND
  206  GND            VSS89  @S9S_MB_2U_LIB.S9S_MB_2U(SCH_1):GND
  204  GND            VSS88  @S9S_MB_2U_LIB.S9S_MB_2U(SCH_1):GND
  202  GND            VSS87  @S9S_MB_2U_LIB.S9S_MB_2U(SCH_1):GND
  199  GND            VSS86  @S9S_MB_2U_LIB.S9S_MB_2U(SCH_1):GND
  197  GND            VSS85  @S9S_MB_2U_LIB.S9S_MB_2U(SCH_1):GND
  195  GND            VSS84  @S9S_MB_2U_LIB.S9S_MB_2U(SCH_1):GND
  193  GND            VSS83  @S9S_MB_2U_LIB.S9S_MB_2U(SCH_1):GND
  191  GND            VSS82  @S9S_MB_2U_LIB.S9S_MB_2U(SCH_1):GND
  188  GND            VSS81  @S9S_MB_2U_LIB.S9S_MB_2U(SCH_1):GND
  186  GND            VSS80  @S9S_MB_2U_LIB.S9S_MB_2U(SCH_1):GND
  184  GND            VSS79  @S9S_MB_2U_LIB.S9S_MB_2U(SCH_1):GND
  182  GND            VSS78  @S9S_MB_2U_LIB.S9S_MB_2U(SCH_1):GND
  180  GND            VSS77  @S9S_MB_2U_LIB.S9S_MB_2U(SCH_1):GND
  177  GND            VSS76  @S9S_MB_2U_LIB.S9S_MB_2U(SCH_1):GND
  175  GND            VSS75  @S9S_MB_2U_LIB.S9S_MB_2U(SCH_1):GND
  173  GND            VSS74  @S9S_MB_2U_LIB.S9S_MB_2U(SCH_1):GND
  171  GND            VSS73  @S9S_MB_2U_LIB.S9S_MB_2U(SCH_1):GND
  169  GND            VSS72  @S9S_MB_2U_LIB.S9S_MB_2U(SCH_1):GND
  166  GND            VSS71  @S9S_MB_2U_LIB.S9S_MB_2U(SCH_1):GND
  164  GND            VSS70  @S9S_MB_2U_LIB.S9S_MB_2U(SCH_1):GND
  162  GND            VSS69  @S9S_MB_2U_LIB.S9S_MB_2U(SCH_1):GND
  160  GND            VSS68  @S9S_MB_2U_LIB.S9S_MB_2U(SCH_1):GND
  158  GND            VSS67  @S9S_MB_2U_LIB.S9S_MB_2U(SCH_1):GND
  155  GND            VSS66  @S9S_MB_2U_LIB.S9S_MB_2U(SCH_1):GND
  153  GND            VSS65  @S9S_MB_2U_LIB.S9S_MB_2U(SCH_1):GND
  151  GND            VSS64  @S9S_MB_2U_LIB.S9S_MB_2U(SCH_1):GND
  143  GND            VSS63  @S9S_MB_2U_LIB.S9S_MB_2U(SCH_1):GND
  141  GND            VSS62  @S9S_MB_2U_LIB.S9S_MB_2U(SCH_1):GND
  139  GND            VSS61  @S9S_MB_2U_LIB.S9S_MB_2U(SCH_1):GND
  136  GND            VSS60  @S9S_MB_2U_LIB.S9S_MB_2U(SCH_1):GND
  134  GND            VSS59  @S9S_MB_2U_LIB.S9S_MB_2U(SCH_1):GND
  132  GND            VSS58  @S9S_MB_2U_LIB.S9S_MB_2U(SCH_1):GND
  130  GND            VSS57  @S9S_MB_2U_LIB.S9S_MB_2U(SCH_1):GND
  128  GND            VSS56  @S9S_MB_2U_LIB.S9S_MB_2U(SCH_1):GND
  125  GND            VSS55  @S9S_MB_2U_LIB.S9S_MB_2U(SCH_1):GND
  123  GND            VSS54  @S9S_MB_2U_LIB.S9S_MB_2U(SCH_1):GND
  121  GND            VSS53  @S9S_MB_2U_LIB.S9S_MB_2U(SCH_1):GND
  119  GND            VSS52  @S9S_MB_2U_LIB.S9S_MB_2U(SCH_1):GND
  117  GND            VSS51  @S9S_MB_2U_LIB.S9S_MB_2U(SCH_1):GND
  114  GND            VSS50  @S9S_MB_2U_LIB.S9S_MB_2U(SCH_1):GND
  112  GND            VSS49  @S9S_MB_2U_LIB.S9S_MB_2U(SCH_1):GND
  110  GND            VSS48  @S9S_MB_2U_LIB.S9S_MB_2U(SCH_1):GND
  108  GND            VSS47  @S9S_MB_2U_LIB.S9S_MB_2U(SCH_1):GND
  106  GND            VSS46  @S9S_MB_2U_LIB.S9S_MB_2U(SCH_1):GND
  103  GND            VSS45  @S9S_MB_2U_LIB.S9S_MB_2U(SCH_1):GND
  101  GND            VSS44  @S9S_MB_2U_LIB.S9S_MB_2U(SCH_1):GND
   99  GND            VSS43  @S9S_MB_2U_LIB.S9S_MB_2U(SCH_1):GND
   97  GND            VSS42  @S9S_MB_2U_LIB.S9S_MB_2U(SCH_1):GND
   95  GND            VSS41  @S9S_MB_2U_LIB.S9S_MB_2U(SCH_1):GND
   92  GND            VSS40  @S9S_MB_2U_LIB.S9S_MB_2U(SCH_1):GND
   90  GND            VSS39  @S9S_MB_2U_LIB.S9S_MB_2U(SCH_1):GND
   88  GND            VSS38  @S9S_MB_2U_LIB.S9S_MB_2U(SCH_1):GND
   85  GND            VSS37  @S9S_MB_2U_LIB.S9S_MB_2U(SCH_1):GND
   83  GND            VSS36  @S9S_MB_2U_LIB.S9S_MB_2U(SCH_1):GND
   81  GND            VSS35  @S9S_MB_2U_LIB.S9S_MB_2U(SCH_1):GND
   79  GND            VSS34  @S9S_MB_2U_LIB.S9S_MB_2U(SCH_1):GND
   77  GND            VSS33  @S9S_MB_2U_LIB.S9S_MB_2U(SCH_1):GND
   75  GND            VSS32  @S9S_MB_2U_LIB.S9S_MB_2U(SCH_1):GND
   73  GND            VSS31  @S9S_MB_2U_LIB.S9S_MB_2U(SCH_1):GND
   71  GND            VSS30  @S9S_MB_2U_LIB.S9S_MB_2U(SCH_1):GND
   69  GND            VSS29  @S9S_MB_2U_LIB.S9S_MB_2U(SCH_1):GND
   67  GND            VSS28  @S9S_MB_2U_LIB.S9S_MB_2U(SCH_1):GND
   65  GND            VSS27  @S9S_MB_2U_LIB.S9S_MB_2U(SCH_1):GND
   63  GND            VSS26  @S9S_MB_2U_LIB.S9S_MB_2U(SCH_1):GND
   61  GND            VSS25  @S9S_MB_2U_LIB.S9S_MB_2U(SCH_1):GND
   59  GND            VSS24  @S9S_MB_2U_LIB.S9S_MB_2U(SCH_1):GND
   57  GND            VSS23  @S9S_MB_2U_LIB.S9S_MB_2U(SCH_1):GND
   54  GND            VSS22  @S9S_MB_2U_LIB.S9S_MB_2U(SCH_1):GND
   52  GND            VSS21  @S9S_MB_2U_LIB.S9S_MB_2U(SCH_1):GND
   50  GND            VSS20  @S9S_MB_2U_LIB.S9S_MB_2U(SCH_1):GND
   48  GND            VSS19  @S9S_MB_2U_LIB.S9S_MB_2U(SCH_1):GND
   46  GND            VSS18  @S9S_MB_2U_LIB.S9S_MB_2U(SCH_1):GND
   43  GND            VSS17  @S9S_MB_2U_LIB.S9S_MB_2U(SCH_1):GND
   41  GND            VSS16  @S9S_MB_2U_LIB.S9S_MB_2U(SCH_1):GND
   39  GND            VSS15  @S9S_MB_2U_LIB.S9S_MB_2U(SCH_1):GND
   37  GND            VSS14  @S9S_MB_2U_LIB.S9S_MB_2U(SCH_1):GND
   35  GND            VSS13  @S9S_MB_2U_LIB.S9S_MB_2U(SCH_1):GND
   32  GND            VSS12  @S9S_MB_2U_LIB.S9S_MB_2U(SCH_1):GND
   30  GND            VSS11  @S9S_MB_2U_LIB.S9S_MB_2U(SCH_1):GND
   28  GND            VSS10  @S9S_MB_2U_LIB.S9S_MB_2U(SCH_1):GND
   26  GND             VSS9  @S9S_MB_2U_LIB.S9S_MB_2U(SCH_1):GND
   24  GND             VSS8  @S9S_MB_2U_LIB.S9S_MB_2U(SCH_1):GND
   21  GND             VSS7  @S9S_MB_2U_LIB.S9S_MB_2U(SCH_1):GND
   19  GND             VSS6  @S9S_MB_2U_LIB.S9S_MB_2U(SCH_1):GND
   17  GND             VSS5  @S9S_MB_2U_LIB.S9S_MB_2U(SCH_1):GND
   15  GND             VSS4  @S9S_MB_2U_LIB.S9S_MB_2U(SCH_1):GND
   13  GND             VSS3  @S9S_MB_2U_LIB.S9S_MB_2U(SCH_1):GND
   10  GND             VSS2  @S9S_MB_2U_LIB.S9S_MB_2U(SCH_1):GND
    8  GND             VSS1  @S9S_MB_2U_LIB.S9S_MB_2U(SCH_1):GND
    6  GND             VSS0  @S9S_MB_2U_LIB.S9S_MB_2U(SCH_1):GND
   G3  GND               G3  @S9S_MB_2U_LIB.S9S_MB_2U(SCH_1):GND
   G2  GND               G2  @S9S_MB_2U_LIB.S9S_MB_2U(SCH_1):GND
   G1  GND               G1  @S9S_MB_2U_LIB.S9S_MB_2U(SCH_1):GND

SCONN288_ADR50001P013C01  I127  J13    [SCONN288_ADR50001P013C01-SCONNA]
   93  M_G_CPU0_SB_DQS_DP<9>  DQS9_B_P  @S9S_MB_2U_LIB.S9S_MB_2U(SCH_1):M_G_CPU0_SB_DQS_DP<9>
  283  M_G_CPU0_SB_DQS_DP<8>  DQS8_B_P  @S9S_MB_2U_LIB.S9S_MB_2U(SCH_1):M_G_CPU0_SB_DQS_DP<8>
  272  M_G_CPU0_SB_DQS_DP<7>  DQS7_B_P  @S9S_MB_2U_LIB.S9S_MB_2U(SCH_1):M_G_CPU0_SB_DQS_DP<7>
  261  M_G_CPU0_SB_DQS_DP<6>  DQS6_B_P  @S9S_MB_2U_LIB.S9S_MB_2U(SCH_1):M_G_CPU0_SB_DQS_DP<6>
  250  M_G_CPU0_SB_DQS_DP<5>  DQS5_B_P  @S9S_MB_2U_LIB.S9S_MB_2U(SCH_1):M_G_CPU0_SB_DQS_DP<5>
  239  M_G_CPU0_SB_DQS_DP<4>  DQS4_B_P  @S9S_MB_2U_LIB.S9S_MB_2U(SCH_1):M_G_CPU0_SB_DQS_DP<4>
  137  M_G_CPU0_SB_DQS_DP<3>  DQS3_B_P  @S9S_MB_2U_LIB.S9S_MB_2U(SCH_1):M_G_CPU0_SB_DQS_DP<3>
  126  M_G_CPU0_SB_DQS_DP<2>  DQS2_B_P  @S9S_MB_2U_LIB.S9S_MB_2U(SCH_1):M_G_CPU0_SB_DQS_DP<2>
  115  M_G_CPU0_SB_DQS_DP<1>  DQS1_B_P  @S9S_MB_2U_LIB.S9S_MB_2U(SCH_1):M_G_CPU0_SB_DQS_DP<1>
  104  M_G_CPU0_SB_DQS_DP<0>  DQS0_B_P  @S9S_MB_2U_LIB.S9S_MB_2U(SCH_1):M_G_CPU0_SB_DQS_DP<0>
   94  M_G_CPU0_SB_DQS_DN<9>  DQS9_B_N  @S9S_MB_2U_LIB.S9S_MB_2U(SCH_1):M_G_CPU0_SB_DQS_DN<9>
  282  M_G_CPU0_SB_DQS_DN<8>  DQS8_B_N  @S9S_MB_2U_LIB.S9S_MB_2U(SCH_1):M_G_CPU0_SB_DQS_DN<8>
  271  M_G_CPU0_SB_DQS_DN<7>  DQS7_B_N  @S9S_MB_2U_LIB.S9S_MB_2U(SCH_1):M_G_CPU0_SB_DQS_DN<7>
  260  M_G_CPU0_SB_DQS_DN<6>  DQS6_B_N  @S9S_MB_2U_LIB.S9S_MB_2U(SCH_1):M_G_CPU0_SB_DQS_DN<6>
  249  M_G_CPU0_SB_DQS_DN<5>  DQS5_B_N  @S9S_MB_2U_LIB.S9S_MB_2U(SCH_1):M_G_CPU0_SB_DQS_DN<5>
  238  M_G_CPU0_SB_DQS_DN<4>  DQS4_B_N  @S9S_MB_2U_LIB.S9S_MB_2U(SCH_1):M_G_CPU0_SB_DQS_DN<4>
  138  M_G_CPU0_SB_DQS_DN<3>  DQS3_B_N  @S9S_MB_2U_LIB.S9S_MB_2U(SCH_1):M_G_CPU0_SB_DQS_DN<3>
  127  M_G_CPU0_SB_DQS_DN<2>  DQS2_B_N  @S9S_MB_2U_LIB.S9S_MB_2U(SCH_1):M_G_CPU0_SB_DQS_DN<2>
  116  M_G_CPU0_SB_DQS_DN<1>  DQS1_B_N  @S9S_MB_2U_LIB.S9S_MB_2U(SCH_1):M_G_CPU0_SB_DQS_DN<1>
  105  M_G_CPU0_SB_DQS_DN<0>  DQS0_B_N  @S9S_MB_2U_LIB.S9S_MB_2U(SCH_1):M_G_CPU0_SB_DQS_DN<0>
  201  M_G_CPU0_SA_DQS_DP<9>  DQS9_A_P  @S9S_MB_2U_LIB.S9S_MB_2U(SCH_1):M_G_CPU0_SA_DQS_DP<9>
  190  M_G_CPU0_SA_DQS_DP<8>  DQS8_A_P  @S9S_MB_2U_LIB.S9S_MB_2U(SCH_1):M_G_CPU0_SA_DQS_DP<8>
  179  M_G_CPU0_SA_DQS_DP<7>  DQS7_A_P  @S9S_MB_2U_LIB.S9S_MB_2U(SCH_1):M_G_CPU0_SA_DQS_DP<7>
  168  M_G_CPU0_SA_DQS_DP<6>  DQS6_A_P  @S9S_MB_2U_LIB.S9S_MB_2U(SCH_1):M_G_CPU0_SA_DQS_DP<6>
  157  M_G_CPU0_SA_DQS_DP<5>  DQS5_A_P  @S9S_MB_2U_LIB.S9S_MB_2U(SCH_1):M_G_CPU0_SA_DQS_DP<5>
   55  M_G_CPU0_SA_DQS_DP<4>  DQS4_A_P  @S9S_MB_2U_LIB.S9S_MB_2U(SCH_1):M_G_CPU0_SA_DQS_DP<4>
   44  M_G_CPU0_SA_DQS_DP<3>  DQS3_A_P  @S9S_MB_2U_LIB.S9S_MB_2U(SCH_1):M_G_CPU0_SA_DQS_DP<3>
   33  M_G_CPU0_SA_DQS_DP<2>  DQS2_A_P  @S9S_MB_2U_LIB.S9S_MB_2U(SCH_1):M_G_CPU0_SA_DQS_DP<2>
   22  M_G_CPU0_SA_DQS_DP<1>  DQS1_A_P  @S9S_MB_2U_LIB.S9S_MB_2U(SCH_1):M_G_CPU0_SA_DQS_DP<1>
   11  M_G_CPU0_SA_DQS_DP<0>  DQS0_A_P  @S9S_MB_2U_LIB.S9S_MB_2U(SCH_1):M_G_CPU0_SA_DQS_DP<0>
  200  M_G_CPU0_SA_DQS_DN<9>  DQS9_A_N  @S9S_MB_2U_LIB.S9S_MB_2U(SCH_1):M_G_CPU0_SA_DQS_DN<9>
  189  M_G_CPU0_SA_DQS_DN<8>  DQS8_A_N  @S9S_MB_2U_LIB.S9S_MB_2U(SCH_1):M_G_CPU0_SA_DQS_DN<8>
  178  M_G_CPU0_SA_DQS_DN<7>  DQS7_A_N  @S9S_MB_2U_LIB.S9S_MB_2U(SCH_1):M_G_CPU0_SA_DQS_DN<7>
  167  M_G_CPU0_SA_DQS_DN<6>  DQS6_A_N  @S9S_MB_2U_LIB.S9S_MB_2U(SCH_1):M_G_CPU0_SA_DQS_DN<6>
  156  M_G_CPU0_SA_DQS_DN<5>  DQS5_A_N  @S9S_MB_2U_LIB.S9S_MB_2U(SCH_1):M_G_CPU0_SA_DQS_DN<5>
   56  M_G_CPU0_SA_DQS_DN<4>  DQS4_A_N  @S9S_MB_2U_LIB.S9S_MB_2U(SCH_1):M_G_CPU0_SA_DQS_DN<4>
   45  M_G_CPU0_SA_DQS_DN<3>  DQS3_A_N  @S9S_MB_2U_LIB.S9S_MB_2U(SCH_1):M_G_CPU0_SA_DQS_DN<3>
   34  M_G_CPU0_SA_DQS_DN<2>  DQS2_A_N  @S9S_MB_2U_LIB.S9S_MB_2U(SCH_1):M_G_CPU0_SA_DQS_DN<2>
   23  M_G_CPU0_SA_DQS_DN<1>  DQS1_A_N  @S9S_MB_2U_LIB.S9S_MB_2U(SCH_1):M_G_CPU0_SA_DQS_DN<1>
   12  M_G_CPU0_SA_DQS_DN<0>  DQS0_A_N  @S9S_MB_2U_LIB.S9S_MB_2U(SCH_1):M_G_CPU0_SA_DQS_DN<0>

SCONN288_ADR50001P013C01  I11  J13    [SCONN288_ADR50001P013C01-SCONNA]
  232  NC              RFU6  NC
  231  NC              RFU5  NC
  220  NC              RFU4  NC
  150  NC              RFU3  NC
  149  NC              RFU2  NC
  144  NC              RFU1  NC
    2  NC              RFU0  NC
  207  RST_M_GH_CPU0_FPGA_N  RESET_N  @S9S_MB_2U_LIB.S9S_MB_2U(SCH_1):RST_M_GH_CPU0_FPGA_N
  147  PWRGD_CHG_CPU0_DIMM1  PWR_GOOD||FAIL_N  @S9S_MB_2U_LIB.S9S_MB_2U(SCH_1):PWRGD_CHG_CPU0_DIMM1
  148  PD_CHG_CPU0_DIMM1_SAA    HAS  @S9S_MB_2U_LIB.S9S_MB_2U(SCH_1):PD_CHG_CPU0_DIMM1_SAA
    3  P3V3_AUX       VIN_MGMT  @S9S_MB_2U_LIB.S9S_MB_2U(SCH_1):P3V3_AUX
   87  M_G_CPU0_SB_RSP<0>  LBS||RSP_N_B  @S9S_MB_2U_LIB.S9S_MB_2U(SCH_1):M_G_CPU0_SB_RSP<0>
  227  M_G_CPU0_SB_PAR  PAR_B  @S9S_MB_2U_LIB.S9S_MB_2U(SCH_1):M_G_CPU0_SB_PAR
  113  M_G_CPU0_SB_DQ<9>  DQ_B9  @S9S_MB_2U_LIB.S9S_MB_2U(SCH_1):M_G_CPU0_SB_DQ<9>
  111  M_G_CPU0_SB_DQ<8>  DQ_B8  @S9S_MB_2U_LIB.S9S_MB_2U(SCH_1):M_G_CPU0_SB_DQ<8>
  254  M_G_CPU0_SB_DQ<7>  DQ_B7  @S9S_MB_2U_LIB.S9S_MB_2U(SCH_1):M_G_CPU0_SB_DQ<7>
  252  M_G_CPU0_SB_DQ<6>  DQ_B6  @S9S_MB_2U_LIB.S9S_MB_2U(SCH_1):M_G_CPU0_SB_DQ<6>
  109  M_G_CPU0_SB_DQ<5>  DQ_B5  @S9S_MB_2U_LIB.S9S_MB_2U(SCH_1):M_G_CPU0_SB_DQ<5>
  107  M_G_CPU0_SB_DQ<4>  DQ_B4  @S9S_MB_2U_LIB.S9S_MB_2U(SCH_1):M_G_CPU0_SB_DQ<4>
  247  M_G_CPU0_SB_DQ<3>  DQ_B3  @S9S_MB_2U_LIB.S9S_MB_2U(SCH_1):M_G_CPU0_SB_DQ<3>
  287  M_G_CPU0_SB_DQ<31>  DQ_B31  @S9S_MB_2U_LIB.S9S_MB_2U(SCH_1):M_G_CPU0_SB_DQ<31>
  285  M_G_CPU0_SB_DQ<30>  DQ_B30  @S9S_MB_2U_LIB.S9S_MB_2U(SCH_1):M_G_CPU0_SB_DQ<30>
  245  M_G_CPU0_SB_DQ<2>  DQ_B2  @S9S_MB_2U_LIB.S9S_MB_2U(SCH_1):M_G_CPU0_SB_DQ<2>
  142  M_G_CPU0_SB_DQ<29>  DQ_B29  @S9S_MB_2U_LIB.S9S_MB_2U(SCH_1):M_G_CPU0_SB_DQ<29>
  140  M_G_CPU0_SB_DQ<28>  DQ_B28  @S9S_MB_2U_LIB.S9S_MB_2U(SCH_1):M_G_CPU0_SB_DQ<28>
  280  M_G_CPU0_SB_DQ<27>  DQ_B27  @S9S_MB_2U_LIB.S9S_MB_2U(SCH_1):M_G_CPU0_SB_DQ<27>
  278  M_G_CPU0_SB_DQ<26>  DQ_B26  @S9S_MB_2U_LIB.S9S_MB_2U(SCH_1):M_G_CPU0_SB_DQ<26>
  135  M_G_CPU0_SB_DQ<25>  DQ_B25  @S9S_MB_2U_LIB.S9S_MB_2U(SCH_1):M_G_CPU0_SB_DQ<25>
  133  M_G_CPU0_SB_DQ<24>  DQ_B24  @S9S_MB_2U_LIB.S9S_MB_2U(SCH_1):M_G_CPU0_SB_DQ<24>
  276  M_G_CPU0_SB_DQ<23>  DQ_B23  @S9S_MB_2U_LIB.S9S_MB_2U(SCH_1):M_G_CPU0_SB_DQ<23>
  274  M_G_CPU0_SB_DQ<22>  DQ_B22  @S9S_MB_2U_LIB.S9S_MB_2U(SCH_1):M_G_CPU0_SB_DQ<22>
  131  M_G_CPU0_SB_DQ<21>  DQ_B21  @S9S_MB_2U_LIB.S9S_MB_2U(SCH_1):M_G_CPU0_SB_DQ<21>
  129  M_G_CPU0_SB_DQ<20>  DQ_B20  @S9S_MB_2U_LIB.S9S_MB_2U(SCH_1):M_G_CPU0_SB_DQ<20>
  102  M_G_CPU0_SB_DQ<1>  DQ_B1  @S9S_MB_2U_LIB.S9S_MB_2U(SCH_1):M_G_CPU0_SB_DQ<1>
  269  M_G_CPU0_SB_DQ<19>  DQ_B19  @S9S_MB_2U_LIB.S9S_MB_2U(SCH_1):M_G_CPU0_SB_DQ<19>
  267  M_G_CPU0_SB_DQ<18>  DQ_B18  @S9S_MB_2U_LIB.S9S_MB_2U(SCH_1):M_G_CPU0_SB_DQ<18>
  124  M_G_CPU0_SB_DQ<17>  DQ_B17  @S9S_MB_2U_LIB.S9S_MB_2U(SCH_1):M_G_CPU0_SB_DQ<17>
  122  M_G_CPU0_SB_DQ<16>  DQ_B16  @S9S_MB_2U_LIB.S9S_MB_2U(SCH_1):M_G_CPU0_SB_DQ<16>
  265  M_G_CPU0_SB_DQ<15>  DQ_B15  @S9S_MB_2U_LIB.S9S_MB_2U(SCH_1):M_G_CPU0_SB_DQ<15>
  263  M_G_CPU0_SB_DQ<14>  DQ_B14  @S9S_MB_2U_LIB.S9S_MB_2U(SCH_1):M_G_CPU0_SB_DQ<14>
  120  M_G_CPU0_SB_DQ<13>  DQ_B13  @S9S_MB_2U_LIB.S9S_MB_2U(SCH_1):M_G_CPU0_SB_DQ<13>
  118  M_G_CPU0_SB_DQ<12>  DQ_B12  @S9S_MB_2U_LIB.S9S_MB_2U(SCH_1):M_G_CPU0_SB_DQ<12>
  258  M_G_CPU0_SB_DQ<11>  DQ_B11  @S9S_MB_2U_LIB.S9S_MB_2U(SCH_1):M_G_CPU0_SB_DQ<11>
  256  M_G_CPU0_SB_DQ<10>  DQ_B10  @S9S_MB_2U_LIB.S9S_MB_2U(SCH_1):M_G_CPU0_SB_DQ<10>
  100  M_G_CPU0_SB_DQ<0>  DQ_B0  @S9S_MB_2U_LIB.S9S_MB_2U(SCH_1):M_G_CPU0_SB_DQ<0>
  229  M_G_CPU0_SB_CS_N<1>  CS1_N_B  @S9S_MB_2U_LIB.S9S_MB_2U(SCH_1):M_G_CPU0_SB_CS_N<1>
   84  M_G_CPU0_SB_CS_N<0>  CS0_N_B  @S9S_MB_2U_LIB.S9S_MB_2U(SCH_1):M_G_CPU0_SB_CS_N<0>
  236  M_G_CPU0_SB_CB<7>  CB_B7  @S9S_MB_2U_LIB.S9S_MB_2U(SCH_1):M_G_CPU0_SB_CB<7>
  234  M_G_CPU0_SB_CB<6>  CB_B6  @S9S_MB_2U_LIB.S9S_MB_2U(SCH_1):M_G_CPU0_SB_CB<6>
   91  M_G_CPU0_SB_CB<5>  CB_B5  @S9S_MB_2U_LIB.S9S_MB_2U(SCH_1):M_G_CPU0_SB_CB<5>
   89  M_G_CPU0_SB_CB<4>  CB_B4  @S9S_MB_2U_LIB.S9S_MB_2U(SCH_1):M_G_CPU0_SB_CB<4>
  243  M_G_CPU0_SB_CB<3>  CB_B3  @S9S_MB_2U_LIB.S9S_MB_2U(SCH_1):M_G_CPU0_SB_CB<3>
  241  M_G_CPU0_SB_CB<2>  CB_B2  @S9S_MB_2U_LIB.S9S_MB_2U(SCH_1):M_G_CPU0_SB_CB<2>
   98  M_G_CPU0_SB_CB<1>  CB_B1  @S9S_MB_2U_LIB.S9S_MB_2U(SCH_1):M_G_CPU0_SB_CB<1>
   96  M_G_CPU0_SB_CB<0>  CB_B0  @S9S_MB_2U_LIB.S9S_MB_2U(SCH_1):M_G_CPU0_SB_CB<0>
   82  M_G_CPU0_SB_CA<6>  CA6_B  @S9S_MB_2U_LIB.S9S_MB_2U(SCH_1):M_G_CPU0_SB_CA<6>
  225  M_G_CPU0_SB_CA<5>  CA5_B  @S9S_MB_2U_LIB.S9S_MB_2U(SCH_1):M_G_CPU0_SB_CA<5>
   80  M_G_CPU0_SB_CA<4>  CA4_B  @S9S_MB_2U_LIB.S9S_MB_2U(SCH_1):M_G_CPU0_SB_CA<4>
  223  M_G_CPU0_SB_CA<3>  CA3_B  @S9S_MB_2U_LIB.S9S_MB_2U(SCH_1):M_G_CPU0_SB_CA<3>
   78  M_G_CPU0_SB_CA<2>  CA2_B  @S9S_MB_2U_LIB.S9S_MB_2U(SCH_1):M_G_CPU0_SB_CA<2>
  221  M_G_CPU0_SB_CA<1>  CA1_B  @S9S_MB_2U_LIB.S9S_MB_2U(SCH_1):M_G_CPU0_SB_CA<1>
   76  M_G_CPU0_SB_CA<0>  CA0_B  @S9S_MB_2U_LIB.S9S_MB_2U(SCH_1):M_G_CPU0_SB_CA<0>
   86  M_G_CPU0_SA_RSP<0>  LBD||RSP_N_A  @S9S_MB_2U_LIB.S9S_MB_2U(SCH_1):M_G_CPU0_SA_RSP<0>
   74  M_G_CPU0_SA_PAR  PAR_A  @S9S_MB_2U_LIB.S9S_MB_2U(SCH_1):M_G_CPU0_SA_PAR
   20  M_G_CPU0_SA_DQ<9>  DQ_A9  @S9S_MB_2U_LIB.S9S_MB_2U(SCH_1):M_G_CPU0_SA_DQ<9>
   18  M_G_CPU0_SA_DQ<8>  DQ_A8  @S9S_MB_2U_LIB.S9S_MB_2U(SCH_1):M_G_CPU0_SA_DQ<8>
  161  M_G_CPU0_SA_DQ<7>  DQ_A7  @S9S_MB_2U_LIB.S9S_MB_2U(SCH_1):M_G_CPU0_SA_DQ<7>
  159  M_G_CPU0_SA_DQ<6>  DQ_A6  @S9S_MB_2U_LIB.S9S_MB_2U(SCH_1):M_G_CPU0_SA_DQ<6>
   16  M_G_CPU0_SA_DQ<5>  DQ_A5  @S9S_MB_2U_LIB.S9S_MB_2U(SCH_1):M_G_CPU0_SA_DQ<5>
   14  M_G_CPU0_SA_DQ<4>  DQ_A4  @S9S_MB_2U_LIB.S9S_MB_2U(SCH_1):M_G_CPU0_SA_DQ<4>
  154  M_G_CPU0_SA_DQ<3>  DQ_A3  @S9S_MB_2U_LIB.S9S_MB_2U(SCH_1):M_G_CPU0_SA_DQ<3>
  194  M_G_CPU0_SA_DQ<31>  DQ_A31  @S9S_MB_2U_LIB.S9S_MB_2U(SCH_1):M_G_CPU0_SA_DQ<31>
  192  M_G_CPU0_SA_DQ<30>  DQ_A30  @S9S_MB_2U_LIB.S9S_MB_2U(SCH_1):M_G_CPU0_SA_DQ<30>
  152  M_G_CPU0_SA_DQ<2>  DQ_A2  @S9S_MB_2U_LIB.S9S_MB_2U(SCH_1):M_G_CPU0_SA_DQ<2>
   49  M_G_CPU0_SA_DQ<29>  DQ_A29  @S9S_MB_2U_LIB.S9S_MB_2U(SCH_1):M_G_CPU0_SA_DQ<29>
   47  M_G_CPU0_SA_DQ<28>  DQ_A28  @S9S_MB_2U_LIB.S9S_MB_2U(SCH_1):M_G_CPU0_SA_DQ<28>
  187  M_G_CPU0_SA_DQ<27>  DQ_A27  @S9S_MB_2U_LIB.S9S_MB_2U(SCH_1):M_G_CPU0_SA_DQ<27>
  185  M_G_CPU0_SA_DQ<26>  DQ_A26  @S9S_MB_2U_LIB.S9S_MB_2U(SCH_1):M_G_CPU0_SA_DQ<26>
   42  M_G_CPU0_SA_DQ<25>  DQ_A25  @S9S_MB_2U_LIB.S9S_MB_2U(SCH_1):M_G_CPU0_SA_DQ<25>
   40  M_G_CPU0_SA_DQ<24>  DQ_A24  @S9S_MB_2U_LIB.S9S_MB_2U(SCH_1):M_G_CPU0_SA_DQ<24>
  183  M_G_CPU0_SA_DQ<23>  DQ_A23  @S9S_MB_2U_LIB.S9S_MB_2U(SCH_1):M_G_CPU0_SA_DQ<23>
  181  M_G_CPU0_SA_DQ<22>  DQ_A22  @S9S_MB_2U_LIB.S9S_MB_2U(SCH_1):M_G_CPU0_SA_DQ<22>
   38  M_G_CPU0_SA_DQ<21>  DQ_A21  @S9S_MB_2U_LIB.S9S_MB_2U(SCH_1):M_G_CPU0_SA_DQ<21>
   36  M_G_CPU0_SA_DQ<20>  DQ_A20  @S9S_MB_2U_LIB.S9S_MB_2U(SCH_1):M_G_CPU0_SA_DQ<20>
    9  M_G_CPU0_SA_DQ<1>  DQ_A1  @S9S_MB_2U_LIB.S9S_MB_2U(SCH_1):M_G_CPU0_SA_DQ<1>
  176  M_G_CPU0_SA_DQ<19>  DQ_A19  @S9S_MB_2U_LIB.S9S_MB_2U(SCH_1):M_G_CPU0_SA_DQ<19>
  174  M_G_CPU0_SA_DQ<18>  DQ_A18  @S9S_MB_2U_LIB.S9S_MB_2U(SCH_1):M_G_CPU0_SA_DQ<18>
   31  M_G_CPU0_SA_DQ<17>  DQ_A17  @S9S_MB_2U_LIB.S9S_MB_2U(SCH_1):M_G_CPU0_SA_DQ<17>
   29  M_G_CPU0_SA_DQ<16>  DQ_A16  @S9S_MB_2U_LIB.S9S_MB_2U(SCH_1):M_G_CPU0_SA_DQ<16>
  172  M_G_CPU0_SA_DQ<15>  DQ_A15  @S9S_MB_2U_LIB.S9S_MB_2U(SCH_1):M_G_CPU0_SA_DQ<15>
  170  M_G_CPU0_SA_DQ<14>  DQ_A14  @S9S_MB_2U_LIB.S9S_MB_2U(SCH_1):M_G_CPU0_SA_DQ<14>
   27  M_G_CPU0_SA_DQ<13>  DQ_A13  @S9S_MB_2U_LIB.S9S_MB_2U(SCH_1):M_G_CPU0_SA_DQ<13>
   25  M_G_CPU0_SA_DQ<12>  DQ_A12  @S9S_MB_2U_LIB.S9S_MB_2U(SCH_1):M_G_CPU0_SA_DQ<12>
  165  M_G_CPU0_SA_DQ<11>  DQ_A11  @S9S_MB_2U_LIB.S9S_MB_2U(SCH_1):M_G_CPU0_SA_DQ<11>
  163  M_G_CPU0_SA_DQ<10>  DQ_A10  @S9S_MB_2U_LIB.S9S_MB_2U(SCH_1):M_G_CPU0_SA_DQ<10>
    7  M_G_CPU0_SA_DQ<0>  DQ_A0  @S9S_MB_2U_LIB.S9S_MB_2U(SCH_1):M_G_CPU0_SA_DQ<0>
  209  M_G_CPU0_SA_CS_N<1>  CS1_N_A  @S9S_MB_2U_LIB.S9S_MB_2U(SCH_1):M_G_CPU0_SA_CS_N<1>
   64  M_G_CPU0_SA_CS_N<0>  CS0_N_A  @S9S_MB_2U_LIB.S9S_MB_2U(SCH_1):M_G_CPU0_SA_CS_N<0>
  205  M_G_CPU0_SA_CB<7>  CB_A7  @S9S_MB_2U_LIB.S9S_MB_2U(SCH_1):M_G_CPU0_SA_CB<7>
  203  M_G_CPU0_SA_CB<6>  CB_A6  @S9S_MB_2U_LIB.S9S_MB_2U(SCH_1):M_G_CPU0_SA_CB<6>
   60  M_G_CPU0_SA_CB<5>  CB_A5  @S9S_MB_2U_LIB.S9S_MB_2U(SCH_1):M_G_CPU0_SA_CB<5>
   58  M_G_CPU0_SA_CB<4>  CB_A4  @S9S_MB_2U_LIB.S9S_MB_2U(SCH_1):M_G_CPU0_SA_CB<4>
  198  M_G_CPU0_SA_CB<3>  CB_A3  @S9S_MB_2U_LIB.S9S_MB_2U(SCH_1):M_G_CPU0_SA_CB<3>
  196  M_G_CPU0_SA_CB<2>  CB_A2  @S9S_MB_2U_LIB.S9S_MB_2U(SCH_1):M_G_CPU0_SA_CB<2>
   53  M_G_CPU0_SA_CB<1>  CB_A1  @S9S_MB_2U_LIB.S9S_MB_2U(SCH_1):M_G_CPU0_SA_CB<1>
   51  M_G_CPU0_SA_CB<0>  CB_A0  @S9S_MB_2U_LIB.S9S_MB_2U(SCH_1):M_G_CPU0_SA_CB<0>
   72  M_G_CPU0_SA_CA<6>  CA6_A  @S9S_MB_2U_LIB.S9S_MB_2U(SCH_1):M_G_CPU0_SA_CA<6>
  215  M_G_CPU0_SA_CA<5>  CA5_A  @S9S_MB_2U_LIB.S9S_MB_2U(SCH_1):M_G_CPU0_SA_CA<5>
   70  M_G_CPU0_SA_CA<4>  CA4_A  @S9S_MB_2U_LIB.S9S_MB_2U(SCH_1):M_G_CPU0_SA_CA<4>
  213  M_G_CPU0_SA_CA<3>  CA3_A  @S9S_MB_2U_LIB.S9S_MB_2U(SCH_1):M_G_CPU0_SA_CA<3>
   68  M_G_CPU0_SA_CA<2>  CA2_A  @S9S_MB_2U_LIB.S9S_MB_2U(SCH_1):M_G_CPU0_SA_CA<2>
  211  M_G_CPU0_SA_CA<1>  CA1_A  @S9S_MB_2U_LIB.S9S_MB_2U(SCH_1):M_G_CPU0_SA_CA<1>
   66  M_G_CPU0_SA_CA<0>  CA0_A  @S9S_MB_2U_LIB.S9S_MB_2U(SCH_1):M_G_CPU0_SA_CA<0>
  217  M_G_CPU0_CLK_DP<0>   CK_P  @S9S_MB_2U_LIB.S9S_MB_2U(SCH_1):M_G_CPU0_CLK_DP<0>
  218  M_G_CPU0_CLK_DN<0>   CK_N  @S9S_MB_2U_LIB.S9S_MB_2U(SCH_1):M_G_CPU0_CLK_DN<0>
   62  M_G_CPU0_ALERT_N  ALERT_N  @S9S_MB_2U_LIB.S9S_MB_2U(SCH_1):M_G_CPU0_ALERT_N
    5  I3C_SPD_DDREFGH_CPU0_LVC1_SDA   HSDA  @S9S_MB_2U_LIB.S9S_MB_2U(SCH_1):I3C_SPD_DDREFGH_CPU0_LVC1_SDA
    4  I3C_SPD_DDREFGH_CPU0_LVC1_SCL   HSCL  @S9S_MB_2U_LIB.S9S_MB_2U(SCH_1):I3C_SPD_DDREFGH_CPU0_LVC1_SCL

SCONN288_ADR50001P003C01  I176  J14    [SCONN288_ADR50001P003C01-SCONNA]
  146  P12V_S3_AUX_CPU0_NVDIMM  VIN_BULK2  @S9S_MB_2U_LIB.S9S_MB_2U(SCH_1):P12V_S3_AUX_CPU0_NVDIMM
  145  P12V_S3_AUX_CPU0_NVDIMM  VIN_BULK1  @S9S_MB_2U_LIB.S9S_MB_2U(SCH_1):P12V_S3_AUX_CPU0_NVDIMM
    1  P12V_S3_AUX_CPU0_NVDIMM  VIN_BULK0  @S9S_MB_2U_LIB.S9S_MB_2U(SCH_1):P12V_S3_AUX_CPU0_NVDIMM
  288  GND            VSS126  @S9S_MB_2U_LIB.S9S_MB_2U(SCH_1):GND
  286  GND            VSS125  @S9S_MB_2U_LIB.S9S_MB_2U(SCH_1):GND
  284  GND            VSS124  @S9S_MB_2U_LIB.S9S_MB_2U(SCH_1):GND
  281  GND            VSS123  @S9S_MB_2U_LIB.S9S_MB_2U(SCH_1):GND
  279  GND            VSS122  @S9S_MB_2U_LIB.S9S_MB_2U(SCH_1):GND
  277  GND            VSS121  @S9S_MB_2U_LIB.S9S_MB_2U(SCH_1):GND
  275  GND            VSS120  @S9S_MB_2U_LIB.S9S_MB_2U(SCH_1):GND
  273  GND            VSS119  @S9S_MB_2U_LIB.S9S_MB_2U(SCH_1):GND
  270  GND            VSS118  @S9S_MB_2U_LIB.S9S_MB_2U(SCH_1):GND
  268  GND            VSS117  @S9S_MB_2U_LIB.S9S_MB_2U(SCH_1):GND
  266  GND            VSS116  @S9S_MB_2U_LIB.S9S_MB_2U(SCH_1):GND
  264  GND            VSS115  @S9S_MB_2U_LIB.S9S_MB_2U(SCH_1):GND
  262  GND            VSS114  @S9S_MB_2U_LIB.S9S_MB_2U(SCH_1):GND
  259  GND            VSS113  @S9S_MB_2U_LIB.S9S_MB_2U(SCH_1):GND
  257  GND            VSS112  @S9S_MB_2U_LIB.S9S_MB_2U(SCH_1):GND
  255  GND            VSS111  @S9S_MB_2U_LIB.S9S_MB_2U(SCH_1):GND
  253  GND            VSS110  @S9S_MB_2U_LIB.S9S_MB_2U(SCH_1):GND
  251  GND            VSS109  @S9S_MB_2U_LIB.S9S_MB_2U(SCH_1):GND
  248  GND            VSS108  @S9S_MB_2U_LIB.S9S_MB_2U(SCH_1):GND
  246  GND            VSS107  @S9S_MB_2U_LIB.S9S_MB_2U(SCH_1):GND
  244  GND            VSS106  @S9S_MB_2U_LIB.S9S_MB_2U(SCH_1):GND
  242  GND            VSS105  @S9S_MB_2U_LIB.S9S_MB_2U(SCH_1):GND
  240  GND            VSS104  @S9S_MB_2U_LIB.S9S_MB_2U(SCH_1):GND
  237  GND            VSS103  @S9S_MB_2U_LIB.S9S_MB_2U(SCH_1):GND
  235  GND            VSS102  @S9S_MB_2U_LIB.S9S_MB_2U(SCH_1):GND
  233  GND            VSS101  @S9S_MB_2U_LIB.S9S_MB_2U(SCH_1):GND
  230  GND            VSS100  @S9S_MB_2U_LIB.S9S_MB_2U(SCH_1):GND
  228  GND            VSS99  @S9S_MB_2U_LIB.S9S_MB_2U(SCH_1):GND
  226  GND            VSS98  @S9S_MB_2U_LIB.S9S_MB_2U(SCH_1):GND
  224  GND            VSS97  @S9S_MB_2U_LIB.S9S_MB_2U(SCH_1):GND
  222  GND            VSS96  @S9S_MB_2U_LIB.S9S_MB_2U(SCH_1):GND
  219  GND            VSS95  @S9S_MB_2U_LIB.S9S_MB_2U(SCH_1):GND
  216  GND            VSS94  @S9S_MB_2U_LIB.S9S_MB_2U(SCH_1):GND
  214  GND            VSS93  @S9S_MB_2U_LIB.S9S_MB_2U(SCH_1):GND
  212  GND            VSS92  @S9S_MB_2U_LIB.S9S_MB_2U(SCH_1):GND
  210  GND            VSS91  @S9S_MB_2U_LIB.S9S_MB_2U(SCH_1):GND
  208  GND            VSS90  @S9S_MB_2U_LIB.S9S_MB_2U(SCH_1):GND
  206  GND            VSS89  @S9S_MB_2U_LIB.S9S_MB_2U(SCH_1):GND
  204  GND            VSS88  @S9S_MB_2U_LIB.S9S_MB_2U(SCH_1):GND
  202  GND            VSS87  @S9S_MB_2U_LIB.S9S_MB_2U(SCH_1):GND
  199  GND            VSS86  @S9S_MB_2U_LIB.S9S_MB_2U(SCH_1):GND
  197  GND            VSS85  @S9S_MB_2U_LIB.S9S_MB_2U(SCH_1):GND
  195  GND            VSS84  @S9S_MB_2U_LIB.S9S_MB_2U(SCH_1):GND
  193  GND            VSS83  @S9S_MB_2U_LIB.S9S_MB_2U(SCH_1):GND
  191  GND            VSS82  @S9S_MB_2U_LIB.S9S_MB_2U(SCH_1):GND
  188  GND            VSS81  @S9S_MB_2U_LIB.S9S_MB_2U(SCH_1):GND
  186  GND            VSS80  @S9S_MB_2U_LIB.S9S_MB_2U(SCH_1):GND
  184  GND            VSS79  @S9S_MB_2U_LIB.S9S_MB_2U(SCH_1):GND
  182  GND            VSS78  @S9S_MB_2U_LIB.S9S_MB_2U(SCH_1):GND
  180  GND            VSS77  @S9S_MB_2U_LIB.S9S_MB_2U(SCH_1):GND
  177  GND            VSS76  @S9S_MB_2U_LIB.S9S_MB_2U(SCH_1):GND
  175  GND            VSS75  @S9S_MB_2U_LIB.S9S_MB_2U(SCH_1):GND
  173  GND            VSS74  @S9S_MB_2U_LIB.S9S_MB_2U(SCH_1):GND
  171  GND            VSS73  @S9S_MB_2U_LIB.S9S_MB_2U(SCH_1):GND
  169  GND            VSS72  @S9S_MB_2U_LIB.S9S_MB_2U(SCH_1):GND
  166  GND            VSS71  @S9S_MB_2U_LIB.S9S_MB_2U(SCH_1):GND
  164  GND            VSS70  @S9S_MB_2U_LIB.S9S_MB_2U(SCH_1):GND
  162  GND            VSS69  @S9S_MB_2U_LIB.S9S_MB_2U(SCH_1):GND
  160  GND            VSS68  @S9S_MB_2U_LIB.S9S_MB_2U(SCH_1):GND
  158  GND            VSS67  @S9S_MB_2U_LIB.S9S_MB_2U(SCH_1):GND
  155  GND            VSS66  @S9S_MB_2U_LIB.S9S_MB_2U(SCH_1):GND
  153  GND            VSS65  @S9S_MB_2U_LIB.S9S_MB_2U(SCH_1):GND
  151  GND            VSS64  @S9S_MB_2U_LIB.S9S_MB_2U(SCH_1):GND
  143  GND            VSS63  @S9S_MB_2U_LIB.S9S_MB_2U(SCH_1):GND
  141  GND            VSS62  @S9S_MB_2U_LIB.S9S_MB_2U(SCH_1):GND
  139  GND            VSS61  @S9S_MB_2U_LIB.S9S_MB_2U(SCH_1):GND
  136  GND            VSS60  @S9S_MB_2U_LIB.S9S_MB_2U(SCH_1):GND
  134  GND            VSS59  @S9S_MB_2U_LIB.S9S_MB_2U(SCH_1):GND
  132  GND            VSS58  @S9S_MB_2U_LIB.S9S_MB_2U(SCH_1):GND
  130  GND            VSS57  @S9S_MB_2U_LIB.S9S_MB_2U(SCH_1):GND
  128  GND            VSS56  @S9S_MB_2U_LIB.S9S_MB_2U(SCH_1):GND
  125  GND            VSS55  @S9S_MB_2U_LIB.S9S_MB_2U(SCH_1):GND
  123  GND            VSS54  @S9S_MB_2U_LIB.S9S_MB_2U(SCH_1):GND
  121  GND            VSS53  @S9S_MB_2U_LIB.S9S_MB_2U(SCH_1):GND
  119  GND            VSS52  @S9S_MB_2U_LIB.S9S_MB_2U(SCH_1):GND
  117  GND            VSS51  @S9S_MB_2U_LIB.S9S_MB_2U(SCH_1):GND
  114  GND            VSS50  @S9S_MB_2U_LIB.S9S_MB_2U(SCH_1):GND
  112  GND            VSS49  @S9S_MB_2U_LIB.S9S_MB_2U(SCH_1):GND
  110  GND            VSS48  @S9S_MB_2U_LIB.S9S_MB_2U(SCH_1):GND
  108  GND            VSS47  @S9S_MB_2U_LIB.S9S_MB_2U(SCH_1):GND
  106  GND            VSS46  @S9S_MB_2U_LIB.S9S_MB_2U(SCH_1):GND
  103  GND            VSS45  @S9S_MB_2U_LIB.S9S_MB_2U(SCH_1):GND
  101  GND            VSS44  @S9S_MB_2U_LIB.S9S_MB_2U(SCH_1):GND
   99  GND            VSS43  @S9S_MB_2U_LIB.S9S_MB_2U(SCH_1):GND
   97  GND            VSS42  @S9S_MB_2U_LIB.S9S_MB_2U(SCH_1):GND
   95  GND            VSS41  @S9S_MB_2U_LIB.S9S_MB_2U(SCH_1):GND
   92  GND            VSS40  @S9S_MB_2U_LIB.S9S_MB_2U(SCH_1):GND
   90  GND            VSS39  @S9S_MB_2U_LIB.S9S_MB_2U(SCH_1):GND
   88  GND            VSS38  @S9S_MB_2U_LIB.S9S_MB_2U(SCH_1):GND
   85  GND            VSS37  @S9S_MB_2U_LIB.S9S_MB_2U(SCH_1):GND
   83  GND            VSS36  @S9S_MB_2U_LIB.S9S_MB_2U(SCH_1):GND
   81  GND            VSS35  @S9S_MB_2U_LIB.S9S_MB_2U(SCH_1):GND
   79  GND            VSS34  @S9S_MB_2U_LIB.S9S_MB_2U(SCH_1):GND
   77  GND            VSS33  @S9S_MB_2U_LIB.S9S_MB_2U(SCH_1):GND
   75  GND            VSS32  @S9S_MB_2U_LIB.S9S_MB_2U(SCH_1):GND
   73  GND            VSS31  @S9S_MB_2U_LIB.S9S_MB_2U(SCH_1):GND
   71  GND            VSS30  @S9S_MB_2U_LIB.S9S_MB_2U(SCH_1):GND
   69  GND            VSS29  @S9S_MB_2U_LIB.S9S_MB_2U(SCH_1):GND
   67  GND            VSS28  @S9S_MB_2U_LIB.S9S_MB_2U(SCH_1):GND
   65  GND            VSS27  @S9S_MB_2U_LIB.S9S_MB_2U(SCH_1):GND
   63  GND            VSS26  @S9S_MB_2U_LIB.S9S_MB_2U(SCH_1):GND
   61  GND            VSS25  @S9S_MB_2U_LIB.S9S_MB_2U(SCH_1):GND
   59  GND            VSS24  @S9S_MB_2U_LIB.S9S_MB_2U(SCH_1):GND
   57  GND            VSS23  @S9S_MB_2U_LIB.S9S_MB_2U(SCH_1):GND
   54  GND            VSS22  @S9S_MB_2U_LIB.S9S_MB_2U(SCH_1):GND
   52  GND            VSS21  @S9S_MB_2U_LIB.S9S_MB_2U(SCH_1):GND
   50  GND            VSS20  @S9S_MB_2U_LIB.S9S_MB_2U(SCH_1):GND
   48  GND            VSS19  @S9S_MB_2U_LIB.S9S_MB_2U(SCH_1):GND
   46  GND            VSS18  @S9S_MB_2U_LIB.S9S_MB_2U(SCH_1):GND
   43  GND            VSS17  @S9S_MB_2U_LIB.S9S_MB_2U(SCH_1):GND
   41  GND            VSS16  @S9S_MB_2U_LIB.S9S_MB_2U(SCH_1):GND
   39  GND            VSS15  @S9S_MB_2U_LIB.S9S_MB_2U(SCH_1):GND
   37  GND            VSS14  @S9S_MB_2U_LIB.S9S_MB_2U(SCH_1):GND
   35  GND            VSS13  @S9S_MB_2U_LIB.S9S_MB_2U(SCH_1):GND
   32  GND            VSS12  @S9S_MB_2U_LIB.S9S_MB_2U(SCH_1):GND
   30  GND            VSS11  @S9S_MB_2U_LIB.S9S_MB_2U(SCH_1):GND
   28  GND            VSS10  @S9S_MB_2U_LIB.S9S_MB_2U(SCH_1):GND
   26  GND             VSS9  @S9S_MB_2U_LIB.S9S_MB_2U(SCH_1):GND
   24  GND             VSS8  @S9S_MB_2U_LIB.S9S_MB_2U(SCH_1):GND
   21  GND             VSS7  @S9S_MB_2U_LIB.S9S_MB_2U(SCH_1):GND
   19  GND             VSS6  @S9S_MB_2U_LIB.S9S_MB_2U(SCH_1):GND
   17  GND             VSS5  @S9S_MB_2U_LIB.S9S_MB_2U(SCH_1):GND
   15  GND             VSS4  @S9S_MB_2U_LIB.S9S_MB_2U(SCH_1):GND
   13  GND             VSS3  @S9S_MB_2U_LIB.S9S_MB_2U(SCH_1):GND
   10  GND             VSS2  @S9S_MB_2U_LIB.S9S_MB_2U(SCH_1):GND
    8  GND             VSS1  @S9S_MB_2U_LIB.S9S_MB_2U(SCH_1):GND
    6  GND             VSS0  @S9S_MB_2U_LIB.S9S_MB_2U(SCH_1):GND
   G3  GND               G3  @S9S_MB_2U_LIB.S9S_MB_2U(SCH_1):GND
   G2  GND               G2  @S9S_MB_2U_LIB.S9S_MB_2U(SCH_1):GND
   G1  GND               G1  @S9S_MB_2U_LIB.S9S_MB_2U(SCH_1):GND

SCONN288_ADR50001P003C01  I124  J14    [SCONN288_ADR50001P003C01-SCONNA]
   93  M_G_CPU0_SB_DQS_DP<9>  DQS9_B_P  @S9S_MB_2U_LIB.S9S_MB_2U(SCH_1):M_G_CPU0_SB_DQS_DP<9>
  283  M_G_CPU0_SB_DQS_DP<8>  DQS8_B_P  @S9S_MB_2U_LIB.S9S_MB_2U(SCH_1):M_G_CPU0_SB_DQS_DP<8>
  272  M_G_CPU0_SB_DQS_DP<7>  DQS7_B_P  @S9S_MB_2U_LIB.S9S_MB_2U(SCH_1):M_G_CPU0_SB_DQS_DP<7>
  261  M_G_CPU0_SB_DQS_DP<6>  DQS6_B_P  @S9S_MB_2U_LIB.S9S_MB_2U(SCH_1):M_G_CPU0_SB_DQS_DP<6>
  250  M_G_CPU0_SB_DQS_DP<5>  DQS5_B_P  @S9S_MB_2U_LIB.S9S_MB_2U(SCH_1):M_G_CPU0_SB_DQS_DP<5>
  239  M_G_CPU0_SB_DQS_DP<4>  DQS4_B_P  @S9S_MB_2U_LIB.S9S_MB_2U(SCH_1):M_G_CPU0_SB_DQS_DP<4>
  137  M_G_CPU0_SB_DQS_DP<3>  DQS3_B_P  @S9S_MB_2U_LIB.S9S_MB_2U(SCH_1):M_G_CPU0_SB_DQS_DP<3>
  126  M_G_CPU0_SB_DQS_DP<2>  DQS2_B_P  @S9S_MB_2U_LIB.S9S_MB_2U(SCH_1):M_G_CPU0_SB_DQS_DP<2>
  115  M_G_CPU0_SB_DQS_DP<1>  DQS1_B_P  @S9S_MB_2U_LIB.S9S_MB_2U(SCH_1):M_G_CPU0_SB_DQS_DP<1>
  104  M_G_CPU0_SB_DQS_DP<0>  DQS0_B_P  @S9S_MB_2U_LIB.S9S_MB_2U(SCH_1):M_G_CPU0_SB_DQS_DP<0>
   94  M_G_CPU0_SB_DQS_DN<9>  DQS9_B_N  @S9S_MB_2U_LIB.S9S_MB_2U(SCH_1):M_G_CPU0_SB_DQS_DN<9>
  282  M_G_CPU0_SB_DQS_DN<8>  DQS8_B_N  @S9S_MB_2U_LIB.S9S_MB_2U(SCH_1):M_G_CPU0_SB_DQS_DN<8>
  271  M_G_CPU0_SB_DQS_DN<7>  DQS7_B_N  @S9S_MB_2U_LIB.S9S_MB_2U(SCH_1):M_G_CPU0_SB_DQS_DN<7>
  260  M_G_CPU0_SB_DQS_DN<6>  DQS6_B_N  @S9S_MB_2U_LIB.S9S_MB_2U(SCH_1):M_G_CPU0_SB_DQS_DN<6>
  249  M_G_CPU0_SB_DQS_DN<5>  DQS5_B_N  @S9S_MB_2U_LIB.S9S_MB_2U(SCH_1):M_G_CPU0_SB_DQS_DN<5>
  238  M_G_CPU0_SB_DQS_DN<4>  DQS4_B_N  @S9S_MB_2U_LIB.S9S_MB_2U(SCH_1):M_G_CPU0_SB_DQS_DN<4>
  138  M_G_CPU0_SB_DQS_DN<3>  DQS3_B_N  @S9S_MB_2U_LIB.S9S_MB_2U(SCH_1):M_G_CPU0_SB_DQS_DN<3>
  127  M_G_CPU0_SB_DQS_DN<2>  DQS2_B_N  @S9S_MB_2U_LIB.S9S_MB_2U(SCH_1):M_G_CPU0_SB_DQS_DN<2>
  116  M_G_CPU0_SB_DQS_DN<1>  DQS1_B_N  @S9S_MB_2U_LIB.S9S_MB_2U(SCH_1):M_G_CPU0_SB_DQS_DN<1>
  105  M_G_CPU0_SB_DQS_DN<0>  DQS0_B_N  @S9S_MB_2U_LIB.S9S_MB_2U(SCH_1):M_G_CPU0_SB_DQS_DN<0>
  201  M_G_CPU0_SA_DQS_DP<9>  DQS9_A_P  @S9S_MB_2U_LIB.S9S_MB_2U(SCH_1):M_G_CPU0_SA_DQS_DP<9>
  190  M_G_CPU0_SA_DQS_DP<8>  DQS8_A_P  @S9S_MB_2U_LIB.S9S_MB_2U(SCH_1):M_G_CPU0_SA_DQS_DP<8>
  179  M_G_CPU0_SA_DQS_DP<7>  DQS7_A_P  @S9S_MB_2U_LIB.S9S_MB_2U(SCH_1):M_G_CPU0_SA_DQS_DP<7>
  168  M_G_CPU0_SA_DQS_DP<6>  DQS6_A_P  @S9S_MB_2U_LIB.S9S_MB_2U(SCH_1):M_G_CPU0_SA_DQS_DP<6>
  157  M_G_CPU0_SA_DQS_DP<5>  DQS5_A_P  @S9S_MB_2U_LIB.S9S_MB_2U(SCH_1):M_G_CPU0_SA_DQS_DP<5>
   55  M_G_CPU0_SA_DQS_DP<4>  DQS4_A_P  @S9S_MB_2U_LIB.S9S_MB_2U(SCH_1):M_G_CPU0_SA_DQS_DP<4>
   44  M_G_CPU0_SA_DQS_DP<3>  DQS3_A_P  @S9S_MB_2U_LIB.S9S_MB_2U(SCH_1):M_G_CPU0_SA_DQS_DP<3>
   33  M_G_CPU0_SA_DQS_DP<2>  DQS2_A_P  @S9S_MB_2U_LIB.S9S_MB_2U(SCH_1):M_G_CPU0_SA_DQS_DP<2>
   22  M_G_CPU0_SA_DQS_DP<1>  DQS1_A_P  @S9S_MB_2U_LIB.S9S_MB_2U(SCH_1):M_G_CPU0_SA_DQS_DP<1>
   11  M_G_CPU0_SA_DQS_DP<0>  DQS0_A_P  @S9S_MB_2U_LIB.S9S_MB_2U(SCH_1):M_G_CPU0_SA_DQS_DP<0>
  200  M_G_CPU0_SA_DQS_DN<9>  DQS9_A_N  @S9S_MB_2U_LIB.S9S_MB_2U(SCH_1):M_G_CPU0_SA_DQS_DN<9>
  189  M_G_CPU0_SA_DQS_DN<8>  DQS8_A_N  @S9S_MB_2U_LIB.S9S_MB_2U(SCH_1):M_G_CPU0_SA_DQS_DN<8>
  178  M_G_CPU0_SA_DQS_DN<7>  DQS7_A_N  @S9S_MB_2U_LIB.S9S_MB_2U(SCH_1):M_G_CPU0_SA_DQS_DN<7>
  167  M_G_CPU0_SA_DQS_DN<6>  DQS6_A_N  @S9S_MB_2U_LIB.S9S_MB_2U(SCH_1):M_G_CPU0_SA_DQS_DN<6>
  156  M_G_CPU0_SA_DQS_DN<5>  DQS5_A_N  @S9S_MB_2U_LIB.S9S_MB_2U(SCH_1):M_G_CPU0_SA_DQS_DN<5>
   56  M_G_CPU0_SA_DQS_DN<4>  DQS4_A_N  @S9S_MB_2U_LIB.S9S_MB_2U(SCH_1):M_G_CPU0_SA_DQS_DN<4>
   45  M_G_CPU0_SA_DQS_DN<3>  DQS3_A_N  @S9S_MB_2U_LIB.S9S_MB_2U(SCH_1):M_G_CPU0_SA_DQS_DN<3>
   34  M_G_CPU0_SA_DQS_DN<2>  DQS2_A_N  @S9S_MB_2U_LIB.S9S_MB_2U(SCH_1):M_G_CPU0_SA_DQS_DN<2>
   23  M_G_CPU0_SA_DQS_DN<1>  DQS1_A_N  @S9S_MB_2U_LIB.S9S_MB_2U(SCH_1):M_G_CPU0_SA_DQS_DN<1>
   12  M_G_CPU0_SA_DQS_DN<0>  DQS0_A_N  @S9S_MB_2U_LIB.S9S_MB_2U(SCH_1):M_G_CPU0_SA_DQS_DN<0>

SCONN288_ADR50001P003C01  I47  J14    [SCONN288_ADR50001P003C01-SCONNA]
  232  NC              RFU6  NC
  231  NC              RFU5  NC
  220  NC              RFU4  NC
  150  NC              RFU3  NC
  149  NC              RFU2  NC
  144  NC              RFU1  NC
    2  NC              RFU0  NC
  207  RST_M_GH_CPU0_FPGA_N  RESET_N  @S9S_MB_2U_LIB.S9S_MB_2U(SCH_1):RST_M_GH_CPU0_FPGA_N
  147  PWRGD_CHG_CPU0_DIMM2  PWR_GOOD||FAIL_N  @S9S_MB_2U_LIB.S9S_MB_2U(SCH_1):PWRGD_CHG_CPU0_DIMM2
  148  PD_CHG_CPU0_DIMM2_SAA    HAS  @S9S_MB_2U_LIB.S9S_MB_2U(SCH_1):PD_CHG_CPU0_DIMM2_SAA
    3  P3V3_AUX       VIN_MGMT  @S9S_MB_2U_LIB.S9S_MB_2U(SCH_1):P3V3_AUX
   87  M_G_CPU0_SB_RSP<1>  LBS||RSP_N_B  @S9S_MB_2U_LIB.S9S_MB_2U(SCH_1):M_G_CPU0_SB_RSP<1>
  227  M_G_CPU0_SB_PAR  PAR_B  @S9S_MB_2U_LIB.S9S_MB_2U(SCH_1):M_G_CPU0_SB_PAR
  113  M_G_CPU0_SB_DQ<9>  DQ_B9  @S9S_MB_2U_LIB.S9S_MB_2U(SCH_1):M_G_CPU0_SB_DQ<9>
  111  M_G_CPU0_SB_DQ<8>  DQ_B8  @S9S_MB_2U_LIB.S9S_MB_2U(SCH_1):M_G_CPU0_SB_DQ<8>
  254  M_G_CPU0_SB_DQ<7>  DQ_B7  @S9S_MB_2U_LIB.S9S_MB_2U(SCH_1):M_G_CPU0_SB_DQ<7>
  252  M_G_CPU0_SB_DQ<6>  DQ_B6  @S9S_MB_2U_LIB.S9S_MB_2U(SCH_1):M_G_CPU0_SB_DQ<6>
  109  M_G_CPU0_SB_DQ<5>  DQ_B5  @S9S_MB_2U_LIB.S9S_MB_2U(SCH_1):M_G_CPU0_SB_DQ<5>
  107  M_G_CPU0_SB_DQ<4>  DQ_B4  @S9S_MB_2U_LIB.S9S_MB_2U(SCH_1):M_G_CPU0_SB_DQ<4>
  247  M_G_CPU0_SB_DQ<3>  DQ_B3  @S9S_MB_2U_LIB.S9S_MB_2U(SCH_1):M_G_CPU0_SB_DQ<3>
  287  M_G_CPU0_SB_DQ<31>  DQ_B31  @S9S_MB_2U_LIB.S9S_MB_2U(SCH_1):M_G_CPU0_SB_DQ<31>
  285  M_G_CPU0_SB_DQ<30>  DQ_B30  @S9S_MB_2U_LIB.S9S_MB_2U(SCH_1):M_G_CPU0_SB_DQ<30>
  245  M_G_CPU0_SB_DQ<2>  DQ_B2  @S9S_MB_2U_LIB.S9S_MB_2U(SCH_1):M_G_CPU0_SB_DQ<2>
  142  M_G_CPU0_SB_DQ<29>  DQ_B29  @S9S_MB_2U_LIB.S9S_MB_2U(SCH_1):M_G_CPU0_SB_DQ<29>
  140  M_G_CPU0_SB_DQ<28>  DQ_B28  @S9S_MB_2U_LIB.S9S_MB_2U(SCH_1):M_G_CPU0_SB_DQ<28>
  280  M_G_CPU0_SB_DQ<27>  DQ_B27  @S9S_MB_2U_LIB.S9S_MB_2U(SCH_1):M_G_CPU0_SB_DQ<27>
  278  M_G_CPU0_SB_DQ<26>  DQ_B26  @S9S_MB_2U_LIB.S9S_MB_2U(SCH_1):M_G_CPU0_SB_DQ<26>
  135  M_G_CPU0_SB_DQ<25>  DQ_B25  @S9S_MB_2U_LIB.S9S_MB_2U(SCH_1):M_G_CPU0_SB_DQ<25>
  133  M_G_CPU0_SB_DQ<24>  DQ_B24  @S9S_MB_2U_LIB.S9S_MB_2U(SCH_1):M_G_CPU0_SB_DQ<24>
  276  M_G_CPU0_SB_DQ<23>  DQ_B23  @S9S_MB_2U_LIB.S9S_MB_2U(SCH_1):M_G_CPU0_SB_DQ<23>
  274  M_G_CPU0_SB_DQ<22>  DQ_B22  @S9S_MB_2U_LIB.S9S_MB_2U(SCH_1):M_G_CPU0_SB_DQ<22>
  131  M_G_CPU0_SB_DQ<21>  DQ_B21  @S9S_MB_2U_LIB.S9S_MB_2U(SCH_1):M_G_CPU0_SB_DQ<21>
  129  M_G_CPU0_SB_DQ<20>  DQ_B20  @S9S_MB_2U_LIB.S9S_MB_2U(SCH_1):M_G_CPU0_SB_DQ<20>
  102  M_G_CPU0_SB_DQ<1>  DQ_B1  @S9S_MB_2U_LIB.S9S_MB_2U(SCH_1):M_G_CPU0_SB_DQ<1>
  269  M_G_CPU0_SB_DQ<19>  DQ_B19  @S9S_MB_2U_LIB.S9S_MB_2U(SCH_1):M_G_CPU0_SB_DQ<19>
  267  M_G_CPU0_SB_DQ<18>  DQ_B18  @S9S_MB_2U_LIB.S9S_MB_2U(SCH_1):M_G_CPU0_SB_DQ<18>
  124  M_G_CPU0_SB_DQ<17>  DQ_B17  @S9S_MB_2U_LIB.S9S_MB_2U(SCH_1):M_G_CPU0_SB_DQ<17>
  122  M_G_CPU0_SB_DQ<16>  DQ_B16  @S9S_MB_2U_LIB.S9S_MB_2U(SCH_1):M_G_CPU0_SB_DQ<16>
  265  M_G_CPU0_SB_DQ<15>  DQ_B15  @S9S_MB_2U_LIB.S9S_MB_2U(SCH_1):M_G_CPU0_SB_DQ<15>
  263  M_G_CPU0_SB_DQ<14>  DQ_B14  @S9S_MB_2U_LIB.S9S_MB_2U(SCH_1):M_G_CPU0_SB_DQ<14>
  120  M_G_CPU0_SB_DQ<13>  DQ_B13  @S9S_MB_2U_LIB.S9S_MB_2U(SCH_1):M_G_CPU0_SB_DQ<13>
  118  M_G_CPU0_SB_DQ<12>  DQ_B12  @S9S_MB_2U_LIB.S9S_MB_2U(SCH_1):M_G_CPU0_SB_DQ<12>
  258  M_G_CPU0_SB_DQ<11>  DQ_B11  @S9S_MB_2U_LIB.S9S_MB_2U(SCH_1):M_G_CPU0_SB_DQ<11>
  256  M_G_CPU0_SB_DQ<10>  DQ_B10  @S9S_MB_2U_LIB.S9S_MB_2U(SCH_1):M_G_CPU0_SB_DQ<10>
  100  M_G_CPU0_SB_DQ<0>  DQ_B0  @S9S_MB_2U_LIB.S9S_MB_2U(SCH_1):M_G_CPU0_SB_DQ<0>
  229  M_G_CPU0_SB_CS_N<3>  CS1_N_B  @S9S_MB_2U_LIB.S9S_MB_2U(SCH_1):M_G_CPU0_SB_CS_N<3>
   84  M_G_CPU0_SB_CS_N<2>  CS0_N_B  @S9S_MB_2U_LIB.S9S_MB_2U(SCH_1):M_G_CPU0_SB_CS_N<2>
  236  M_G_CPU0_SB_CB<7>  CB_B7  @S9S_MB_2U_LIB.S9S_MB_2U(SCH_1):M_G_CPU0_SB_CB<7>
  234  M_G_CPU0_SB_CB<6>  CB_B6  @S9S_MB_2U_LIB.S9S_MB_2U(SCH_1):M_G_CPU0_SB_CB<6>
   91  M_G_CPU0_SB_CB<5>  CB_B5  @S9S_MB_2U_LIB.S9S_MB_2U(SCH_1):M_G_CPU0_SB_CB<5>
   89  M_G_CPU0_SB_CB<4>  CB_B4  @S9S_MB_2U_LIB.S9S_MB_2U(SCH_1):M_G_CPU0_SB_CB<4>
  243  M_G_CPU0_SB_CB<3>  CB_B3  @S9S_MB_2U_LIB.S9S_MB_2U(SCH_1):M_G_CPU0_SB_CB<3>
  241  M_G_CPU0_SB_CB<2>  CB_B2  @S9S_MB_2U_LIB.S9S_MB_2U(SCH_1):M_G_CPU0_SB_CB<2>
   98  M_G_CPU0_SB_CB<1>  CB_B1  @S9S_MB_2U_LIB.S9S_MB_2U(SCH_1):M_G_CPU0_SB_CB<1>
   96  M_G_CPU0_SB_CB<0>  CB_B0  @S9S_MB_2U_LIB.S9S_MB_2U(SCH_1):M_G_CPU0_SB_CB<0>
   82  M_G_CPU0_SB_CA<6>  CA6_B  @S9S_MB_2U_LIB.S9S_MB_2U(SCH_1):M_G_CPU0_SB_CA<6>
  225  M_G_CPU0_SB_CA<5>  CA5_B  @S9S_MB_2U_LIB.S9S_MB_2U(SCH_1):M_G_CPU0_SB_CA<5>
   80  M_G_CPU0_SB_CA<4>  CA4_B  @S9S_MB_2U_LIB.S9S_MB_2U(SCH_1):M_G_CPU0_SB_CA<4>
  223  M_G_CPU0_SB_CA<3>  CA3_B  @S9S_MB_2U_LIB.S9S_MB_2U(SCH_1):M_G_CPU0_SB_CA<3>
   78  M_G_CPU0_SB_CA<2>  CA2_B  @S9S_MB_2U_LIB.S9S_MB_2U(SCH_1):M_G_CPU0_SB_CA<2>
  221  M_G_CPU0_SB_CA<1>  CA1_B  @S9S_MB_2U_LIB.S9S_MB_2U(SCH_1):M_G_CPU0_SB_CA<1>
   76  M_G_CPU0_SB_CA<0>  CA0_B  @S9S_MB_2U_LIB.S9S_MB_2U(SCH_1):M_G_CPU0_SB_CA<0>
   86  M_G_CPU0_SA_RSP<1>  LBD||RSP_N_A  @S9S_MB_2U_LIB.S9S_MB_2U(SCH_1):M_G_CPU0_SA_RSP<1>
   74  M_G_CPU0_SA_PAR  PAR_A  @S9S_MB_2U_LIB.S9S_MB_2U(SCH_1):M_G_CPU0_SA_PAR
   20  M_G_CPU0_SA_DQ<9>  DQ_A9  @S9S_MB_2U_LIB.S9S_MB_2U(SCH_1):M_G_CPU0_SA_DQ<9>
   18  M_G_CPU0_SA_DQ<8>  DQ_A8  @S9S_MB_2U_LIB.S9S_MB_2U(SCH_1):M_G_CPU0_SA_DQ<8>
  161  M_G_CPU0_SA_DQ<7>  DQ_A7  @S9S_MB_2U_LIB.S9S_MB_2U(SCH_1):M_G_CPU0_SA_DQ<7>
  159  M_G_CPU0_SA_DQ<6>  DQ_A6  @S9S_MB_2U_LIB.S9S_MB_2U(SCH_1):M_G_CPU0_SA_DQ<6>
   16  M_G_CPU0_SA_DQ<5>  DQ_A5  @S9S_MB_2U_LIB.S9S_MB_2U(SCH_1):M_G_CPU0_SA_DQ<5>
   14  M_G_CPU0_SA_DQ<4>  DQ_A4  @S9S_MB_2U_LIB.S9S_MB_2U(SCH_1):M_G_CPU0_SA_DQ<4>
  154  M_G_CPU0_SA_DQ<3>  DQ_A3  @S9S_MB_2U_LIB.S9S_MB_2U(SCH_1):M_G_CPU0_SA_DQ<3>
  194  M_G_CPU0_SA_DQ<31>  DQ_A31  @S9S_MB_2U_LIB.S9S_MB_2U(SCH_1):M_G_CPU0_SA_DQ<31>
  192  M_G_CPU0_SA_DQ<30>  DQ_A30  @S9S_MB_2U_LIB.S9S_MB_2U(SCH_1):M_G_CPU0_SA_DQ<30>
  152  M_G_CPU0_SA_DQ<2>  DQ_A2  @S9S_MB_2U_LIB.S9S_MB_2U(SCH_1):M_G_CPU0_SA_DQ<2>
   49  M_G_CPU0_SA_DQ<29>  DQ_A29  @S9S_MB_2U_LIB.S9S_MB_2U(SCH_1):M_G_CPU0_SA_DQ<29>
   47  M_G_CPU0_SA_DQ<28>  DQ_A28  @S9S_MB_2U_LIB.S9S_MB_2U(SCH_1):M_G_CPU0_SA_DQ<28>
  187  M_G_CPU0_SA_DQ<27>  DQ_A27  @S9S_MB_2U_LIB.S9S_MB_2U(SCH_1):M_G_CPU0_SA_DQ<27>
  185  M_G_CPU0_SA_DQ<26>  DQ_A26  @S9S_MB_2U_LIB.S9S_MB_2U(SCH_1):M_G_CPU0_SA_DQ<26>
   42  M_G_CPU0_SA_DQ<25>  DQ_A25  @S9S_MB_2U_LIB.S9S_MB_2U(SCH_1):M_G_CPU0_SA_DQ<25>
   40  M_G_CPU0_SA_DQ<24>  DQ_A24  @S9S_MB_2U_LIB.S9S_MB_2U(SCH_1):M_G_CPU0_SA_DQ<24>
  183  M_G_CPU0_SA_DQ<23>  DQ_A23  @S9S_MB_2U_LIB.S9S_MB_2U(SCH_1):M_G_CPU0_SA_DQ<23>
  181  M_G_CPU0_SA_DQ<22>  DQ_A22  @S9S_MB_2U_LIB.S9S_MB_2U(SCH_1):M_G_CPU0_SA_DQ<22>
   38  M_G_CPU0_SA_DQ<21>  DQ_A21  @S9S_MB_2U_LIB.S9S_MB_2U(SCH_1):M_G_CPU0_SA_DQ<21>
   36  M_G_CPU0_SA_DQ<20>  DQ_A20  @S9S_MB_2U_LIB.S9S_MB_2U(SCH_1):M_G_CPU0_SA_DQ<20>
    9  M_G_CPU0_SA_DQ<1>  DQ_A1  @S9S_MB_2U_LIB.S9S_MB_2U(SCH_1):M_G_CPU0_SA_DQ<1>
  176  M_G_CPU0_SA_DQ<19>  DQ_A19  @S9S_MB_2U_LIB.S9S_MB_2U(SCH_1):M_G_CPU0_SA_DQ<19>
  174  M_G_CPU0_SA_DQ<18>  DQ_A18  @S9S_MB_2U_LIB.S9S_MB_2U(SCH_1):M_G_CPU0_SA_DQ<18>
   31  M_G_CPU0_SA_DQ<17>  DQ_A17  @S9S_MB_2U_LIB.S9S_MB_2U(SCH_1):M_G_CPU0_SA_DQ<17>
   29  M_G_CPU0_SA_DQ<16>  DQ_A16  @S9S_MB_2U_LIB.S9S_MB_2U(SCH_1):M_G_CPU0_SA_DQ<16>
  172  M_G_CPU0_SA_DQ<15>  DQ_A15  @S9S_MB_2U_LIB.S9S_MB_2U(SCH_1):M_G_CPU0_SA_DQ<15>
  170  M_G_CPU0_SA_DQ<14>  DQ_A14  @S9S_MB_2U_LIB.S9S_MB_2U(SCH_1):M_G_CPU0_SA_DQ<14>
   27  M_G_CPU0_SA_DQ<13>  DQ_A13  @S9S_MB_2U_LIB.S9S_MB_2U(SCH_1):M_G_CPU0_SA_DQ<13>
   25  M_G_CPU0_SA_DQ<12>  DQ_A12  @S9S_MB_2U_LIB.S9S_MB_2U(SCH_1):M_G_CPU0_SA_DQ<12>
  165  M_G_CPU0_SA_DQ<11>  DQ_A11  @S9S_MB_2U_LIB.S9S_MB_2U(SCH_1):M_G_CPU0_SA_DQ<11>
  163  M_G_CPU0_SA_DQ<10>  DQ_A10  @S9S_MB_2U_LIB.S9S_MB_2U(SCH_1):M_G_CPU0_SA_DQ<10>
    7  M_G_CPU0_SA_DQ<0>  DQ_A0  @S9S_MB_2U_LIB.S9S_MB_2U(SCH_1):M_G_CPU0_SA_DQ<0>
  209  M_G_CPU0_SA_CS_N<3>  CS1_N_A  @S9S_MB_2U_LIB.S9S_MB_2U(SCH_1):M_G_CPU0_SA_CS_N<3>
   64  M_G_CPU0_SA_CS_N<2>  CS0_N_A  @S9S_MB_2U_LIB.S9S_MB_2U(SCH_1):M_G_CPU0_SA_CS_N<2>
  205  M_G_CPU0_SA_CB<7>  CB_A7  @S9S_MB_2U_LIB.S9S_MB_2U(SCH_1):M_G_CPU0_SA_CB<7>
  203  M_G_CPU0_SA_CB<6>  CB_A6  @S9S_MB_2U_LIB.S9S_MB_2U(SCH_1):M_G_CPU0_SA_CB<6>
   60  M_G_CPU0_SA_CB<5>  CB_A5  @S9S_MB_2U_LIB.S9S_MB_2U(SCH_1):M_G_CPU0_SA_CB<5>
   58  M_G_CPU0_SA_CB<4>  CB_A4  @S9S_MB_2U_LIB.S9S_MB_2U(SCH_1):M_G_CPU0_SA_CB<4>
  198  M_G_CPU0_SA_CB<3>  CB_A3  @S9S_MB_2U_LIB.S9S_MB_2U(SCH_1):M_G_CPU0_SA_CB<3>
  196  M_G_CPU0_SA_CB<2>  CB_A2  @S9S_MB_2U_LIB.S9S_MB_2U(SCH_1):M_G_CPU0_SA_CB<2>
   53  M_G_CPU0_SA_CB<1>  CB_A1  @S9S_MB_2U_LIB.S9S_MB_2U(SCH_1):M_G_CPU0_SA_CB<1>
   51  M_G_CPU0_SA_CB<0>  CB_A0  @S9S_MB_2U_LIB.S9S_MB_2U(SCH_1):M_G_CPU0_SA_CB<0>
   72  M_G_CPU0_SA_CA<6>  CA6_A  @S9S_MB_2U_LIB.S9S_MB_2U(SCH_1):M_G_CPU0_SA_CA<6>
  215  M_G_CPU0_SA_CA<5>  CA5_A  @S9S_MB_2U_LIB.S9S_MB_2U(SCH_1):M_G_CPU0_SA_CA<5>
   70  M_G_CPU0_SA_CA<4>  CA4_A  @S9S_MB_2U_LIB.S9S_MB_2U(SCH_1):M_G_CPU0_SA_CA<4>
  213  M_G_CPU0_SA_CA<3>  CA3_A  @S9S_MB_2U_LIB.S9S_MB_2U(SCH_1):M_G_CPU0_SA_CA<3>
   68  M_G_CPU0_SA_CA<2>  CA2_A  @S9S_MB_2U_LIB.S9S_MB_2U(SCH_1):M_G_CPU0_SA_CA<2>
  211  M_G_CPU0_SA_CA<1>  CA1_A  @S9S_MB_2U_LIB.S9S_MB_2U(SCH_1):M_G_CPU0_SA_CA<1>
   66  M_G_CPU0_SA_CA<0>  CA0_A  @S9S_MB_2U_LIB.S9S_MB_2U(SCH_1):M_G_CPU0_SA_CA<0>
  217  M_G_CPU0_CLK_DP<1>   CK_P  @S9S_MB_2U_LIB.S9S_MB_2U(SCH_1):M_G_CPU0_CLK_DP<1>
  218  M_G_CPU0_CLK_DN<1>   CK_N  @S9S_MB_2U_LIB.S9S_MB_2U(SCH_1):M_G_CPU0_CLK_DN<1>
   62  M_G_CPU0_ALERT_N  ALERT_N  @S9S_MB_2U_LIB.S9S_MB_2U(SCH_1):M_G_CPU0_ALERT_N
    5  I3C_SPD_DDREFGH_CPU0_LVC1_SDA   HSDA  @S9S_MB_2U_LIB.S9S_MB_2U(SCH_1):I3C_SPD_DDREFGH_CPU0_LVC1_SDA
    4  I3C_SPD_DDREFGH_CPU0_LVC1_SCL   HSCL  @S9S_MB_2U_LIB.S9S_MB_2U(SCH_1):I3C_SPD_DDREFGH_CPU0_LVC1_SCL

SCONN288_ADR50001P013C01  I176  J15    [SCONN288_ADR50001P013C01-SCONNA]
  146  P12V_S3_AUX_CPU0_NVDIMM  VIN_BULK2  @S9S_MB_2U_LIB.S9S_MB_2U(SCH_1):P12V_S3_AUX_CPU0_NVDIMM
  145  P12V_S3_AUX_CPU0_NVDIMM  VIN_BULK1  @S9S_MB_2U_LIB.S9S_MB_2U(SCH_1):P12V_S3_AUX_CPU0_NVDIMM
    1  P12V_S3_AUX_CPU0_NVDIMM  VIN_BULK0  @S9S_MB_2U_LIB.S9S_MB_2U(SCH_1):P12V_S3_AUX_CPU0_NVDIMM
  288  GND            VSS126  @S9S_MB_2U_LIB.S9S_MB_2U(SCH_1):GND
  286  GND            VSS125  @S9S_MB_2U_LIB.S9S_MB_2U(SCH_1):GND
  284  GND            VSS124  @S9S_MB_2U_LIB.S9S_MB_2U(SCH_1):GND
  281  GND            VSS123  @S9S_MB_2U_LIB.S9S_MB_2U(SCH_1):GND
  279  GND            VSS122  @S9S_MB_2U_LIB.S9S_MB_2U(SCH_1):GND
  277  GND            VSS121  @S9S_MB_2U_LIB.S9S_MB_2U(SCH_1):GND
  275  GND            VSS120  @S9S_MB_2U_LIB.S9S_MB_2U(SCH_1):GND
  273  GND            VSS119  @S9S_MB_2U_LIB.S9S_MB_2U(SCH_1):GND
  270  GND            VSS118  @S9S_MB_2U_LIB.S9S_MB_2U(SCH_1):GND
  268  GND            VSS117  @S9S_MB_2U_LIB.S9S_MB_2U(SCH_1):GND
  266  GND            VSS116  @S9S_MB_2U_LIB.S9S_MB_2U(SCH_1):GND
  264  GND            VSS115  @S9S_MB_2U_LIB.S9S_MB_2U(SCH_1):GND
  262  GND            VSS114  @S9S_MB_2U_LIB.S9S_MB_2U(SCH_1):GND
  259  GND            VSS113  @S9S_MB_2U_LIB.S9S_MB_2U(SCH_1):GND
  257  GND            VSS112  @S9S_MB_2U_LIB.S9S_MB_2U(SCH_1):GND
  255  GND            VSS111  @S9S_MB_2U_LIB.S9S_MB_2U(SCH_1):GND
  253  GND            VSS110  @S9S_MB_2U_LIB.S9S_MB_2U(SCH_1):GND
  251  GND            VSS109  @S9S_MB_2U_LIB.S9S_MB_2U(SCH_1):GND
  248  GND            VSS108  @S9S_MB_2U_LIB.S9S_MB_2U(SCH_1):GND
  246  GND            VSS107  @S9S_MB_2U_LIB.S9S_MB_2U(SCH_1):GND
  244  GND            VSS106  @S9S_MB_2U_LIB.S9S_MB_2U(SCH_1):GND
  242  GND            VSS105  @S9S_MB_2U_LIB.S9S_MB_2U(SCH_1):GND
  240  GND            VSS104  @S9S_MB_2U_LIB.S9S_MB_2U(SCH_1):GND
  237  GND            VSS103  @S9S_MB_2U_LIB.S9S_MB_2U(SCH_1):GND
  235  GND            VSS102  @S9S_MB_2U_LIB.S9S_MB_2U(SCH_1):GND
  233  GND            VSS101  @S9S_MB_2U_LIB.S9S_MB_2U(SCH_1):GND
  230  GND            VSS100  @S9S_MB_2U_LIB.S9S_MB_2U(SCH_1):GND
  228  GND            VSS99  @S9S_MB_2U_LIB.S9S_MB_2U(SCH_1):GND
  226  GND            VSS98  @S9S_MB_2U_LIB.S9S_MB_2U(SCH_1):GND
  224  GND            VSS97  @S9S_MB_2U_LIB.S9S_MB_2U(SCH_1):GND
  222  GND            VSS96  @S9S_MB_2U_LIB.S9S_MB_2U(SCH_1):GND
  219  GND            VSS95  @S9S_MB_2U_LIB.S9S_MB_2U(SCH_1):GND
  216  GND            VSS94  @S9S_MB_2U_LIB.S9S_MB_2U(SCH_1):GND
  214  GND            VSS93  @S9S_MB_2U_LIB.S9S_MB_2U(SCH_1):GND
  212  GND            VSS92  @S9S_MB_2U_LIB.S9S_MB_2U(SCH_1):GND
  210  GND            VSS91  @S9S_MB_2U_LIB.S9S_MB_2U(SCH_1):GND
  208  GND            VSS90  @S9S_MB_2U_LIB.S9S_MB_2U(SCH_1):GND
  206  GND            VSS89  @S9S_MB_2U_LIB.S9S_MB_2U(SCH_1):GND
  204  GND            VSS88  @S9S_MB_2U_LIB.S9S_MB_2U(SCH_1):GND
  202  GND            VSS87  @S9S_MB_2U_LIB.S9S_MB_2U(SCH_1):GND
  199  GND            VSS86  @S9S_MB_2U_LIB.S9S_MB_2U(SCH_1):GND
  197  GND            VSS85  @S9S_MB_2U_LIB.S9S_MB_2U(SCH_1):GND
  195  GND            VSS84  @S9S_MB_2U_LIB.S9S_MB_2U(SCH_1):GND
  193  GND            VSS83  @S9S_MB_2U_LIB.S9S_MB_2U(SCH_1):GND
  191  GND            VSS82  @S9S_MB_2U_LIB.S9S_MB_2U(SCH_1):GND
  188  GND            VSS81  @S9S_MB_2U_LIB.S9S_MB_2U(SCH_1):GND
  186  GND            VSS80  @S9S_MB_2U_LIB.S9S_MB_2U(SCH_1):GND
  184  GND            VSS79  @S9S_MB_2U_LIB.S9S_MB_2U(SCH_1):GND
  182  GND            VSS78  @S9S_MB_2U_LIB.S9S_MB_2U(SCH_1):GND
  180  GND            VSS77  @S9S_MB_2U_LIB.S9S_MB_2U(SCH_1):GND
  177  GND            VSS76  @S9S_MB_2U_LIB.S9S_MB_2U(SCH_1):GND
  175  GND            VSS75  @S9S_MB_2U_LIB.S9S_MB_2U(SCH_1):GND
  173  GND            VSS74  @S9S_MB_2U_LIB.S9S_MB_2U(SCH_1):GND
  171  GND            VSS73  @S9S_MB_2U_LIB.S9S_MB_2U(SCH_1):GND
  169  GND            VSS72  @S9S_MB_2U_LIB.S9S_MB_2U(SCH_1):GND
  166  GND            VSS71  @S9S_MB_2U_LIB.S9S_MB_2U(SCH_1):GND
  164  GND            VSS70  @S9S_MB_2U_LIB.S9S_MB_2U(SCH_1):GND
  162  GND            VSS69  @S9S_MB_2U_LIB.S9S_MB_2U(SCH_1):GND
  160  GND            VSS68  @S9S_MB_2U_LIB.S9S_MB_2U(SCH_1):GND
  158  GND            VSS67  @S9S_MB_2U_LIB.S9S_MB_2U(SCH_1):GND
  155  GND            VSS66  @S9S_MB_2U_LIB.S9S_MB_2U(SCH_1):GND
  153  GND            VSS65  @S9S_MB_2U_LIB.S9S_MB_2U(SCH_1):GND
  151  GND            VSS64  @S9S_MB_2U_LIB.S9S_MB_2U(SCH_1):GND
  143  GND            VSS63  @S9S_MB_2U_LIB.S9S_MB_2U(SCH_1):GND
  141  GND            VSS62  @S9S_MB_2U_LIB.S9S_MB_2U(SCH_1):GND
  139  GND            VSS61  @S9S_MB_2U_LIB.S9S_MB_2U(SCH_1):GND
  136  GND            VSS60  @S9S_MB_2U_LIB.S9S_MB_2U(SCH_1):GND
  134  GND            VSS59  @S9S_MB_2U_LIB.S9S_MB_2U(SCH_1):GND
  132  GND            VSS58  @S9S_MB_2U_LIB.S9S_MB_2U(SCH_1):GND
  130  GND            VSS57  @S9S_MB_2U_LIB.S9S_MB_2U(SCH_1):GND
  128  GND            VSS56  @S9S_MB_2U_LIB.S9S_MB_2U(SCH_1):GND
  125  GND            VSS55  @S9S_MB_2U_LIB.S9S_MB_2U(SCH_1):GND
  123  GND            VSS54  @S9S_MB_2U_LIB.S9S_MB_2U(SCH_1):GND
  121  GND            VSS53  @S9S_MB_2U_LIB.S9S_MB_2U(SCH_1):GND
  119  GND            VSS52  @S9S_MB_2U_LIB.S9S_MB_2U(SCH_1):GND
  117  GND            VSS51  @S9S_MB_2U_LIB.S9S_MB_2U(SCH_1):GND
  114  GND            VSS50  @S9S_MB_2U_LIB.S9S_MB_2U(SCH_1):GND
  112  GND            VSS49  @S9S_MB_2U_LIB.S9S_MB_2U(SCH_1):GND
  110  GND            VSS48  @S9S_MB_2U_LIB.S9S_MB_2U(SCH_1):GND
  108  GND            VSS47  @S9S_MB_2U_LIB.S9S_MB_2U(SCH_1):GND
  106  GND            VSS46  @S9S_MB_2U_LIB.S9S_MB_2U(SCH_1):GND
  103  GND            VSS45  @S9S_MB_2U_LIB.S9S_MB_2U(SCH_1):GND
  101  GND            VSS44  @S9S_MB_2U_LIB.S9S_MB_2U(SCH_1):GND
   99  GND            VSS43  @S9S_MB_2U_LIB.S9S_MB_2U(SCH_1):GND
   97  GND            VSS42  @S9S_MB_2U_LIB.S9S_MB_2U(SCH_1):GND
   95  GND            VSS41  @S9S_MB_2U_LIB.S9S_MB_2U(SCH_1):GND
   92  GND            VSS40  @S9S_MB_2U_LIB.S9S_MB_2U(SCH_1):GND
   90  GND            VSS39  @S9S_MB_2U_LIB.S9S_MB_2U(SCH_1):GND
   88  GND            VSS38  @S9S_MB_2U_LIB.S9S_MB_2U(SCH_1):GND
   85  GND            VSS37  @S9S_MB_2U_LIB.S9S_MB_2U(SCH_1):GND
   83  GND            VSS36  @S9S_MB_2U_LIB.S9S_MB_2U(SCH_1):GND
   81  GND            VSS35  @S9S_MB_2U_LIB.S9S_MB_2U(SCH_1):GND
   79  GND            VSS34  @S9S_MB_2U_LIB.S9S_MB_2U(SCH_1):GND
   77  GND            VSS33  @S9S_MB_2U_LIB.S9S_MB_2U(SCH_1):GND
   75  GND            VSS32  @S9S_MB_2U_LIB.S9S_MB_2U(SCH_1):GND
   73  GND            VSS31  @S9S_MB_2U_LIB.S9S_MB_2U(SCH_1):GND
   71  GND            VSS30  @S9S_MB_2U_LIB.S9S_MB_2U(SCH_1):GND
   69  GND            VSS29  @S9S_MB_2U_LIB.S9S_MB_2U(SCH_1):GND
   67  GND            VSS28  @S9S_MB_2U_LIB.S9S_MB_2U(SCH_1):GND
   65  GND            VSS27  @S9S_MB_2U_LIB.S9S_MB_2U(SCH_1):GND
   63  GND            VSS26  @S9S_MB_2U_LIB.S9S_MB_2U(SCH_1):GND
   61  GND            VSS25  @S9S_MB_2U_LIB.S9S_MB_2U(SCH_1):GND
   59  GND            VSS24  @S9S_MB_2U_LIB.S9S_MB_2U(SCH_1):GND
   57  GND            VSS23  @S9S_MB_2U_LIB.S9S_MB_2U(SCH_1):GND
   54  GND            VSS22  @S9S_MB_2U_LIB.S9S_MB_2U(SCH_1):GND
   52  GND            VSS21  @S9S_MB_2U_LIB.S9S_MB_2U(SCH_1):GND
   50  GND            VSS20  @S9S_MB_2U_LIB.S9S_MB_2U(SCH_1):GND
   48  GND            VSS19  @S9S_MB_2U_LIB.S9S_MB_2U(SCH_1):GND
   46  GND            VSS18  @S9S_MB_2U_LIB.S9S_MB_2U(SCH_1):GND
   43  GND            VSS17  @S9S_MB_2U_LIB.S9S_MB_2U(SCH_1):GND
   41  GND            VSS16  @S9S_MB_2U_LIB.S9S_MB_2U(SCH_1):GND
   39  GND            VSS15  @S9S_MB_2U_LIB.S9S_MB_2U(SCH_1):GND
   37  GND            VSS14  @S9S_MB_2U_LIB.S9S_MB_2U(SCH_1):GND
   35  GND            VSS13  @S9S_MB_2U_LIB.S9S_MB_2U(SCH_1):GND
   32  GND            VSS12  @S9S_MB_2U_LIB.S9S_MB_2U(SCH_1):GND
   30  GND            VSS11  @S9S_MB_2U_LIB.S9S_MB_2U(SCH_1):GND
   28  GND            VSS10  @S9S_MB_2U_LIB.S9S_MB_2U(SCH_1):GND
   26  GND             VSS9  @S9S_MB_2U_LIB.S9S_MB_2U(SCH_1):GND
   24  GND             VSS8  @S9S_MB_2U_LIB.S9S_MB_2U(SCH_1):GND
   21  GND             VSS7  @S9S_MB_2U_LIB.S9S_MB_2U(SCH_1):GND
   19  GND             VSS6  @S9S_MB_2U_LIB.S9S_MB_2U(SCH_1):GND
   17  GND             VSS5  @S9S_MB_2U_LIB.S9S_MB_2U(SCH_1):GND
   15  GND             VSS4  @S9S_MB_2U_LIB.S9S_MB_2U(SCH_1):GND
   13  GND             VSS3  @S9S_MB_2U_LIB.S9S_MB_2U(SCH_1):GND
   10  GND             VSS2  @S9S_MB_2U_LIB.S9S_MB_2U(SCH_1):GND
    8  GND             VSS1  @S9S_MB_2U_LIB.S9S_MB_2U(SCH_1):GND
    6  GND             VSS0  @S9S_MB_2U_LIB.S9S_MB_2U(SCH_1):GND
   G3  GND               G3  @S9S_MB_2U_LIB.S9S_MB_2U(SCH_1):GND
   G2  GND               G2  @S9S_MB_2U_LIB.S9S_MB_2U(SCH_1):GND
   G1  GND               G1  @S9S_MB_2U_LIB.S9S_MB_2U(SCH_1):GND

SCONN288_ADR50001P013C01  I124  J15    [SCONN288_ADR50001P013C01-SCONNA]
   93  M_H_CPU0_SB_DQS_DP<9>  DQS9_B_P  @S9S_MB_2U_LIB.S9S_MB_2U(SCH_1):M_H_CPU0_SB_DQS_DP<9>
  283  M_H_CPU0_SB_DQS_DP<8>  DQS8_B_P  @S9S_MB_2U_LIB.S9S_MB_2U(SCH_1):M_H_CPU0_SB_DQS_DP<8>
  272  M_H_CPU0_SB_DQS_DP<7>  DQS7_B_P  @S9S_MB_2U_LIB.S9S_MB_2U(SCH_1):M_H_CPU0_SB_DQS_DP<7>
  261  M_H_CPU0_SB_DQS_DP<6>  DQS6_B_P  @S9S_MB_2U_LIB.S9S_MB_2U(SCH_1):M_H_CPU0_SB_DQS_DP<6>
  250  M_H_CPU0_SB_DQS_DP<5>  DQS5_B_P  @S9S_MB_2U_LIB.S9S_MB_2U(SCH_1):M_H_CPU0_SB_DQS_DP<5>
  239  M_H_CPU0_SB_DQS_DP<4>  DQS4_B_P  @S9S_MB_2U_LIB.S9S_MB_2U(SCH_1):M_H_CPU0_SB_DQS_DP<4>
  137  M_H_CPU0_SB_DQS_DP<3>  DQS3_B_P  @S9S_MB_2U_LIB.S9S_MB_2U(SCH_1):M_H_CPU0_SB_DQS_DP<3>
  126  M_H_CPU0_SB_DQS_DP<2>  DQS2_B_P  @S9S_MB_2U_LIB.S9S_MB_2U(SCH_1):M_H_CPU0_SB_DQS_DP<2>
  115  M_H_CPU0_SB_DQS_DP<1>  DQS1_B_P  @S9S_MB_2U_LIB.S9S_MB_2U(SCH_1):M_H_CPU0_SB_DQS_DP<1>
  104  M_H_CPU0_SB_DQS_DP<0>  DQS0_B_P  @S9S_MB_2U_LIB.S9S_MB_2U(SCH_1):M_H_CPU0_SB_DQS_DP<0>
   94  M_H_CPU0_SB_DQS_DN<9>  DQS9_B_N  @S9S_MB_2U_LIB.S9S_MB_2U(SCH_1):M_H_CPU0_SB_DQS_DN<9>
  282  M_H_CPU0_SB_DQS_DN<8>  DQS8_B_N  @S9S_MB_2U_LIB.S9S_MB_2U(SCH_1):M_H_CPU0_SB_DQS_DN<8>
  271  M_H_CPU0_SB_DQS_DN<7>  DQS7_B_N  @S9S_MB_2U_LIB.S9S_MB_2U(SCH_1):M_H_CPU0_SB_DQS_DN<7>
  260  M_H_CPU0_SB_DQS_DN<6>  DQS6_B_N  @S9S_MB_2U_LIB.S9S_MB_2U(SCH_1):M_H_CPU0_SB_DQS_DN<6>
  249  M_H_CPU0_SB_DQS_DN<5>  DQS5_B_N  @S9S_MB_2U_LIB.S9S_MB_2U(SCH_1):M_H_CPU0_SB_DQS_DN<5>
  238  M_H_CPU0_SB_DQS_DN<4>  DQS4_B_N  @S9S_MB_2U_LIB.S9S_MB_2U(SCH_1):M_H_CPU0_SB_DQS_DN<4>
  138  M_H_CPU0_SB_DQS_DN<3>  DQS3_B_N  @S9S_MB_2U_LIB.S9S_MB_2U(SCH_1):M_H_CPU0_SB_DQS_DN<3>
  127  M_H_CPU0_SB_DQS_DN<2>  DQS2_B_N  @S9S_MB_2U_LIB.S9S_MB_2U(SCH_1):M_H_CPU0_SB_DQS_DN<2>
  116  M_H_CPU0_SB_DQS_DN<1>  DQS1_B_N  @S9S_MB_2U_LIB.S9S_MB_2U(SCH_1):M_H_CPU0_SB_DQS_DN<1>
  105  M_H_CPU0_SB_DQS_DN<0>  DQS0_B_N  @S9S_MB_2U_LIB.S9S_MB_2U(SCH_1):M_H_CPU0_SB_DQS_DN<0>
  201  M_H_CPU0_SA_DQS_DP<9>  DQS9_A_P  @S9S_MB_2U_LIB.S9S_MB_2U(SCH_1):M_H_CPU0_SA_DQS_DP<9>
  190  M_H_CPU0_SA_DQS_DP<8>  DQS8_A_P  @S9S_MB_2U_LIB.S9S_MB_2U(SCH_1):M_H_CPU0_SA_DQS_DP<8>
  179  M_H_CPU0_SA_DQS_DP<7>  DQS7_A_P  @S9S_MB_2U_LIB.S9S_MB_2U(SCH_1):M_H_CPU0_SA_DQS_DP<7>
  168  M_H_CPU0_SA_DQS_DP<6>  DQS6_A_P  @S9S_MB_2U_LIB.S9S_MB_2U(SCH_1):M_H_CPU0_SA_DQS_DP<6>
  157  M_H_CPU0_SA_DQS_DP<5>  DQS5_A_P  @S9S_MB_2U_LIB.S9S_MB_2U(SCH_1):M_H_CPU0_SA_DQS_DP<5>
   55  M_H_CPU0_SA_DQS_DP<4>  DQS4_A_P  @S9S_MB_2U_LIB.S9S_MB_2U(SCH_1):M_H_CPU0_SA_DQS_DP<4>
   44  M_H_CPU0_SA_DQS_DP<3>  DQS3_A_P  @S9S_MB_2U_LIB.S9S_MB_2U(SCH_1):M_H_CPU0_SA_DQS_DP<3>
   33  M_H_CPU0_SA_DQS_DP<2>  DQS2_A_P  @S9S_MB_2U_LIB.S9S_MB_2U(SCH_1):M_H_CPU0_SA_DQS_DP<2>
   22  M_H_CPU0_SA_DQS_DP<1>  DQS1_A_P  @S9S_MB_2U_LIB.S9S_MB_2U(SCH_1):M_H_CPU0_SA_DQS_DP<1>
   11  M_H_CPU0_SA_DQS_DP<0>  DQS0_A_P  @S9S_MB_2U_LIB.S9S_MB_2U(SCH_1):M_H_CPU0_SA_DQS_DP<0>
  200  M_H_CPU0_SA_DQS_DN<9>  DQS9_A_N  @S9S_MB_2U_LIB.S9S_MB_2U(SCH_1):M_H_CPU0_SA_DQS_DN<9>
  189  M_H_CPU0_SA_DQS_DN<8>  DQS8_A_N  @S9S_MB_2U_LIB.S9S_MB_2U(SCH_1):M_H_CPU0_SA_DQS_DN<8>
  178  M_H_CPU0_SA_DQS_DN<7>  DQS7_A_N  @S9S_MB_2U_LIB.S9S_MB_2U(SCH_1):M_H_CPU0_SA_DQS_DN<7>
  167  M_H_CPU0_SA_DQS_DN<6>  DQS6_A_N  @S9S_MB_2U_LIB.S9S_MB_2U(SCH_1):M_H_CPU0_SA_DQS_DN<6>
  156  M_H_CPU0_SA_DQS_DN<5>  DQS5_A_N  @S9S_MB_2U_LIB.S9S_MB_2U(SCH_1):M_H_CPU0_SA_DQS_DN<5>
   56  M_H_CPU0_SA_DQS_DN<4>  DQS4_A_N  @S9S_MB_2U_LIB.S9S_MB_2U(SCH_1):M_H_CPU0_SA_DQS_DN<4>
   45  M_H_CPU0_SA_DQS_DN<3>  DQS3_A_N  @S9S_MB_2U_LIB.S9S_MB_2U(SCH_1):M_H_CPU0_SA_DQS_DN<3>
   34  M_H_CPU0_SA_DQS_DN<2>  DQS2_A_N  @S9S_MB_2U_LIB.S9S_MB_2U(SCH_1):M_H_CPU0_SA_DQS_DN<2>
   23  M_H_CPU0_SA_DQS_DN<1>  DQS1_A_N  @S9S_MB_2U_LIB.S9S_MB_2U(SCH_1):M_H_CPU0_SA_DQS_DN<1>
   12  M_H_CPU0_SA_DQS_DN<0>  DQS0_A_N  @S9S_MB_2U_LIB.S9S_MB_2U(SCH_1):M_H_CPU0_SA_DQS_DN<0>

SCONN288_ADR50001P013C01  I48  J15    [SCONN288_ADR50001P013C01-SCONNA]
  232  NC              RFU6  NC
  231  NC              RFU5  NC
  220  NC              RFU4  NC
  150  NC              RFU3  NC
  149  NC              RFU2  NC
  144  NC              RFU1  NC
    2  NC              RFU0  NC
  207  RST_M_GH_CPU0_FPGA_N  RESET_N  @S9S_MB_2U_LIB.S9S_MB_2U(SCH_1):RST_M_GH_CPU0_FPGA_N
  147  PWRGD_CHH_CPU0_DIMM1  PWR_GOOD||FAIL_N  @S9S_MB_2U_LIB.S9S_MB_2U(SCH_1):PWRGD_CHH_CPU0_DIMM1
  148  PD_CHH_CPU0_DIMM1_SAA    HAS  @S9S_MB_2U_LIB.S9S_MB_2U(SCH_1):PD_CHH_CPU0_DIMM1_SAA
    3  P3V3_AUX       VIN_MGMT  @S9S_MB_2U_LIB.S9S_MB_2U(SCH_1):P3V3_AUX
   87  M_H_CPU0_SB_RSP<0>  LBS||RSP_N_B  @S9S_MB_2U_LIB.S9S_MB_2U(SCH_1):M_H_CPU0_SB_RSP<0>
  227  M_H_CPU0_SB_PAR  PAR_B  @S9S_MB_2U_LIB.S9S_MB_2U(SCH_1):M_H_CPU0_SB_PAR
  113  M_H_CPU0_SB_DQ<9>  DQ_B9  @S9S_MB_2U_LIB.S9S_MB_2U(SCH_1):M_H_CPU0_SB_DQ<9>
  111  M_H_CPU0_SB_DQ<8>  DQ_B8  @S9S_MB_2U_LIB.S9S_MB_2U(SCH_1):M_H_CPU0_SB_DQ<8>
  254  M_H_CPU0_SB_DQ<7>  DQ_B7  @S9S_MB_2U_LIB.S9S_MB_2U(SCH_1):M_H_CPU0_SB_DQ<7>
  252  M_H_CPU0_SB_DQ<6>  DQ_B6  @S9S_MB_2U_LIB.S9S_MB_2U(SCH_1):M_H_CPU0_SB_DQ<6>
  109  M_H_CPU0_SB_DQ<5>  DQ_B5  @S9S_MB_2U_LIB.S9S_MB_2U(SCH_1):M_H_CPU0_SB_DQ<5>
  107  M_H_CPU0_SB_DQ<4>  DQ_B4  @S9S_MB_2U_LIB.S9S_MB_2U(SCH_1):M_H_CPU0_SB_DQ<4>
  247  M_H_CPU0_SB_DQ<3>  DQ_B3  @S9S_MB_2U_LIB.S9S_MB_2U(SCH_1):M_H_CPU0_SB_DQ<3>
  287  M_H_CPU0_SB_DQ<31>  DQ_B31  @S9S_MB_2U_LIB.S9S_MB_2U(SCH_1):M_H_CPU0_SB_DQ<31>
  285  M_H_CPU0_SB_DQ<30>  DQ_B30  @S9S_MB_2U_LIB.S9S_MB_2U(SCH_1):M_H_CPU0_SB_DQ<30>
  245  M_H_CPU0_SB_DQ<2>  DQ_B2  @S9S_MB_2U_LIB.S9S_MB_2U(SCH_1):M_H_CPU0_SB_DQ<2>
  142  M_H_CPU0_SB_DQ<29>  DQ_B29  @S9S_MB_2U_LIB.S9S_MB_2U(SCH_1):M_H_CPU0_SB_DQ<29>
  140  M_H_CPU0_SB_DQ<28>  DQ_B28  @S9S_MB_2U_LIB.S9S_MB_2U(SCH_1):M_H_CPU0_SB_DQ<28>
  280  M_H_CPU0_SB_DQ<27>  DQ_B27  @S9S_MB_2U_LIB.S9S_MB_2U(SCH_1):M_H_CPU0_SB_DQ<27>
  278  M_H_CPU0_SB_DQ<26>  DQ_B26  @S9S_MB_2U_LIB.S9S_MB_2U(SCH_1):M_H_CPU0_SB_DQ<26>
  135  M_H_CPU0_SB_DQ<25>  DQ_B25  @S9S_MB_2U_LIB.S9S_MB_2U(SCH_1):M_H_CPU0_SB_DQ<25>
  133  M_H_CPU0_SB_DQ<24>  DQ_B24  @S9S_MB_2U_LIB.S9S_MB_2U(SCH_1):M_H_CPU0_SB_DQ<24>
  276  M_H_CPU0_SB_DQ<23>  DQ_B23  @S9S_MB_2U_LIB.S9S_MB_2U(SCH_1):M_H_CPU0_SB_DQ<23>
  274  M_H_CPU0_SB_DQ<22>  DQ_B22  @S9S_MB_2U_LIB.S9S_MB_2U(SCH_1):M_H_CPU0_SB_DQ<22>
  131  M_H_CPU0_SB_DQ<21>  DQ_B21  @S9S_MB_2U_LIB.S9S_MB_2U(SCH_1):M_H_CPU0_SB_DQ<21>
  129  M_H_CPU0_SB_DQ<20>  DQ_B20  @S9S_MB_2U_LIB.S9S_MB_2U(SCH_1):M_H_CPU0_SB_DQ<20>
  102  M_H_CPU0_SB_DQ<1>  DQ_B1  @S9S_MB_2U_LIB.S9S_MB_2U(SCH_1):M_H_CPU0_SB_DQ<1>
  269  M_H_CPU0_SB_DQ<19>  DQ_B19  @S9S_MB_2U_LIB.S9S_MB_2U(SCH_1):M_H_CPU0_SB_DQ<19>
  267  M_H_CPU0_SB_DQ<18>  DQ_B18  @S9S_MB_2U_LIB.S9S_MB_2U(SCH_1):M_H_CPU0_SB_DQ<18>
  124  M_H_CPU0_SB_DQ<17>  DQ_B17  @S9S_MB_2U_LIB.S9S_MB_2U(SCH_1):M_H_CPU0_SB_DQ<17>
  122  M_H_CPU0_SB_DQ<16>  DQ_B16  @S9S_MB_2U_LIB.S9S_MB_2U(SCH_1):M_H_CPU0_SB_DQ<16>
  265  M_H_CPU0_SB_DQ<15>  DQ_B15  @S9S_MB_2U_LIB.S9S_MB_2U(SCH_1):M_H_CPU0_SB_DQ<15>
  263  M_H_CPU0_SB_DQ<14>  DQ_B14  @S9S_MB_2U_LIB.S9S_MB_2U(SCH_1):M_H_CPU0_SB_DQ<14>
  120  M_H_CPU0_SB_DQ<13>  DQ_B13  @S9S_MB_2U_LIB.S9S_MB_2U(SCH_1):M_H_CPU0_SB_DQ<13>
  118  M_H_CPU0_SB_DQ<12>  DQ_B12  @S9S_MB_2U_LIB.S9S_MB_2U(SCH_1):M_H_CPU0_SB_DQ<12>
  258  M_H_CPU0_SB_DQ<11>  DQ_B11  @S9S_MB_2U_LIB.S9S_MB_2U(SCH_1):M_H_CPU0_SB_DQ<11>
  256  M_H_CPU0_SB_DQ<10>  DQ_B10  @S9S_MB_2U_LIB.S9S_MB_2U(SCH_1):M_H_CPU0_SB_DQ<10>
  100  M_H_CPU0_SB_DQ<0>  DQ_B0  @S9S_MB_2U_LIB.S9S_MB_2U(SCH_1):M_H_CPU0_SB_DQ<0>
  229  M_H_CPU0_SB_CS_N<1>  CS1_N_B  @S9S_MB_2U_LIB.S9S_MB_2U(SCH_1):M_H_CPU0_SB_CS_N<1>
   84  M_H_CPU0_SB_CS_N<0>  CS0_N_B  @S9S_MB_2U_LIB.S9S_MB_2U(SCH_1):M_H_CPU0_SB_CS_N<0>
  236  M_H_CPU0_SB_CB<7>  CB_B7  @S9S_MB_2U_LIB.S9S_MB_2U(SCH_1):M_H_CPU0_SB_CB<7>
  234  M_H_CPU0_SB_CB<6>  CB_B6  @S9S_MB_2U_LIB.S9S_MB_2U(SCH_1):M_H_CPU0_SB_CB<6>
   91  M_H_CPU0_SB_CB<5>  CB_B5  @S9S_MB_2U_LIB.S9S_MB_2U(SCH_1):M_H_CPU0_SB_CB<5>
   89  M_H_CPU0_SB_CB<4>  CB_B4  @S9S_MB_2U_LIB.S9S_MB_2U(SCH_1):M_H_CPU0_SB_CB<4>
  243  M_H_CPU0_SB_CB<3>  CB_B3  @S9S_MB_2U_LIB.S9S_MB_2U(SCH_1):M_H_CPU0_SB_CB<3>
  241  M_H_CPU0_SB_CB<2>  CB_B2  @S9S_MB_2U_LIB.S9S_MB_2U(SCH_1):M_H_CPU0_SB_CB<2>
   98  M_H_CPU0_SB_CB<1>  CB_B1  @S9S_MB_2U_LIB.S9S_MB_2U(SCH_1):M_H_CPU0_SB_CB<1>
   96  M_H_CPU0_SB_CB<0>  CB_B0  @S9S_MB_2U_LIB.S9S_MB_2U(SCH_1):M_H_CPU0_SB_CB<0>
   82  M_H_CPU0_SB_CA<6>  CA6_B  @S9S_MB_2U_LIB.S9S_MB_2U(SCH_1):M_H_CPU0_SB_CA<6>
  225  M_H_CPU0_SB_CA<5>  CA5_B  @S9S_MB_2U_LIB.S9S_MB_2U(SCH_1):M_H_CPU0_SB_CA<5>
   80  M_H_CPU0_SB_CA<4>  CA4_B  @S9S_MB_2U_LIB.S9S_MB_2U(SCH_1):M_H_CPU0_SB_CA<4>
  223  M_H_CPU0_SB_CA<3>  CA3_B  @S9S_MB_2U_LIB.S9S_MB_2U(SCH_1):M_H_CPU0_SB_CA<3>
   78  M_H_CPU0_SB_CA<2>  CA2_B  @S9S_MB_2U_LIB.S9S_MB_2U(SCH_1):M_H_CPU0_SB_CA<2>
  221  M_H_CPU0_SB_CA<1>  CA1_B  @S9S_MB_2U_LIB.S9S_MB_2U(SCH_1):M_H_CPU0_SB_CA<1>
   76  M_H_CPU0_SB_CA<0>  CA0_B  @S9S_MB_2U_LIB.S9S_MB_2U(SCH_1):M_H_CPU0_SB_CA<0>
   86  M_H_CPU0_SA_RSP<0>  LBD||RSP_N_A  @S9S_MB_2U_LIB.S9S_MB_2U(SCH_1):M_H_CPU0_SA_RSP<0>
   74  M_H_CPU0_SA_PAR  PAR_A  @S9S_MB_2U_LIB.S9S_MB_2U(SCH_1):M_H_CPU0_SA_PAR
   20  M_H_CPU0_SA_DQ<9>  DQ_A9  @S9S_MB_2U_LIB.S9S_MB_2U(SCH_1):M_H_CPU0_SA_DQ<9>
   18  M_H_CPU0_SA_DQ<8>  DQ_A8  @S9S_MB_2U_LIB.S9S_MB_2U(SCH_1):M_H_CPU0_SA_DQ<8>
  161  M_H_CPU0_SA_DQ<7>  DQ_A7  @S9S_MB_2U_LIB.S9S_MB_2U(SCH_1):M_H_CPU0_SA_DQ<7>
  159  M_H_CPU0_SA_DQ<6>  DQ_A6  @S9S_MB_2U_LIB.S9S_MB_2U(SCH_1):M_H_CPU0_SA_DQ<6>
   16  M_H_CPU0_SA_DQ<5>  DQ_A5  @S9S_MB_2U_LIB.S9S_MB_2U(SCH_1):M_H_CPU0_SA_DQ<5>
   14  M_H_CPU0_SA_DQ<4>  DQ_A4  @S9S_MB_2U_LIB.S9S_MB_2U(SCH_1):M_H_CPU0_SA_DQ<4>
  154  M_H_CPU0_SA_DQ<3>  DQ_A3  @S9S_MB_2U_LIB.S9S_MB_2U(SCH_1):M_H_CPU0_SA_DQ<3>
  194  M_H_CPU0_SA_DQ<31>  DQ_A31  @S9S_MB_2U_LIB.S9S_MB_2U(SCH_1):M_H_CPU0_SA_DQ<31>
  192  M_H_CPU0_SA_DQ<30>  DQ_A30  @S9S_MB_2U_LIB.S9S_MB_2U(SCH_1):M_H_CPU0_SA_DQ<30>
  152  M_H_CPU0_SA_DQ<2>  DQ_A2  @S9S_MB_2U_LIB.S9S_MB_2U(SCH_1):M_H_CPU0_SA_DQ<2>
   49  M_H_CPU0_SA_DQ<29>  DQ_A29  @S9S_MB_2U_LIB.S9S_MB_2U(SCH_1):M_H_CPU0_SA_DQ<29>
   47  M_H_CPU0_SA_DQ<28>  DQ_A28  @S9S_MB_2U_LIB.S9S_MB_2U(SCH_1):M_H_CPU0_SA_DQ<28>
  187  M_H_CPU0_SA_DQ<27>  DQ_A27  @S9S_MB_2U_LIB.S9S_MB_2U(SCH_1):M_H_CPU0_SA_DQ<27>
  185  M_H_CPU0_SA_DQ<26>  DQ_A26  @S9S_MB_2U_LIB.S9S_MB_2U(SCH_1):M_H_CPU0_SA_DQ<26>
   42  M_H_CPU0_SA_DQ<25>  DQ_A25  @S9S_MB_2U_LIB.S9S_MB_2U(SCH_1):M_H_CPU0_SA_DQ<25>
   40  M_H_CPU0_SA_DQ<24>  DQ_A24  @S9S_MB_2U_LIB.S9S_MB_2U(SCH_1):M_H_CPU0_SA_DQ<24>
  183  M_H_CPU0_SA_DQ<23>  DQ_A23  @S9S_MB_2U_LIB.S9S_MB_2U(SCH_1):M_H_CPU0_SA_DQ<23>
  181  M_H_CPU0_SA_DQ<22>  DQ_A22  @S9S_MB_2U_LIB.S9S_MB_2U(SCH_1):M_H_CPU0_SA_DQ<22>
   38  M_H_CPU0_SA_DQ<21>  DQ_A21  @S9S_MB_2U_LIB.S9S_MB_2U(SCH_1):M_H_CPU0_SA_DQ<21>
   36  M_H_CPU0_SA_DQ<20>  DQ_A20  @S9S_MB_2U_LIB.S9S_MB_2U(SCH_1):M_H_CPU0_SA_DQ<20>
    9  M_H_CPU0_SA_DQ<1>  DQ_A1  @S9S_MB_2U_LIB.S9S_MB_2U(SCH_1):M_H_CPU0_SA_DQ<1>
  176  M_H_CPU0_SA_DQ<19>  DQ_A19  @S9S_MB_2U_LIB.S9S_MB_2U(SCH_1):M_H_CPU0_SA_DQ<19>
  174  M_H_CPU0_SA_DQ<18>  DQ_A18  @S9S_MB_2U_LIB.S9S_MB_2U(SCH_1):M_H_CPU0_SA_DQ<18>
   31  M_H_CPU0_SA_DQ<17>  DQ_A17  @S9S_MB_2U_LIB.S9S_MB_2U(SCH_1):M_H_CPU0_SA_DQ<17>
   29  M_H_CPU0_SA_DQ<16>  DQ_A16  @S9S_MB_2U_LIB.S9S_MB_2U(SCH_1):M_H_CPU0_SA_DQ<16>
  172  M_H_CPU0_SA_DQ<15>  DQ_A15  @S9S_MB_2U_LIB.S9S_MB_2U(SCH_1):M_H_CPU0_SA_DQ<15>
  170  M_H_CPU0_SA_DQ<14>  DQ_A14  @S9S_MB_2U_LIB.S9S_MB_2U(SCH_1):M_H_CPU0_SA_DQ<14>
   27  M_H_CPU0_SA_DQ<13>  DQ_A13  @S9S_MB_2U_LIB.S9S_MB_2U(SCH_1):M_H_CPU0_SA_DQ<13>
   25  M_H_CPU0_SA_DQ<12>  DQ_A12  @S9S_MB_2U_LIB.S9S_MB_2U(SCH_1):M_H_CPU0_SA_DQ<12>
  165  M_H_CPU0_SA_DQ<11>  DQ_A11  @S9S_MB_2U_LIB.S9S_MB_2U(SCH_1):M_H_CPU0_SA_DQ<11>
  163  M_H_CPU0_SA_DQ<10>  DQ_A10  @S9S_MB_2U_LIB.S9S_MB_2U(SCH_1):M_H_CPU0_SA_DQ<10>
    7  M_H_CPU0_SA_DQ<0>  DQ_A0  @S9S_MB_2U_LIB.S9S_MB_2U(SCH_1):M_H_CPU0_SA_DQ<0>
  209  M_H_CPU0_SA_CS_N<1>  CS1_N_A  @S9S_MB_2U_LIB.S9S_MB_2U(SCH_1):M_H_CPU0_SA_CS_N<1>
   64  M_H_CPU0_SA_CS_N<0>  CS0_N_A  @S9S_MB_2U_LIB.S9S_MB_2U(SCH_1):M_H_CPU0_SA_CS_N<0>
  205  M_H_CPU0_SA_CB<7>  CB_A7  @S9S_MB_2U_LIB.S9S_MB_2U(SCH_1):M_H_CPU0_SA_CB<7>
  203  M_H_CPU0_SA_CB<6>  CB_A6  @S9S_MB_2U_LIB.S9S_MB_2U(SCH_1):M_H_CPU0_SA_CB<6>
   60  M_H_CPU0_SA_CB<5>  CB_A5  @S9S_MB_2U_LIB.S9S_MB_2U(SCH_1):M_H_CPU0_SA_CB<5>
   58  M_H_CPU0_SA_CB<4>  CB_A4  @S9S_MB_2U_LIB.S9S_MB_2U(SCH_1):M_H_CPU0_SA_CB<4>
  198  M_H_CPU0_SA_CB<3>  CB_A3  @S9S_MB_2U_LIB.S9S_MB_2U(SCH_1):M_H_CPU0_SA_CB<3>
  196  M_H_CPU0_SA_CB<2>  CB_A2  @S9S_MB_2U_LIB.S9S_MB_2U(SCH_1):M_H_CPU0_SA_CB<2>
   53  M_H_CPU0_SA_CB<1>  CB_A1  @S9S_MB_2U_LIB.S9S_MB_2U(SCH_1):M_H_CPU0_SA_CB<1>
   51  M_H_CPU0_SA_CB<0>  CB_A0  @S9S_MB_2U_LIB.S9S_MB_2U(SCH_1):M_H_CPU0_SA_CB<0>
   72  M_H_CPU0_SA_CA<6>  CA6_A  @S9S_MB_2U_LIB.S9S_MB_2U(SCH_1):M_H_CPU0_SA_CA<6>
  215  M_H_CPU0_SA_CA<5>  CA5_A  @S9S_MB_2U_LIB.S9S_MB_2U(SCH_1):M_H_CPU0_SA_CA<5>
   70  M_H_CPU0_SA_CA<4>  CA4_A  @S9S_MB_2U_LIB.S9S_MB_2U(SCH_1):M_H_CPU0_SA_CA<4>
  213  M_H_CPU0_SA_CA<3>  CA3_A  @S9S_MB_2U_LIB.S9S_MB_2U(SCH_1):M_H_CPU0_SA_CA<3>
   68  M_H_CPU0_SA_CA<2>  CA2_A  @S9S_MB_2U_LIB.S9S_MB_2U(SCH_1):M_H_CPU0_SA_CA<2>
  211  M_H_CPU0_SA_CA<1>  CA1_A  @S9S_MB_2U_LIB.S9S_MB_2U(SCH_1):M_H_CPU0_SA_CA<1>
   66  M_H_CPU0_SA_CA<0>  CA0_A  @S9S_MB_2U_LIB.S9S_MB_2U(SCH_1):M_H_CPU0_SA_CA<0>
  217  M_H_CPU0_CLK_DP<0>   CK_P  @S9S_MB_2U_LIB.S9S_MB_2U(SCH_1):M_H_CPU0_CLK_DP<0>
  218  M_H_CPU0_CLK_DN<0>   CK_N  @S9S_MB_2U_LIB.S9S_MB_2U(SCH_1):M_H_CPU0_CLK_DN<0>
   62  M_H_CPU0_ALERT_N  ALERT_N  @S9S_MB_2U_LIB.S9S_MB_2U(SCH_1):M_H_CPU0_ALERT_N
    5  I3C_SPD_DDREFGH_CPU0_LVC1_SDA   HSDA  @S9S_MB_2U_LIB.S9S_MB_2U(SCH_1):I3C_SPD_DDREFGH_CPU0_LVC1_SDA
    4  I3C_SPD_DDREFGH_CPU0_LVC1_SCL   HSCL  @S9S_MB_2U_LIB.S9S_MB_2U(SCH_1):I3C_SPD_DDREFGH_CPU0_LVC1_SCL

SCONN288_ADR50001P003C01  I64  J16    [SCONN288_ADR50001P003C01-SCONNA]
  146  P12V_S3_AUX_CPU0_NVDIMM  VIN_BULK2  @S9S_MB_2U_LIB.S9S_MB_2U(SCH_1):P12V_S3_AUX_CPU0_NVDIMM
  145  P12V_S3_AUX_CPU0_NVDIMM  VIN_BULK1  @S9S_MB_2U_LIB.S9S_MB_2U(SCH_1):P12V_S3_AUX_CPU0_NVDIMM
    1  P12V_S3_AUX_CPU0_NVDIMM  VIN_BULK0  @S9S_MB_2U_LIB.S9S_MB_2U(SCH_1):P12V_S3_AUX_CPU0_NVDIMM
  288  GND            VSS126  @S9S_MB_2U_LIB.S9S_MB_2U(SCH_1):GND
  286  GND            VSS125  @S9S_MB_2U_LIB.S9S_MB_2U(SCH_1):GND
  284  GND            VSS124  @S9S_MB_2U_LIB.S9S_MB_2U(SCH_1):GND
  281  GND            VSS123  @S9S_MB_2U_LIB.S9S_MB_2U(SCH_1):GND
  279  GND            VSS122  @S9S_MB_2U_LIB.S9S_MB_2U(SCH_1):GND
  277  GND            VSS121  @S9S_MB_2U_LIB.S9S_MB_2U(SCH_1):GND
  275  GND            VSS120  @S9S_MB_2U_LIB.S9S_MB_2U(SCH_1):GND
  273  GND            VSS119  @S9S_MB_2U_LIB.S9S_MB_2U(SCH_1):GND
  270  GND            VSS118  @S9S_MB_2U_LIB.S9S_MB_2U(SCH_1):GND
  268  GND            VSS117  @S9S_MB_2U_LIB.S9S_MB_2U(SCH_1):GND
  266  GND            VSS116  @S9S_MB_2U_LIB.S9S_MB_2U(SCH_1):GND
  264  GND            VSS115  @S9S_MB_2U_LIB.S9S_MB_2U(SCH_1):GND
  262  GND            VSS114  @S9S_MB_2U_LIB.S9S_MB_2U(SCH_1):GND
  259  GND            VSS113  @S9S_MB_2U_LIB.S9S_MB_2U(SCH_1):GND
  257  GND            VSS112  @S9S_MB_2U_LIB.S9S_MB_2U(SCH_1):GND
  255  GND            VSS111  @S9S_MB_2U_LIB.S9S_MB_2U(SCH_1):GND
  253  GND            VSS110  @S9S_MB_2U_LIB.S9S_MB_2U(SCH_1):GND
  251  GND            VSS109  @S9S_MB_2U_LIB.S9S_MB_2U(SCH_1):GND
  248  GND            VSS108  @S9S_MB_2U_LIB.S9S_MB_2U(SCH_1):GND
  246  GND            VSS107  @S9S_MB_2U_LIB.S9S_MB_2U(SCH_1):GND
  244  GND            VSS106  @S9S_MB_2U_LIB.S9S_MB_2U(SCH_1):GND
  242  GND            VSS105  @S9S_MB_2U_LIB.S9S_MB_2U(SCH_1):GND
  240  GND            VSS104  @S9S_MB_2U_LIB.S9S_MB_2U(SCH_1):GND
  237  GND            VSS103  @S9S_MB_2U_LIB.S9S_MB_2U(SCH_1):GND
  235  GND            VSS102  @S9S_MB_2U_LIB.S9S_MB_2U(SCH_1):GND
  233  GND            VSS101  @S9S_MB_2U_LIB.S9S_MB_2U(SCH_1):GND
  230  GND            VSS100  @S9S_MB_2U_LIB.S9S_MB_2U(SCH_1):GND
  228  GND            VSS99  @S9S_MB_2U_LIB.S9S_MB_2U(SCH_1):GND
  226  GND            VSS98  @S9S_MB_2U_LIB.S9S_MB_2U(SCH_1):GND
  224  GND            VSS97  @S9S_MB_2U_LIB.S9S_MB_2U(SCH_1):GND
  222  GND            VSS96  @S9S_MB_2U_LIB.S9S_MB_2U(SCH_1):GND
  219  GND            VSS95  @S9S_MB_2U_LIB.S9S_MB_2U(SCH_1):GND
  216  GND            VSS94  @S9S_MB_2U_LIB.S9S_MB_2U(SCH_1):GND
  214  GND            VSS93  @S9S_MB_2U_LIB.S9S_MB_2U(SCH_1):GND
  212  GND            VSS92  @S9S_MB_2U_LIB.S9S_MB_2U(SCH_1):GND
  210  GND            VSS91  @S9S_MB_2U_LIB.S9S_MB_2U(SCH_1):GND
  208  GND            VSS90  @S9S_MB_2U_LIB.S9S_MB_2U(SCH_1):GND
  206  GND            VSS89  @S9S_MB_2U_LIB.S9S_MB_2U(SCH_1):GND
  204  GND            VSS88  @S9S_MB_2U_LIB.S9S_MB_2U(SCH_1):GND
  202  GND            VSS87  @S9S_MB_2U_LIB.S9S_MB_2U(SCH_1):GND
  199  GND            VSS86  @S9S_MB_2U_LIB.S9S_MB_2U(SCH_1):GND
  197  GND            VSS85  @S9S_MB_2U_LIB.S9S_MB_2U(SCH_1):GND
  195  GND            VSS84  @S9S_MB_2U_LIB.S9S_MB_2U(SCH_1):GND
  193  GND            VSS83  @S9S_MB_2U_LIB.S9S_MB_2U(SCH_1):GND
  191  GND            VSS82  @S9S_MB_2U_LIB.S9S_MB_2U(SCH_1):GND
  188  GND            VSS81  @S9S_MB_2U_LIB.S9S_MB_2U(SCH_1):GND
  186  GND            VSS80  @S9S_MB_2U_LIB.S9S_MB_2U(SCH_1):GND
  184  GND            VSS79  @S9S_MB_2U_LIB.S9S_MB_2U(SCH_1):GND
  182  GND            VSS78  @S9S_MB_2U_LIB.S9S_MB_2U(SCH_1):GND
  180  GND            VSS77  @S9S_MB_2U_LIB.S9S_MB_2U(SCH_1):GND
  177  GND            VSS76  @S9S_MB_2U_LIB.S9S_MB_2U(SCH_1):GND
  175  GND            VSS75  @S9S_MB_2U_LIB.S9S_MB_2U(SCH_1):GND
  173  GND            VSS74  @S9S_MB_2U_LIB.S9S_MB_2U(SCH_1):GND
  171  GND            VSS73  @S9S_MB_2U_LIB.S9S_MB_2U(SCH_1):GND
  169  GND            VSS72  @S9S_MB_2U_LIB.S9S_MB_2U(SCH_1):GND
  166  GND            VSS71  @S9S_MB_2U_LIB.S9S_MB_2U(SCH_1):GND
  164  GND            VSS70  @S9S_MB_2U_LIB.S9S_MB_2U(SCH_1):GND
  162  GND            VSS69  @S9S_MB_2U_LIB.S9S_MB_2U(SCH_1):GND
  160  GND            VSS68  @S9S_MB_2U_LIB.S9S_MB_2U(SCH_1):GND
  158  GND            VSS67  @S9S_MB_2U_LIB.S9S_MB_2U(SCH_1):GND
  155  GND            VSS66  @S9S_MB_2U_LIB.S9S_MB_2U(SCH_1):GND
  153  GND            VSS65  @S9S_MB_2U_LIB.S9S_MB_2U(SCH_1):GND
  151  GND            VSS64  @S9S_MB_2U_LIB.S9S_MB_2U(SCH_1):GND
  143  GND            VSS63  @S9S_MB_2U_LIB.S9S_MB_2U(SCH_1):GND
  141  GND            VSS62  @S9S_MB_2U_LIB.S9S_MB_2U(SCH_1):GND
  139  GND            VSS61  @S9S_MB_2U_LIB.S9S_MB_2U(SCH_1):GND
  136  GND            VSS60  @S9S_MB_2U_LIB.S9S_MB_2U(SCH_1):GND
  134  GND            VSS59  @S9S_MB_2U_LIB.S9S_MB_2U(SCH_1):GND
  132  GND            VSS58  @S9S_MB_2U_LIB.S9S_MB_2U(SCH_1):GND
  130  GND            VSS57  @S9S_MB_2U_LIB.S9S_MB_2U(SCH_1):GND
  128  GND            VSS56  @S9S_MB_2U_LIB.S9S_MB_2U(SCH_1):GND
  125  GND            VSS55  @S9S_MB_2U_LIB.S9S_MB_2U(SCH_1):GND
  123  GND            VSS54  @S9S_MB_2U_LIB.S9S_MB_2U(SCH_1):GND
  121  GND            VSS53  @S9S_MB_2U_LIB.S9S_MB_2U(SCH_1):GND
  119  GND            VSS52  @S9S_MB_2U_LIB.S9S_MB_2U(SCH_1):GND
  117  GND            VSS51  @S9S_MB_2U_LIB.S9S_MB_2U(SCH_1):GND
  114  GND            VSS50  @S9S_MB_2U_LIB.S9S_MB_2U(SCH_1):GND
  112  GND            VSS49  @S9S_MB_2U_LIB.S9S_MB_2U(SCH_1):GND
  110  GND            VSS48  @S9S_MB_2U_LIB.S9S_MB_2U(SCH_1):GND
  108  GND            VSS47  @S9S_MB_2U_LIB.S9S_MB_2U(SCH_1):GND
  106  GND            VSS46  @S9S_MB_2U_LIB.S9S_MB_2U(SCH_1):GND
  103  GND            VSS45  @S9S_MB_2U_LIB.S9S_MB_2U(SCH_1):GND
  101  GND            VSS44  @S9S_MB_2U_LIB.S9S_MB_2U(SCH_1):GND
   99  GND            VSS43  @S9S_MB_2U_LIB.S9S_MB_2U(SCH_1):GND
   97  GND            VSS42  @S9S_MB_2U_LIB.S9S_MB_2U(SCH_1):GND
   95  GND            VSS41  @S9S_MB_2U_LIB.S9S_MB_2U(SCH_1):GND
   92  GND            VSS40  @S9S_MB_2U_LIB.S9S_MB_2U(SCH_1):GND
   90  GND            VSS39  @S9S_MB_2U_LIB.S9S_MB_2U(SCH_1):GND
   88  GND            VSS38  @S9S_MB_2U_LIB.S9S_MB_2U(SCH_1):GND
   85  GND            VSS37  @S9S_MB_2U_LIB.S9S_MB_2U(SCH_1):GND
   83  GND            VSS36  @S9S_MB_2U_LIB.S9S_MB_2U(SCH_1):GND
   81  GND            VSS35  @S9S_MB_2U_LIB.S9S_MB_2U(SCH_1):GND
   79  GND            VSS34  @S9S_MB_2U_LIB.S9S_MB_2U(SCH_1):GND
   77  GND            VSS33  @S9S_MB_2U_LIB.S9S_MB_2U(SCH_1):GND
   75  GND            VSS32  @S9S_MB_2U_LIB.S9S_MB_2U(SCH_1):GND
   73  GND            VSS31  @S9S_MB_2U_LIB.S9S_MB_2U(SCH_1):GND
   71  GND            VSS30  @S9S_MB_2U_LIB.S9S_MB_2U(SCH_1):GND
   69  GND            VSS29  @S9S_MB_2U_LIB.S9S_MB_2U(SCH_1):GND
   67  GND            VSS28  @S9S_MB_2U_LIB.S9S_MB_2U(SCH_1):GND
   65  GND            VSS27  @S9S_MB_2U_LIB.S9S_MB_2U(SCH_1):GND
   63  GND            VSS26  @S9S_MB_2U_LIB.S9S_MB_2U(SCH_1):GND
   61  GND            VSS25  @S9S_MB_2U_LIB.S9S_MB_2U(SCH_1):GND
   59  GND            VSS24  @S9S_MB_2U_LIB.S9S_MB_2U(SCH_1):GND
   57  GND            VSS23  @S9S_MB_2U_LIB.S9S_MB_2U(SCH_1):GND
   54  GND            VSS22  @S9S_MB_2U_LIB.S9S_MB_2U(SCH_1):GND
   52  GND            VSS21  @S9S_MB_2U_LIB.S9S_MB_2U(SCH_1):GND
   50  GND            VSS20  @S9S_MB_2U_LIB.S9S_MB_2U(SCH_1):GND
   48  GND            VSS19  @S9S_MB_2U_LIB.S9S_MB_2U(SCH_1):GND
   46  GND            VSS18  @S9S_MB_2U_LIB.S9S_MB_2U(SCH_1):GND
   43  GND            VSS17  @S9S_MB_2U_LIB.S9S_MB_2U(SCH_1):GND
   41  GND            VSS16  @S9S_MB_2U_LIB.S9S_MB_2U(SCH_1):GND
   39  GND            VSS15  @S9S_MB_2U_LIB.S9S_MB_2U(SCH_1):GND
   37  GND            VSS14  @S9S_MB_2U_LIB.S9S_MB_2U(SCH_1):GND
   35  GND            VSS13  @S9S_MB_2U_LIB.S9S_MB_2U(SCH_1):GND
   32  GND            VSS12  @S9S_MB_2U_LIB.S9S_MB_2U(SCH_1):GND
   30  GND            VSS11  @S9S_MB_2U_LIB.S9S_MB_2U(SCH_1):GND
   28  GND            VSS10  @S9S_MB_2U_LIB.S9S_MB_2U(SCH_1):GND
   26  GND             VSS9  @S9S_MB_2U_LIB.S9S_MB_2U(SCH_1):GND
   24  GND             VSS8  @S9S_MB_2U_LIB.S9S_MB_2U(SCH_1):GND
   21  GND             VSS7  @S9S_MB_2U_LIB.S9S_MB_2U(SCH_1):GND
   19  GND             VSS6  @S9S_MB_2U_LIB.S9S_MB_2U(SCH_1):GND
   17  GND             VSS5  @S9S_MB_2U_LIB.S9S_MB_2U(SCH_1):GND
   15  GND             VSS4  @S9S_MB_2U_LIB.S9S_MB_2U(SCH_1):GND
   13  GND             VSS3  @S9S_MB_2U_LIB.S9S_MB_2U(SCH_1):GND
   10  GND             VSS2  @S9S_MB_2U_LIB.S9S_MB_2U(SCH_1):GND
    8  GND             VSS1  @S9S_MB_2U_LIB.S9S_MB_2U(SCH_1):GND
    6  GND             VSS0  @S9S_MB_2U_LIB.S9S_MB_2U(SCH_1):GND
   G3  GND               G3  @S9S_MB_2U_LIB.S9S_MB_2U(SCH_1):GND
   G2  GND               G2  @S9S_MB_2U_LIB.S9S_MB_2U(SCH_1):GND
   G1  GND               G1  @S9S_MB_2U_LIB.S9S_MB_2U(SCH_1):GND

SCONN288_ADR50001P003C01  I132  J16    [SCONN288_ADR50001P003C01-SCONNA]
   93  M_H_CPU0_SB_DQS_DP<9>  DQS9_B_P  @S9S_MB_2U_LIB.S9S_MB_2U(SCH_1):M_H_CPU0_SB_DQS_DP<9>
  283  M_H_CPU0_SB_DQS_DP<8>  DQS8_B_P  @S9S_MB_2U_LIB.S9S_MB_2U(SCH_1):M_H_CPU0_SB_DQS_DP<8>
  272  M_H_CPU0_SB_DQS_DP<7>  DQS7_B_P  @S9S_MB_2U_LIB.S9S_MB_2U(SCH_1):M_H_CPU0_SB_DQS_DP<7>
  261  M_H_CPU0_SB_DQS_DP<6>  DQS6_B_P  @S9S_MB_2U_LIB.S9S_MB_2U(SCH_1):M_H_CPU0_SB_DQS_DP<6>
  250  M_H_CPU0_SB_DQS_DP<5>  DQS5_B_P  @S9S_MB_2U_LIB.S9S_MB_2U(SCH_1):M_H_CPU0_SB_DQS_DP<5>
  239  M_H_CPU0_SB_DQS_DP<4>  DQS4_B_P  @S9S_MB_2U_LIB.S9S_MB_2U(SCH_1):M_H_CPU0_SB_DQS_DP<4>
  137  M_H_CPU0_SB_DQS_DP<3>  DQS3_B_P  @S9S_MB_2U_LIB.S9S_MB_2U(SCH_1):M_H_CPU0_SB_DQS_DP<3>
  126  M_H_CPU0_SB_DQS_DP<2>  DQS2_B_P  @S9S_MB_2U_LIB.S9S_MB_2U(SCH_1):M_H_CPU0_SB_DQS_DP<2>
  115  M_H_CPU0_SB_DQS_DP<1>  DQS1_B_P  @S9S_MB_2U_LIB.S9S_MB_2U(SCH_1):M_H_CPU0_SB_DQS_DP<1>
  104  M_H_CPU0_SB_DQS_DP<0>  DQS0_B_P  @S9S_MB_2U_LIB.S9S_MB_2U(SCH_1):M_H_CPU0_SB_DQS_DP<0>
   94  M_H_CPU0_SB_DQS_DN<9>  DQS9_B_N  @S9S_MB_2U_LIB.S9S_MB_2U(SCH_1):M_H_CPU0_SB_DQS_DN<9>
  282  M_H_CPU0_SB_DQS_DN<8>  DQS8_B_N  @S9S_MB_2U_LIB.S9S_MB_2U(SCH_1):M_H_CPU0_SB_DQS_DN<8>
  271  M_H_CPU0_SB_DQS_DN<7>  DQS7_B_N  @S9S_MB_2U_LIB.S9S_MB_2U(SCH_1):M_H_CPU0_SB_DQS_DN<7>
  260  M_H_CPU0_SB_DQS_DN<6>  DQS6_B_N  @S9S_MB_2U_LIB.S9S_MB_2U(SCH_1):M_H_CPU0_SB_DQS_DN<6>
  249  M_H_CPU0_SB_DQS_DN<5>  DQS5_B_N  @S9S_MB_2U_LIB.S9S_MB_2U(SCH_1):M_H_CPU0_SB_DQS_DN<5>
  238  M_H_CPU0_SB_DQS_DN<4>  DQS4_B_N  @S9S_MB_2U_LIB.S9S_MB_2U(SCH_1):M_H_CPU0_SB_DQS_DN<4>
  138  M_H_CPU0_SB_DQS_DN<3>  DQS3_B_N  @S9S_MB_2U_LIB.S9S_MB_2U(SCH_1):M_H_CPU0_SB_DQS_DN<3>
  127  M_H_CPU0_SB_DQS_DN<2>  DQS2_B_N  @S9S_MB_2U_LIB.S9S_MB_2U(SCH_1):M_H_CPU0_SB_DQS_DN<2>
  116  M_H_CPU0_SB_DQS_DN<1>  DQS1_B_N  @S9S_MB_2U_LIB.S9S_MB_2U(SCH_1):M_H_CPU0_SB_DQS_DN<1>
  105  M_H_CPU0_SB_DQS_DN<0>  DQS0_B_N  @S9S_MB_2U_LIB.S9S_MB_2U(SCH_1):M_H_CPU0_SB_DQS_DN<0>
  201  M_H_CPU0_SA_DQS_DP<9>  DQS9_A_P  @S9S_MB_2U_LIB.S9S_MB_2U(SCH_1):M_H_CPU0_SA_DQS_DP<9>
  190  M_H_CPU0_SA_DQS_DP<8>  DQS8_A_P  @S9S_MB_2U_LIB.S9S_MB_2U(SCH_1):M_H_CPU0_SA_DQS_DP<8>
  179  M_H_CPU0_SA_DQS_DP<7>  DQS7_A_P  @S9S_MB_2U_LIB.S9S_MB_2U(SCH_1):M_H_CPU0_SA_DQS_DP<7>
  168  M_H_CPU0_SA_DQS_DP<6>  DQS6_A_P  @S9S_MB_2U_LIB.S9S_MB_2U(SCH_1):M_H_CPU0_SA_DQS_DP<6>
  157  M_H_CPU0_SA_DQS_DP<5>  DQS5_A_P  @S9S_MB_2U_LIB.S9S_MB_2U(SCH_1):M_H_CPU0_SA_DQS_DP<5>
   55  M_H_CPU0_SA_DQS_DP<4>  DQS4_A_P  @S9S_MB_2U_LIB.S9S_MB_2U(SCH_1):M_H_CPU0_SA_DQS_DP<4>
   44  M_H_CPU0_SA_DQS_DP<3>  DQS3_A_P  @S9S_MB_2U_LIB.S9S_MB_2U(SCH_1):M_H_CPU0_SA_DQS_DP<3>
   33  M_H_CPU0_SA_DQS_DP<2>  DQS2_A_P  @S9S_MB_2U_LIB.S9S_MB_2U(SCH_1):M_H_CPU0_SA_DQS_DP<2>
   22  M_H_CPU0_SA_DQS_DP<1>  DQS1_A_P  @S9S_MB_2U_LIB.S9S_MB_2U(SCH_1):M_H_CPU0_SA_DQS_DP<1>
   11  M_H_CPU0_SA_DQS_DP<0>  DQS0_A_P  @S9S_MB_2U_LIB.S9S_MB_2U(SCH_1):M_H_CPU0_SA_DQS_DP<0>
  200  M_H_CPU0_SA_DQS_DN<9>  DQS9_A_N  @S9S_MB_2U_LIB.S9S_MB_2U(SCH_1):M_H_CPU0_SA_DQS_DN<9>
  189  M_H_CPU0_SA_DQS_DN<8>  DQS8_A_N  @S9S_MB_2U_LIB.S9S_MB_2U(SCH_1):M_H_CPU0_SA_DQS_DN<8>
  178  M_H_CPU0_SA_DQS_DN<7>  DQS7_A_N  @S9S_MB_2U_LIB.S9S_MB_2U(SCH_1):M_H_CPU0_SA_DQS_DN<7>
  167  M_H_CPU0_SA_DQS_DN<6>  DQS6_A_N  @S9S_MB_2U_LIB.S9S_MB_2U(SCH_1):M_H_CPU0_SA_DQS_DN<6>
  156  M_H_CPU0_SA_DQS_DN<5>  DQS5_A_N  @S9S_MB_2U_LIB.S9S_MB_2U(SCH_1):M_H_CPU0_SA_DQS_DN<5>
   56  M_H_CPU0_SA_DQS_DN<4>  DQS4_A_N  @S9S_MB_2U_LIB.S9S_MB_2U(SCH_1):M_H_CPU0_SA_DQS_DN<4>
   45  M_H_CPU0_SA_DQS_DN<3>  DQS3_A_N  @S9S_MB_2U_LIB.S9S_MB_2U(SCH_1):M_H_CPU0_SA_DQS_DN<3>
   34  M_H_CPU0_SA_DQS_DN<2>  DQS2_A_N  @S9S_MB_2U_LIB.S9S_MB_2U(SCH_1):M_H_CPU0_SA_DQS_DN<2>
   23  M_H_CPU0_SA_DQS_DN<1>  DQS1_A_N  @S9S_MB_2U_LIB.S9S_MB_2U(SCH_1):M_H_CPU0_SA_DQS_DN<1>
   12  M_H_CPU0_SA_DQS_DN<0>  DQS0_A_N  @S9S_MB_2U_LIB.S9S_MB_2U(SCH_1):M_H_CPU0_SA_DQS_DN<0>

SCONN288_ADR50001P003C01  I6   J16    [SCONN288_ADR50001P003C01-SCONNA]
  232  NC              RFU6  NC
  231  NC              RFU5  NC
  220  NC              RFU4  NC
  150  NC              RFU3  NC
  149  NC              RFU2  NC
  144  NC              RFU1  NC
    2  NC              RFU0  NC
  207  RST_M_GH_CPU0_FPGA_N  RESET_N  @S9S_MB_2U_LIB.S9S_MB_2U(SCH_1):RST_M_GH_CPU0_FPGA_N
  147  PWRGD_CHH_CPU0_DIMM2  PWR_GOOD||FAIL_N  @S9S_MB_2U_LIB.S9S_MB_2U(SCH_1):PWRGD_CHH_CPU0_DIMM2
  148  PD_CHH_CPU0_DIMM2_SAA    HAS  @S9S_MB_2U_LIB.S9S_MB_2U(SCH_1):PD_CHH_CPU0_DIMM2_SAA
    3  P3V3_AUX       VIN_MGMT  @S9S_MB_2U_LIB.S9S_MB_2U(SCH_1):P3V3_AUX
   87  M_H_CPU0_SB_RSP<1>  LBS||RSP_N_B  @S9S_MB_2U_LIB.S9S_MB_2U(SCH_1):M_H_CPU0_SB_RSP<1>
  227  M_H_CPU0_SB_PAR  PAR_B  @S9S_MB_2U_LIB.S9S_MB_2U(SCH_1):M_H_CPU0_SB_PAR
  113  M_H_CPU0_SB_DQ<9>  DQ_B9  @S9S_MB_2U_LIB.S9S_MB_2U(SCH_1):M_H_CPU0_SB_DQ<9>
  111  M_H_CPU0_SB_DQ<8>  DQ_B8  @S9S_MB_2U_LIB.S9S_MB_2U(SCH_1):M_H_CPU0_SB_DQ<8>
  254  M_H_CPU0_SB_DQ<7>  DQ_B7  @S9S_MB_2U_LIB.S9S_MB_2U(SCH_1):M_H_CPU0_SB_DQ<7>
  252  M_H_CPU0_SB_DQ<6>  DQ_B6  @S9S_MB_2U_LIB.S9S_MB_2U(SCH_1):M_H_CPU0_SB_DQ<6>
  109  M_H_CPU0_SB_DQ<5>  DQ_B5  @S9S_MB_2U_LIB.S9S_MB_2U(SCH_1):M_H_CPU0_SB_DQ<5>
  107  M_H_CPU0_SB_DQ<4>  DQ_B4  @S9S_MB_2U_LIB.S9S_MB_2U(SCH_1):M_H_CPU0_SB_DQ<4>
  247  M_H_CPU0_SB_DQ<3>  DQ_B3  @S9S_MB_2U_LIB.S9S_MB_2U(SCH_1):M_H_CPU0_SB_DQ<3>
  287  M_H_CPU0_SB_DQ<31>  DQ_B31  @S9S_MB_2U_LIB.S9S_MB_2U(SCH_1):M_H_CPU0_SB_DQ<31>
  285  M_H_CPU0_SB_DQ<30>  DQ_B30  @S9S_MB_2U_LIB.S9S_MB_2U(SCH_1):M_H_CPU0_SB_DQ<30>
  245  M_H_CPU0_SB_DQ<2>  DQ_B2  @S9S_MB_2U_LIB.S9S_MB_2U(SCH_1):M_H_CPU0_SB_DQ<2>
  142  M_H_CPU0_SB_DQ<29>  DQ_B29  @S9S_MB_2U_LIB.S9S_MB_2U(SCH_1):M_H_CPU0_SB_DQ<29>
  140  M_H_CPU0_SB_DQ<28>  DQ_B28  @S9S_MB_2U_LIB.S9S_MB_2U(SCH_1):M_H_CPU0_SB_DQ<28>
  280  M_H_CPU0_SB_DQ<27>  DQ_B27  @S9S_MB_2U_LIB.S9S_MB_2U(SCH_1):M_H_CPU0_SB_DQ<27>
  278  M_H_CPU0_SB_DQ<26>  DQ_B26  @S9S_MB_2U_LIB.S9S_MB_2U(SCH_1):M_H_CPU0_SB_DQ<26>
  135  M_H_CPU0_SB_DQ<25>  DQ_B25  @S9S_MB_2U_LIB.S9S_MB_2U(SCH_1):M_H_CPU0_SB_DQ<25>
  133  M_H_CPU0_SB_DQ<24>  DQ_B24  @S9S_MB_2U_LIB.S9S_MB_2U(SCH_1):M_H_CPU0_SB_DQ<24>
  276  M_H_CPU0_SB_DQ<23>  DQ_B23  @S9S_MB_2U_LIB.S9S_MB_2U(SCH_1):M_H_CPU0_SB_DQ<23>
  274  M_H_CPU0_SB_DQ<22>  DQ_B22  @S9S_MB_2U_LIB.S9S_MB_2U(SCH_1):M_H_CPU0_SB_DQ<22>
  131  M_H_CPU0_SB_DQ<21>  DQ_B21  @S9S_MB_2U_LIB.S9S_MB_2U(SCH_1):M_H_CPU0_SB_DQ<21>
  129  M_H_CPU0_SB_DQ<20>  DQ_B20  @S9S_MB_2U_LIB.S9S_MB_2U(SCH_1):M_H_CPU0_SB_DQ<20>
  102  M_H_CPU0_SB_DQ<1>  DQ_B1  @S9S_MB_2U_LIB.S9S_MB_2U(SCH_1):M_H_CPU0_SB_DQ<1>
  269  M_H_CPU0_SB_DQ<19>  DQ_B19  @S9S_MB_2U_LIB.S9S_MB_2U(SCH_1):M_H_CPU0_SB_DQ<19>
  267  M_H_CPU0_SB_DQ<18>  DQ_B18  @S9S_MB_2U_LIB.S9S_MB_2U(SCH_1):M_H_CPU0_SB_DQ<18>
  124  M_H_CPU0_SB_DQ<17>  DQ_B17  @S9S_MB_2U_LIB.S9S_MB_2U(SCH_1):M_H_CPU0_SB_DQ<17>
  122  M_H_CPU0_SB_DQ<16>  DQ_B16  @S9S_MB_2U_LIB.S9S_MB_2U(SCH_1):M_H_CPU0_SB_DQ<16>
  265  M_H_CPU0_SB_DQ<15>  DQ_B15  @S9S_MB_2U_LIB.S9S_MB_2U(SCH_1):M_H_CPU0_SB_DQ<15>
  263  M_H_CPU0_SB_DQ<14>  DQ_B14  @S9S_MB_2U_LIB.S9S_MB_2U(SCH_1):M_H_CPU0_SB_DQ<14>
  120  M_H_CPU0_SB_DQ<13>  DQ_B13  @S9S_MB_2U_LIB.S9S_MB_2U(SCH_1):M_H_CPU0_SB_DQ<13>
  118  M_H_CPU0_SB_DQ<12>  DQ_B12  @S9S_MB_2U_LIB.S9S_MB_2U(SCH_1):M_H_CPU0_SB_DQ<12>
  258  M_H_CPU0_SB_DQ<11>  DQ_B11  @S9S_MB_2U_LIB.S9S_MB_2U(SCH_1):M_H_CPU0_SB_DQ<11>
  256  M_H_CPU0_SB_DQ<10>  DQ_B10  @S9S_MB_2U_LIB.S9S_MB_2U(SCH_1):M_H_CPU0_SB_DQ<10>
  100  M_H_CPU0_SB_DQ<0>  DQ_B0  @S9S_MB_2U_LIB.S9S_MB_2U(SCH_1):M_H_CPU0_SB_DQ<0>
  229  M_H_CPU0_SB_CS_N<3>  CS1_N_B  @S9S_MB_2U_LIB.S9S_MB_2U(SCH_1):M_H_CPU0_SB_CS_N<3>
   84  M_H_CPU0_SB_CS_N<2>  CS0_N_B  @S9S_MB_2U_LIB.S9S_MB_2U(SCH_1):M_H_CPU0_SB_CS_N<2>
  236  M_H_CPU0_SB_CB<7>  CB_B7  @S9S_MB_2U_LIB.S9S_MB_2U(SCH_1):M_H_CPU0_SB_CB<7>
  234  M_H_CPU0_SB_CB<6>  CB_B6  @S9S_MB_2U_LIB.S9S_MB_2U(SCH_1):M_H_CPU0_SB_CB<6>
   91  M_H_CPU0_SB_CB<5>  CB_B5  @S9S_MB_2U_LIB.S9S_MB_2U(SCH_1):M_H_CPU0_SB_CB<5>
   89  M_H_CPU0_SB_CB<4>  CB_B4  @S9S_MB_2U_LIB.S9S_MB_2U(SCH_1):M_H_CPU0_SB_CB<4>
  243  M_H_CPU0_SB_CB<3>  CB_B3  @S9S_MB_2U_LIB.S9S_MB_2U(SCH_1):M_H_CPU0_SB_CB<3>
  241  M_H_CPU0_SB_CB<2>  CB_B2  @S9S_MB_2U_LIB.S9S_MB_2U(SCH_1):M_H_CPU0_SB_CB<2>
   98  M_H_CPU0_SB_CB<1>  CB_B1  @S9S_MB_2U_LIB.S9S_MB_2U(SCH_1):M_H_CPU0_SB_CB<1>
   96  M_H_CPU0_SB_CB<0>  CB_B0  @S9S_MB_2U_LIB.S9S_MB_2U(SCH_1):M_H_CPU0_SB_CB<0>
   82  M_H_CPU0_SB_CA<6>  CA6_B  @S9S_MB_2U_LIB.S9S_MB_2U(SCH_1):M_H_CPU0_SB_CA<6>
  225  M_H_CPU0_SB_CA<5>  CA5_B  @S9S_MB_2U_LIB.S9S_MB_2U(SCH_1):M_H_CPU0_SB_CA<5>
   80  M_H_CPU0_SB_CA<4>  CA4_B  @S9S_MB_2U_LIB.S9S_MB_2U(SCH_1):M_H_CPU0_SB_CA<4>
  223  M_H_CPU0_SB_CA<3>  CA3_B  @S9S_MB_2U_LIB.S9S_MB_2U(SCH_1):M_H_CPU0_SB_CA<3>
   78  M_H_CPU0_SB_CA<2>  CA2_B  @S9S_MB_2U_LIB.S9S_MB_2U(SCH_1):M_H_CPU0_SB_CA<2>
  221  M_H_CPU0_SB_CA<1>  CA1_B  @S9S_MB_2U_LIB.S9S_MB_2U(SCH_1):M_H_CPU0_SB_CA<1>
   76  M_H_CPU0_SB_CA<0>  CA0_B  @S9S_MB_2U_LIB.S9S_MB_2U(SCH_1):M_H_CPU0_SB_CA<0>
   86  M_H_CPU0_SA_RSP<1>  LBD||RSP_N_A  @S9S_MB_2U_LIB.S9S_MB_2U(SCH_1):M_H_CPU0_SA_RSP<1>
   74  M_H_CPU0_SA_PAR  PAR_A  @S9S_MB_2U_LIB.S9S_MB_2U(SCH_1):M_H_CPU0_SA_PAR
   20  M_H_CPU0_SA_DQ<9>  DQ_A9  @S9S_MB_2U_LIB.S9S_MB_2U(SCH_1):M_H_CPU0_SA_DQ<9>
   18  M_H_CPU0_SA_DQ<8>  DQ_A8  @S9S_MB_2U_LIB.S9S_MB_2U(SCH_1):M_H_CPU0_SA_DQ<8>
  161  M_H_CPU0_SA_DQ<7>  DQ_A7  @S9S_MB_2U_LIB.S9S_MB_2U(SCH_1):M_H_CPU0_SA_DQ<7>
  159  M_H_CPU0_SA_DQ<6>  DQ_A6  @S9S_MB_2U_LIB.S9S_MB_2U(SCH_1):M_H_CPU0_SA_DQ<6>
   16  M_H_CPU0_SA_DQ<5>  DQ_A5  @S9S_MB_2U_LIB.S9S_MB_2U(SCH_1):M_H_CPU0_SA_DQ<5>
   14  M_H_CPU0_SA_DQ<4>  DQ_A4  @S9S_MB_2U_LIB.S9S_MB_2U(SCH_1):M_H_CPU0_SA_DQ<4>
  154  M_H_CPU0_SA_DQ<3>  DQ_A3  @S9S_MB_2U_LIB.S9S_MB_2U(SCH_1):M_H_CPU0_SA_DQ<3>
  194  M_H_CPU0_SA_DQ<31>  DQ_A31  @S9S_MB_2U_LIB.S9S_MB_2U(SCH_1):M_H_CPU0_SA_DQ<31>
  192  M_H_CPU0_SA_DQ<30>  DQ_A30  @S9S_MB_2U_LIB.S9S_MB_2U(SCH_1):M_H_CPU0_SA_DQ<30>
  152  M_H_CPU0_SA_DQ<2>  DQ_A2  @S9S_MB_2U_LIB.S9S_MB_2U(SCH_1):M_H_CPU0_SA_DQ<2>
   49  M_H_CPU0_SA_DQ<29>  DQ_A29  @S9S_MB_2U_LIB.S9S_MB_2U(SCH_1):M_H_CPU0_SA_DQ<29>
   47  M_H_CPU0_SA_DQ<28>  DQ_A28  @S9S_MB_2U_LIB.S9S_MB_2U(SCH_1):M_H_CPU0_SA_DQ<28>
  187  M_H_CPU0_SA_DQ<27>  DQ_A27  @S9S_MB_2U_LIB.S9S_MB_2U(SCH_1):M_H_CPU0_SA_DQ<27>
  185  M_H_CPU0_SA_DQ<26>  DQ_A26  @S9S_MB_2U_LIB.S9S_MB_2U(SCH_1):M_H_CPU0_SA_DQ<26>
   42  M_H_CPU0_SA_DQ<25>  DQ_A25  @S9S_MB_2U_LIB.S9S_MB_2U(SCH_1):M_H_CPU0_SA_DQ<25>
   40  M_H_CPU0_SA_DQ<24>  DQ_A24  @S9S_MB_2U_LIB.S9S_MB_2U(SCH_1):M_H_CPU0_SA_DQ<24>
  183  M_H_CPU0_SA_DQ<23>  DQ_A23  @S9S_MB_2U_LIB.S9S_MB_2U(SCH_1):M_H_CPU0_SA_DQ<23>
  181  M_H_CPU0_SA_DQ<22>  DQ_A22  @S9S_MB_2U_LIB.S9S_MB_2U(SCH_1):M_H_CPU0_SA_DQ<22>
   38  M_H_CPU0_SA_DQ<21>  DQ_A21  @S9S_MB_2U_LIB.S9S_MB_2U(SCH_1):M_H_CPU0_SA_DQ<21>
   36  M_H_CPU0_SA_DQ<20>  DQ_A20  @S9S_MB_2U_LIB.S9S_MB_2U(SCH_1):M_H_CPU0_SA_DQ<20>
    9  M_H_CPU0_SA_DQ<1>  DQ_A1  @S9S_MB_2U_LIB.S9S_MB_2U(SCH_1):M_H_CPU0_SA_DQ<1>
  176  M_H_CPU0_SA_DQ<19>  DQ_A19  @S9S_MB_2U_LIB.S9S_MB_2U(SCH_1):M_H_CPU0_SA_DQ<19>
  174  M_H_CPU0_SA_DQ<18>  DQ_A18  @S9S_MB_2U_LIB.S9S_MB_2U(SCH_1):M_H_CPU0_SA_DQ<18>
   31  M_H_CPU0_SA_DQ<17>  DQ_A17  @S9S_MB_2U_LIB.S9S_MB_2U(SCH_1):M_H_CPU0_SA_DQ<17>
   29  M_H_CPU0_SA_DQ<16>  DQ_A16  @S9S_MB_2U_LIB.S9S_MB_2U(SCH_1):M_H_CPU0_SA_DQ<16>
  172  M_H_CPU0_SA_DQ<15>  DQ_A15  @S9S_MB_2U_LIB.S9S_MB_2U(SCH_1):M_H_CPU0_SA_DQ<15>
  170  M_H_CPU0_SA_DQ<14>  DQ_A14  @S9S_MB_2U_LIB.S9S_MB_2U(SCH_1):M_H_CPU0_SA_DQ<14>
   27  M_H_CPU0_SA_DQ<13>  DQ_A13  @S9S_MB_2U_LIB.S9S_MB_2U(SCH_1):M_H_CPU0_SA_DQ<13>
   25  M_H_CPU0_SA_DQ<12>  DQ_A12  @S9S_MB_2U_LIB.S9S_MB_2U(SCH_1):M_H_CPU0_SA_DQ<12>
  165  M_H_CPU0_SA_DQ<11>  DQ_A11  @S9S_MB_2U_LIB.S9S_MB_2U(SCH_1):M_H_CPU0_SA_DQ<11>
  163  M_H_CPU0_SA_DQ<10>  DQ_A10  @S9S_MB_2U_LIB.S9S_MB_2U(SCH_1):M_H_CPU0_SA_DQ<10>
    7  M_H_CPU0_SA_DQ<0>  DQ_A0  @S9S_MB_2U_LIB.S9S_MB_2U(SCH_1):M_H_CPU0_SA_DQ<0>
  209  M_H_CPU0_SA_CS_N<3>  CS1_N_A  @S9S_MB_2U_LIB.S9S_MB_2U(SCH_1):M_H_CPU0_SA_CS_N<3>
   64  M_H_CPU0_SA_CS_N<2>  CS0_N_A  @S9S_MB_2U_LIB.S9S_MB_2U(SCH_1):M_H_CPU0_SA_CS_N<2>
  205  M_H_CPU0_SA_CB<7>  CB_A7  @S9S_MB_2U_LIB.S9S_MB_2U(SCH_1):M_H_CPU0_SA_CB<7>
  203  M_H_CPU0_SA_CB<6>  CB_A6  @S9S_MB_2U_LIB.S9S_MB_2U(SCH_1):M_H_CPU0_SA_CB<6>
   60  M_H_CPU0_SA_CB<5>  CB_A5  @S9S_MB_2U_LIB.S9S_MB_2U(SCH_1):M_H_CPU0_SA_CB<5>
   58  M_H_CPU0_SA_CB<4>  CB_A4  @S9S_MB_2U_LIB.S9S_MB_2U(SCH_1):M_H_CPU0_SA_CB<4>
  198  M_H_CPU0_SA_CB<3>  CB_A3  @S9S_MB_2U_LIB.S9S_MB_2U(SCH_1):M_H_CPU0_SA_CB<3>
  196  M_H_CPU0_SA_CB<2>  CB_A2  @S9S_MB_2U_LIB.S9S_MB_2U(SCH_1):M_H_CPU0_SA_CB<2>
   53  M_H_CPU0_SA_CB<1>  CB_A1  @S9S_MB_2U_LIB.S9S_MB_2U(SCH_1):M_H_CPU0_SA_CB<1>
   51  M_H_CPU0_SA_CB<0>  CB_A0  @S9S_MB_2U_LIB.S9S_MB_2U(SCH_1):M_H_CPU0_SA_CB<0>
   72  M_H_CPU0_SA_CA<6>  CA6_A  @S9S_MB_2U_LIB.S9S_MB_2U(SCH_1):M_H_CPU0_SA_CA<6>
  215  M_H_CPU0_SA_CA<5>  CA5_A  @S9S_MB_2U_LIB.S9S_MB_2U(SCH_1):M_H_CPU0_SA_CA<5>
   70  M_H_CPU0_SA_CA<4>  CA4_A  @S9S_MB_2U_LIB.S9S_MB_2U(SCH_1):M_H_CPU0_SA_CA<4>
  213  M_H_CPU0_SA_CA<3>  CA3_A  @S9S_MB_2U_LIB.S9S_MB_2U(SCH_1):M_H_CPU0_SA_CA<3>
   68  M_H_CPU0_SA_CA<2>  CA2_A  @S9S_MB_2U_LIB.S9S_MB_2U(SCH_1):M_H_CPU0_SA_CA<2>
  211  M_H_CPU0_SA_CA<1>  CA1_A  @S9S_MB_2U_LIB.S9S_MB_2U(SCH_1):M_H_CPU0_SA_CA<1>
   66  M_H_CPU0_SA_CA<0>  CA0_A  @S9S_MB_2U_LIB.S9S_MB_2U(SCH_1):M_H_CPU0_SA_CA<0>
  217  M_H_CPU0_CLK_DP<1>   CK_P  @S9S_MB_2U_LIB.S9S_MB_2U(SCH_1):M_H_CPU0_CLK_DP<1>
  218  M_H_CPU0_CLK_DN<1>   CK_N  @S9S_MB_2U_LIB.S9S_MB_2U(SCH_1):M_H_CPU0_CLK_DN<1>
   62  M_H_CPU0_ALERT_N  ALERT_N  @S9S_MB_2U_LIB.S9S_MB_2U(SCH_1):M_H_CPU0_ALERT_N
    5  I3C_SPD_DDREFGH_CPU0_LVC1_SDA   HSDA  @S9S_MB_2U_LIB.S9S_MB_2U(SCH_1):I3C_SPD_DDREFGH_CPU0_LVC1_SDA
    4  I3C_SPD_DDREFGH_CPU0_LVC1_SCL   HSCL  @S9S_MB_2U_LIB.S9S_MB_2U(SCH_1):I3C_SPD_DDREFGH_CPU0_LVC1_SCL

SCONN288_ADR50001P013C01  I147  J17    [SCONN288_ADR50001P013C01-SCONNA]
  146  P12V_S3_AUX_CPU1_NVDIMM  VIN_BULK2  @S9S_MB_2U_LIB.S9S_MB_2U(SCH_1):P12V_S3_AUX_CPU1_NVDIMM
  145  P12V_S3_AUX_CPU1_NVDIMM  VIN_BULK1  @S9S_MB_2U_LIB.S9S_MB_2U(SCH_1):P12V_S3_AUX_CPU1_NVDIMM
    1  P12V_S3_AUX_CPU1_NVDIMM  VIN_BULK0  @S9S_MB_2U_LIB.S9S_MB_2U(SCH_1):P12V_S3_AUX_CPU1_NVDIMM
  288  GND            VSS126  @S9S_MB_2U_LIB.S9S_MB_2U(SCH_1):GND
  286  GND            VSS125  @S9S_MB_2U_LIB.S9S_MB_2U(SCH_1):GND
  284  GND            VSS124  @S9S_MB_2U_LIB.S9S_MB_2U(SCH_1):GND
  281  GND            VSS123  @S9S_MB_2U_LIB.S9S_MB_2U(SCH_1):GND
  279  GND            VSS122  @S9S_MB_2U_LIB.S9S_MB_2U(SCH_1):GND
  277  GND            VSS121  @S9S_MB_2U_LIB.S9S_MB_2U(SCH_1):GND
  275  GND            VSS120  @S9S_MB_2U_LIB.S9S_MB_2U(SCH_1):GND
  273  GND            VSS119  @S9S_MB_2U_LIB.S9S_MB_2U(SCH_1):GND
  270  GND            VSS118  @S9S_MB_2U_LIB.S9S_MB_2U(SCH_1):GND
  268  GND            VSS117  @S9S_MB_2U_LIB.S9S_MB_2U(SCH_1):GND
  266  GND            VSS116  @S9S_MB_2U_LIB.S9S_MB_2U(SCH_1):GND
  264  GND            VSS115  @S9S_MB_2U_LIB.S9S_MB_2U(SCH_1):GND
  262  GND            VSS114  @S9S_MB_2U_LIB.S9S_MB_2U(SCH_1):GND
  259  GND            VSS113  @S9S_MB_2U_LIB.S9S_MB_2U(SCH_1):GND
  257  GND            VSS112  @S9S_MB_2U_LIB.S9S_MB_2U(SCH_1):GND
  255  GND            VSS111  @S9S_MB_2U_LIB.S9S_MB_2U(SCH_1):GND
  253  GND            VSS110  @S9S_MB_2U_LIB.S9S_MB_2U(SCH_1):GND
  251  GND            VSS109  @S9S_MB_2U_LIB.S9S_MB_2U(SCH_1):GND
  248  GND            VSS108  @S9S_MB_2U_LIB.S9S_MB_2U(SCH_1):GND
  246  GND            VSS107  @S9S_MB_2U_LIB.S9S_MB_2U(SCH_1):GND
  244  GND            VSS106  @S9S_MB_2U_LIB.S9S_MB_2U(SCH_1):GND
  242  GND            VSS105  @S9S_MB_2U_LIB.S9S_MB_2U(SCH_1):GND
  240  GND            VSS104  @S9S_MB_2U_LIB.S9S_MB_2U(SCH_1):GND
  237  GND            VSS103  @S9S_MB_2U_LIB.S9S_MB_2U(SCH_1):GND
  235  GND            VSS102  @S9S_MB_2U_LIB.S9S_MB_2U(SCH_1):GND
  233  GND            VSS101  @S9S_MB_2U_LIB.S9S_MB_2U(SCH_1):GND
  230  GND            VSS100  @S9S_MB_2U_LIB.S9S_MB_2U(SCH_1):GND
  228  GND            VSS99  @S9S_MB_2U_LIB.S9S_MB_2U(SCH_1):GND
  226  GND            VSS98  @S9S_MB_2U_LIB.S9S_MB_2U(SCH_1):GND
  224  GND            VSS97  @S9S_MB_2U_LIB.S9S_MB_2U(SCH_1):GND
  222  GND            VSS96  @S9S_MB_2U_LIB.S9S_MB_2U(SCH_1):GND
  219  GND            VSS95  @S9S_MB_2U_LIB.S9S_MB_2U(SCH_1):GND
  216  GND            VSS94  @S9S_MB_2U_LIB.S9S_MB_2U(SCH_1):GND
  214  GND            VSS93  @S9S_MB_2U_LIB.S9S_MB_2U(SCH_1):GND
  212  GND            VSS92  @S9S_MB_2U_LIB.S9S_MB_2U(SCH_1):GND
  210  GND            VSS91  @S9S_MB_2U_LIB.S9S_MB_2U(SCH_1):GND
  208  GND            VSS90  @S9S_MB_2U_LIB.S9S_MB_2U(SCH_1):GND
  206  GND            VSS89  @S9S_MB_2U_LIB.S9S_MB_2U(SCH_1):GND
  204  GND            VSS88  @S9S_MB_2U_LIB.S9S_MB_2U(SCH_1):GND
  202  GND            VSS87  @S9S_MB_2U_LIB.S9S_MB_2U(SCH_1):GND
  199  GND            VSS86  @S9S_MB_2U_LIB.S9S_MB_2U(SCH_1):GND
  197  GND            VSS85  @S9S_MB_2U_LIB.S9S_MB_2U(SCH_1):GND
  195  GND            VSS84  @S9S_MB_2U_LIB.S9S_MB_2U(SCH_1):GND
  193  GND            VSS83  @S9S_MB_2U_LIB.S9S_MB_2U(SCH_1):GND
  191  GND            VSS82  @S9S_MB_2U_LIB.S9S_MB_2U(SCH_1):GND
  188  GND            VSS81  @S9S_MB_2U_LIB.S9S_MB_2U(SCH_1):GND
  186  GND            VSS80  @S9S_MB_2U_LIB.S9S_MB_2U(SCH_1):GND
  184  GND            VSS79  @S9S_MB_2U_LIB.S9S_MB_2U(SCH_1):GND
  182  GND            VSS78  @S9S_MB_2U_LIB.S9S_MB_2U(SCH_1):GND
  180  GND            VSS77  @S9S_MB_2U_LIB.S9S_MB_2U(SCH_1):GND
  177  GND            VSS76  @S9S_MB_2U_LIB.S9S_MB_2U(SCH_1):GND
  175  GND            VSS75  @S9S_MB_2U_LIB.S9S_MB_2U(SCH_1):GND
  173  GND            VSS74  @S9S_MB_2U_LIB.S9S_MB_2U(SCH_1):GND
  171  GND            VSS73  @S9S_MB_2U_LIB.S9S_MB_2U(SCH_1):GND
  169  GND            VSS72  @S9S_MB_2U_LIB.S9S_MB_2U(SCH_1):GND
  166  GND            VSS71  @S9S_MB_2U_LIB.S9S_MB_2U(SCH_1):GND
  164  GND            VSS70  @S9S_MB_2U_LIB.S9S_MB_2U(SCH_1):GND
  162  GND            VSS69  @S9S_MB_2U_LIB.S9S_MB_2U(SCH_1):GND
  160  GND            VSS68  @S9S_MB_2U_LIB.S9S_MB_2U(SCH_1):GND
  158  GND            VSS67  @S9S_MB_2U_LIB.S9S_MB_2U(SCH_1):GND
  155  GND            VSS66  @S9S_MB_2U_LIB.S9S_MB_2U(SCH_1):GND
  153  GND            VSS65  @S9S_MB_2U_LIB.S9S_MB_2U(SCH_1):GND
  151  GND            VSS64  @S9S_MB_2U_LIB.S9S_MB_2U(SCH_1):GND
  143  GND            VSS63  @S9S_MB_2U_LIB.S9S_MB_2U(SCH_1):GND
  141  GND            VSS62  @S9S_MB_2U_LIB.S9S_MB_2U(SCH_1):GND
  139  GND            VSS61  @S9S_MB_2U_LIB.S9S_MB_2U(SCH_1):GND
  136  GND            VSS60  @S9S_MB_2U_LIB.S9S_MB_2U(SCH_1):GND
  134  GND            VSS59  @S9S_MB_2U_LIB.S9S_MB_2U(SCH_1):GND
  132  GND            VSS58  @S9S_MB_2U_LIB.S9S_MB_2U(SCH_1):GND
  130  GND            VSS57  @S9S_MB_2U_LIB.S9S_MB_2U(SCH_1):GND
  128  GND            VSS56  @S9S_MB_2U_LIB.S9S_MB_2U(SCH_1):GND
  125  GND            VSS55  @S9S_MB_2U_LIB.S9S_MB_2U(SCH_1):GND
  123  GND            VSS54  @S9S_MB_2U_LIB.S9S_MB_2U(SCH_1):GND
  121  GND            VSS53  @S9S_MB_2U_LIB.S9S_MB_2U(SCH_1):GND
  119  GND            VSS52  @S9S_MB_2U_LIB.S9S_MB_2U(SCH_1):GND
  117  GND            VSS51  @S9S_MB_2U_LIB.S9S_MB_2U(SCH_1):GND
  114  GND            VSS50  @S9S_MB_2U_LIB.S9S_MB_2U(SCH_1):GND
  112  GND            VSS49  @S9S_MB_2U_LIB.S9S_MB_2U(SCH_1):GND
  110  GND            VSS48  @S9S_MB_2U_LIB.S9S_MB_2U(SCH_1):GND
  108  GND            VSS47  @S9S_MB_2U_LIB.S9S_MB_2U(SCH_1):GND
  106  GND            VSS46  @S9S_MB_2U_LIB.S9S_MB_2U(SCH_1):GND
  103  GND            VSS45  @S9S_MB_2U_LIB.S9S_MB_2U(SCH_1):GND
  101  GND            VSS44  @S9S_MB_2U_LIB.S9S_MB_2U(SCH_1):GND
   99  GND            VSS43  @S9S_MB_2U_LIB.S9S_MB_2U(SCH_1):GND
   97  GND            VSS42  @S9S_MB_2U_LIB.S9S_MB_2U(SCH_1):GND
   95  GND            VSS41  @S9S_MB_2U_LIB.S9S_MB_2U(SCH_1):GND
   92  GND            VSS40  @S9S_MB_2U_LIB.S9S_MB_2U(SCH_1):GND
   90  GND            VSS39  @S9S_MB_2U_LIB.S9S_MB_2U(SCH_1):GND
   88  GND            VSS38  @S9S_MB_2U_LIB.S9S_MB_2U(SCH_1):GND
   85  GND            VSS37  @S9S_MB_2U_LIB.S9S_MB_2U(SCH_1):GND
   83  GND            VSS36  @S9S_MB_2U_LIB.S9S_MB_2U(SCH_1):GND
   81  GND            VSS35  @S9S_MB_2U_LIB.S9S_MB_2U(SCH_1):GND
   79  GND            VSS34  @S9S_MB_2U_LIB.S9S_MB_2U(SCH_1):GND
   77  GND            VSS33  @S9S_MB_2U_LIB.S9S_MB_2U(SCH_1):GND
   75  GND            VSS32  @S9S_MB_2U_LIB.S9S_MB_2U(SCH_1):GND
   73  GND            VSS31  @S9S_MB_2U_LIB.S9S_MB_2U(SCH_1):GND
   71  GND            VSS30  @S9S_MB_2U_LIB.S9S_MB_2U(SCH_1):GND
   69  GND            VSS29  @S9S_MB_2U_LIB.S9S_MB_2U(SCH_1):GND
   67  GND            VSS28  @S9S_MB_2U_LIB.S9S_MB_2U(SCH_1):GND
   65  GND            VSS27  @S9S_MB_2U_LIB.S9S_MB_2U(SCH_1):GND
   63  GND            VSS26  @S9S_MB_2U_LIB.S9S_MB_2U(SCH_1):GND
   61  GND            VSS25  @S9S_MB_2U_LIB.S9S_MB_2U(SCH_1):GND
   59  GND            VSS24  @S9S_MB_2U_LIB.S9S_MB_2U(SCH_1):GND
   57  GND            VSS23  @S9S_MB_2U_LIB.S9S_MB_2U(SCH_1):GND
   54  GND            VSS22  @S9S_MB_2U_LIB.S9S_MB_2U(SCH_1):GND
   52  GND            VSS21  @S9S_MB_2U_LIB.S9S_MB_2U(SCH_1):GND
   50  GND            VSS20  @S9S_MB_2U_LIB.S9S_MB_2U(SCH_1):GND
   48  GND            VSS19  @S9S_MB_2U_LIB.S9S_MB_2U(SCH_1):GND
   46  GND            VSS18  @S9S_MB_2U_LIB.S9S_MB_2U(SCH_1):GND
   43  GND            VSS17  @S9S_MB_2U_LIB.S9S_MB_2U(SCH_1):GND
   41  GND            VSS16  @S9S_MB_2U_LIB.S9S_MB_2U(SCH_1):GND
   39  GND            VSS15  @S9S_MB_2U_LIB.S9S_MB_2U(SCH_1):GND
   37  GND            VSS14  @S9S_MB_2U_LIB.S9S_MB_2U(SCH_1):GND
   35  GND            VSS13  @S9S_MB_2U_LIB.S9S_MB_2U(SCH_1):GND
   32  GND            VSS12  @S9S_MB_2U_LIB.S9S_MB_2U(SCH_1):GND
   30  GND            VSS11  @S9S_MB_2U_LIB.S9S_MB_2U(SCH_1):GND
   28  GND            VSS10  @S9S_MB_2U_LIB.S9S_MB_2U(SCH_1):GND
   26  GND             VSS9  @S9S_MB_2U_LIB.S9S_MB_2U(SCH_1):GND
   24  GND             VSS8  @S9S_MB_2U_LIB.S9S_MB_2U(SCH_1):GND
   21  GND             VSS7  @S9S_MB_2U_LIB.S9S_MB_2U(SCH_1):GND
   19  GND             VSS6  @S9S_MB_2U_LIB.S9S_MB_2U(SCH_1):GND
   17  GND             VSS5  @S9S_MB_2U_LIB.S9S_MB_2U(SCH_1):GND
   15  GND             VSS4  @S9S_MB_2U_LIB.S9S_MB_2U(SCH_1):GND
   13  GND             VSS3  @S9S_MB_2U_LIB.S9S_MB_2U(SCH_1):GND
   10  GND             VSS2  @S9S_MB_2U_LIB.S9S_MB_2U(SCH_1):GND
    8  GND             VSS1  @S9S_MB_2U_LIB.S9S_MB_2U(SCH_1):GND
    6  GND             VSS0  @S9S_MB_2U_LIB.S9S_MB_2U(SCH_1):GND
   G3  GND               G3  @S9S_MB_2U_LIB.S9S_MB_2U(SCH_1):GND
   G2  GND               G2  @S9S_MB_2U_LIB.S9S_MB_2U(SCH_1):GND
   G1  GND               G1  @S9S_MB_2U_LIB.S9S_MB_2U(SCH_1):GND

SCONN288_ADR50001P013C01  I126  J17    [SCONN288_ADR50001P013C01-SCONNA]
   93  M_A_CPU1_SB_DQS_DP<9>  DQS9_B_P  @S9S_MB_2U_LIB.S9S_MB_2U(SCH_1):M_A_CPU1_SB_DQS_DP<9>
  283  M_A_CPU1_SB_DQS_DP<8>  DQS8_B_P  @S9S_MB_2U_LIB.S9S_MB_2U(SCH_1):M_A_CPU1_SB_DQS_DP<8>
  272  M_A_CPU1_SB_DQS_DP<7>  DQS7_B_P  @S9S_MB_2U_LIB.S9S_MB_2U(SCH_1):M_A_CPU1_SB_DQS_DP<7>
  261  M_A_CPU1_SB_DQS_DP<6>  DQS6_B_P  @S9S_MB_2U_LIB.S9S_MB_2U(SCH_1):M_A_CPU1_SB_DQS_DP<6>
  250  M_A_CPU1_SB_DQS_DP<5>  DQS5_B_P  @S9S_MB_2U_LIB.S9S_MB_2U(SCH_1):M_A_CPU1_SB_DQS_DP<5>
  239  M_A_CPU1_SB_DQS_DP<4>  DQS4_B_P  @S9S_MB_2U_LIB.S9S_MB_2U(SCH_1):M_A_CPU1_SB_DQS_DP<4>
  137  M_A_CPU1_SB_DQS_DP<3>  DQS3_B_P  @S9S_MB_2U_LIB.S9S_MB_2U(SCH_1):M_A_CPU1_SB_DQS_DP<3>
  126  M_A_CPU1_SB_DQS_DP<2>  DQS2_B_P  @S9S_MB_2U_LIB.S9S_MB_2U(SCH_1):M_A_CPU1_SB_DQS_DP<2>
  115  M_A_CPU1_SB_DQS_DP<1>  DQS1_B_P  @S9S_MB_2U_LIB.S9S_MB_2U(SCH_1):M_A_CPU1_SB_DQS_DP<1>
  104  M_A_CPU1_SB_DQS_DP<0>  DQS0_B_P  @S9S_MB_2U_LIB.S9S_MB_2U(SCH_1):M_A_CPU1_SB_DQS_DP<0>
   94  M_A_CPU1_SB_DQS_DN<9>  DQS9_B_N  @S9S_MB_2U_LIB.S9S_MB_2U(SCH_1):M_A_CPU1_SB_DQS_DN<9>
  282  M_A_CPU1_SB_DQS_DN<8>  DQS8_B_N  @S9S_MB_2U_LIB.S9S_MB_2U(SCH_1):M_A_CPU1_SB_DQS_DN<8>
  271  M_A_CPU1_SB_DQS_DN<7>  DQS7_B_N  @S9S_MB_2U_LIB.S9S_MB_2U(SCH_1):M_A_CPU1_SB_DQS_DN<7>
  260  M_A_CPU1_SB_DQS_DN<6>  DQS6_B_N  @S9S_MB_2U_LIB.S9S_MB_2U(SCH_1):M_A_CPU1_SB_DQS_DN<6>
  249  M_A_CPU1_SB_DQS_DN<5>  DQS5_B_N  @S9S_MB_2U_LIB.S9S_MB_2U(SCH_1):M_A_CPU1_SB_DQS_DN<5>
  238  M_A_CPU1_SB_DQS_DN<4>  DQS4_B_N  @S9S_MB_2U_LIB.S9S_MB_2U(SCH_1):M_A_CPU1_SB_DQS_DN<4>
  138  M_A_CPU1_SB_DQS_DN<3>  DQS3_B_N  @S9S_MB_2U_LIB.S9S_MB_2U(SCH_1):M_A_CPU1_SB_DQS_DN<3>
  127  M_A_CPU1_SB_DQS_DN<2>  DQS2_B_N  @S9S_MB_2U_LIB.S9S_MB_2U(SCH_1):M_A_CPU1_SB_DQS_DN<2>
  116  M_A_CPU1_SB_DQS_DN<1>  DQS1_B_N  @S9S_MB_2U_LIB.S9S_MB_2U(SCH_1):M_A_CPU1_SB_DQS_DN<1>
  105  M_A_CPU1_SB_DQS_DN<0>  DQS0_B_N  @S9S_MB_2U_LIB.S9S_MB_2U(SCH_1):M_A_CPU1_SB_DQS_DN<0>
  201  M_A_CPU1_SA_DQS_DP<9>  DQS9_A_P  @S9S_MB_2U_LIB.S9S_MB_2U(SCH_1):M_A_CPU1_SA_DQS_DP<9>
  190  M_A_CPU1_SA_DQS_DP<8>  DQS8_A_P  @S9S_MB_2U_LIB.S9S_MB_2U(SCH_1):M_A_CPU1_SA_DQS_DP<8>
  179  M_A_CPU1_SA_DQS_DP<7>  DQS7_A_P  @S9S_MB_2U_LIB.S9S_MB_2U(SCH_1):M_A_CPU1_SA_DQS_DP<7>
  168  M_A_CPU1_SA_DQS_DP<6>  DQS6_A_P  @S9S_MB_2U_LIB.S9S_MB_2U(SCH_1):M_A_CPU1_SA_DQS_DP<6>
  157  M_A_CPU1_SA_DQS_DP<5>  DQS5_A_P  @S9S_MB_2U_LIB.S9S_MB_2U(SCH_1):M_A_CPU1_SA_DQS_DP<5>
   55  M_A_CPU1_SA_DQS_DP<4>  DQS4_A_P  @S9S_MB_2U_LIB.S9S_MB_2U(SCH_1):M_A_CPU1_SA_DQS_DP<4>
   44  M_A_CPU1_SA_DQS_DP<3>  DQS3_A_P  @S9S_MB_2U_LIB.S9S_MB_2U(SCH_1):M_A_CPU1_SA_DQS_DP<3>
   33  M_A_CPU1_SA_DQS_DP<2>  DQS2_A_P  @S9S_MB_2U_LIB.S9S_MB_2U(SCH_1):M_A_CPU1_SA_DQS_DP<2>
   22  M_A_CPU1_SA_DQS_DP<1>  DQS1_A_P  @S9S_MB_2U_LIB.S9S_MB_2U(SCH_1):M_A_CPU1_SA_DQS_DP<1>
   11  M_A_CPU1_SA_DQS_DP<0>  DQS0_A_P  @S9S_MB_2U_LIB.S9S_MB_2U(SCH_1):M_A_CPU1_SA_DQS_DP<0>
  200  M_A_CPU1_SA_DQS_DN<9>  DQS9_A_N  @S9S_MB_2U_LIB.S9S_MB_2U(SCH_1):M_A_CPU1_SA_DQS_DN<9>
  189  M_A_CPU1_SA_DQS_DN<8>  DQS8_A_N  @S9S_MB_2U_LIB.S9S_MB_2U(SCH_1):M_A_CPU1_SA_DQS_DN<8>
  178  M_A_CPU1_SA_DQS_DN<7>  DQS7_A_N  @S9S_MB_2U_LIB.S9S_MB_2U(SCH_1):M_A_CPU1_SA_DQS_DN<7>
  167  M_A_CPU1_SA_DQS_DN<6>  DQS6_A_N  @S9S_MB_2U_LIB.S9S_MB_2U(SCH_1):M_A_CPU1_SA_DQS_DN<6>
  156  M_A_CPU1_SA_DQS_DN<5>  DQS5_A_N  @S9S_MB_2U_LIB.S9S_MB_2U(SCH_1):M_A_CPU1_SA_DQS_DN<5>
   56  M_A_CPU1_SA_DQS_DN<4>  DQS4_A_N  @S9S_MB_2U_LIB.S9S_MB_2U(SCH_1):M_A_CPU1_SA_DQS_DN<4>
   45  M_A_CPU1_SA_DQS_DN<3>  DQS3_A_N  @S9S_MB_2U_LIB.S9S_MB_2U(SCH_1):M_A_CPU1_SA_DQS_DN<3>
   34  M_A_CPU1_SA_DQS_DN<2>  DQS2_A_N  @S9S_MB_2U_LIB.S9S_MB_2U(SCH_1):M_A_CPU1_SA_DQS_DN<2>
   23  M_A_CPU1_SA_DQS_DN<1>  DQS1_A_N  @S9S_MB_2U_LIB.S9S_MB_2U(SCH_1):M_A_CPU1_SA_DQS_DN<1>
   12  M_A_CPU1_SA_DQS_DN<0>  DQS0_A_N  @S9S_MB_2U_LIB.S9S_MB_2U(SCH_1):M_A_CPU1_SA_DQS_DN<0>

SCONN288_ADR50001P013C01  I12  J17    [SCONN288_ADR50001P013C01-SCONNA]
  232  NC              RFU6  NC
  231  NC              RFU5  NC
  220  NC              RFU4  NC
  150  NC              RFU3  NC
  149  NC              RFU2  NC
  144  NC              RFU1  NC
    2  NC              RFU0  NC
  207  RST_M_AB_CPU1_FPGA_N  RESET_N  @S9S_MB_2U_LIB.S9S_MB_2U(SCH_1):RST_M_AB_CPU1_FPGA_N
  147  PWRGD_CHA_CPU1_DIMM1  PWR_GOOD||FAIL_N  @S9S_MB_2U_LIB.S9S_MB_2U(SCH_1):PWRGD_CHA_CPU1_DIMM1
  148  PD_CHA_CPU1_DIMM1_SAA    HAS  @S9S_MB_2U_LIB.S9S_MB_2U(SCH_1):PD_CHA_CPU1_DIMM1_SAA
    3  P3V3_AUX       VIN_MGMT  @S9S_MB_2U_LIB.S9S_MB_2U(SCH_1):P3V3_AUX
   87  M_A_CPU1_SB_RSP<0>  LBS||RSP_N_B  @S9S_MB_2U_LIB.S9S_MB_2U(SCH_1):M_A_CPU1_SB_RSP<0>
  227  M_A_CPU1_SB_PAR  PAR_B  @S9S_MB_2U_LIB.S9S_MB_2U(SCH_1):M_A_CPU1_SB_PAR
  113  M_A_CPU1_SB_DQ<9>  DQ_B9  @S9S_MB_2U_LIB.S9S_MB_2U(SCH_1):M_A_CPU1_SB_DQ<9>
  111  M_A_CPU1_SB_DQ<8>  DQ_B8  @S9S_MB_2U_LIB.S9S_MB_2U(SCH_1):M_A_CPU1_SB_DQ<8>
  254  M_A_CPU1_SB_DQ<7>  DQ_B7  @S9S_MB_2U_LIB.S9S_MB_2U(SCH_1):M_A_CPU1_SB_DQ<7>
  252  M_A_CPU1_SB_DQ<6>  DQ_B6  @S9S_MB_2U_LIB.S9S_MB_2U(SCH_1):M_A_CPU1_SB_DQ<6>
  109  M_A_CPU1_SB_DQ<5>  DQ_B5  @S9S_MB_2U_LIB.S9S_MB_2U(SCH_1):M_A_CPU1_SB_DQ<5>
  107  M_A_CPU1_SB_DQ<4>  DQ_B4  @S9S_MB_2U_LIB.S9S_MB_2U(SCH_1):M_A_CPU1_SB_DQ<4>
  247  M_A_CPU1_SB_DQ<3>  DQ_B3  @S9S_MB_2U_LIB.S9S_MB_2U(SCH_1):M_A_CPU1_SB_DQ<3>
  287  M_A_CPU1_SB_DQ<31>  DQ_B31  @S9S_MB_2U_LIB.S9S_MB_2U(SCH_1):M_A_CPU1_SB_DQ<31>
  285  M_A_CPU1_SB_DQ<30>  DQ_B30  @S9S_MB_2U_LIB.S9S_MB_2U(SCH_1):M_A_CPU1_SB_DQ<30>
  245  M_A_CPU1_SB_DQ<2>  DQ_B2  @S9S_MB_2U_LIB.S9S_MB_2U(SCH_1):M_A_CPU1_SB_DQ<2>
  142  M_A_CPU1_SB_DQ<29>  DQ_B29  @S9S_MB_2U_LIB.S9S_MB_2U(SCH_1):M_A_CPU1_SB_DQ<29>
  140  M_A_CPU1_SB_DQ<28>  DQ_B28  @S9S_MB_2U_LIB.S9S_MB_2U(SCH_1):M_A_CPU1_SB_DQ<28>
  280  M_A_CPU1_SB_DQ<27>  DQ_B27  @S9S_MB_2U_LIB.S9S_MB_2U(SCH_1):M_A_CPU1_SB_DQ<27>
  278  M_A_CPU1_SB_DQ<26>  DQ_B26  @S9S_MB_2U_LIB.S9S_MB_2U(SCH_1):M_A_CPU1_SB_DQ<26>
  135  M_A_CPU1_SB_DQ<25>  DQ_B25  @S9S_MB_2U_LIB.S9S_MB_2U(SCH_1):M_A_CPU1_SB_DQ<25>
  133  M_A_CPU1_SB_DQ<24>  DQ_B24  @S9S_MB_2U_LIB.S9S_MB_2U(SCH_1):M_A_CPU1_SB_DQ<24>
  276  M_A_CPU1_SB_DQ<23>  DQ_B23  @S9S_MB_2U_LIB.S9S_MB_2U(SCH_1):M_A_CPU1_SB_DQ<23>
  274  M_A_CPU1_SB_DQ<22>  DQ_B22  @S9S_MB_2U_LIB.S9S_MB_2U(SCH_1):M_A_CPU1_SB_DQ<22>
  131  M_A_CPU1_SB_DQ<21>  DQ_B21  @S9S_MB_2U_LIB.S9S_MB_2U(SCH_1):M_A_CPU1_SB_DQ<21>
  129  M_A_CPU1_SB_DQ<20>  DQ_B20  @S9S_MB_2U_LIB.S9S_MB_2U(SCH_1):M_A_CPU1_SB_DQ<20>
  102  M_A_CPU1_SB_DQ<1>  DQ_B1  @S9S_MB_2U_LIB.S9S_MB_2U(SCH_1):M_A_CPU1_SB_DQ<1>
  269  M_A_CPU1_SB_DQ<19>  DQ_B19  @S9S_MB_2U_LIB.S9S_MB_2U(SCH_1):M_A_CPU1_SB_DQ<19>
  267  M_A_CPU1_SB_DQ<18>  DQ_B18  @S9S_MB_2U_LIB.S9S_MB_2U(SCH_1):M_A_CPU1_SB_DQ<18>
  124  M_A_CPU1_SB_DQ<17>  DQ_B17  @S9S_MB_2U_LIB.S9S_MB_2U(SCH_1):M_A_CPU1_SB_DQ<17>
  122  M_A_CPU1_SB_DQ<16>  DQ_B16  @S9S_MB_2U_LIB.S9S_MB_2U(SCH_1):M_A_CPU1_SB_DQ<16>
  265  M_A_CPU1_SB_DQ<15>  DQ_B15  @S9S_MB_2U_LIB.S9S_MB_2U(SCH_1):M_A_CPU1_SB_DQ<15>
  263  M_A_CPU1_SB_DQ<14>  DQ_B14  @S9S_MB_2U_LIB.S9S_MB_2U(SCH_1):M_A_CPU1_SB_DQ<14>
  120  M_A_CPU1_SB_DQ<13>  DQ_B13  @S9S_MB_2U_LIB.S9S_MB_2U(SCH_1):M_A_CPU1_SB_DQ<13>
  118  M_A_CPU1_SB_DQ<12>  DQ_B12  @S9S_MB_2U_LIB.S9S_MB_2U(SCH_1):M_A_CPU1_SB_DQ<12>
  258  M_A_CPU1_SB_DQ<11>  DQ_B11  @S9S_MB_2U_LIB.S9S_MB_2U(SCH_1):M_A_CPU1_SB_DQ<11>
  256  M_A_CPU1_SB_DQ<10>  DQ_B10  @S9S_MB_2U_LIB.S9S_MB_2U(SCH_1):M_A_CPU1_SB_DQ<10>
  100  M_A_CPU1_SB_DQ<0>  DQ_B0  @S9S_MB_2U_LIB.S9S_MB_2U(SCH_1):M_A_CPU1_SB_DQ<0>
  229  M_A_CPU1_SB_CS_N<1>  CS1_N_B  @S9S_MB_2U_LIB.S9S_MB_2U(SCH_1):M_A_CPU1_SB_CS_N<1>
   84  M_A_CPU1_SB_CS_N<0>  CS0_N_B  @S9S_MB_2U_LIB.S9S_MB_2U(SCH_1):M_A_CPU1_SB_CS_N<0>
  236  M_A_CPU1_SB_CB<7>  CB_B7  @S9S_MB_2U_LIB.S9S_MB_2U(SCH_1):M_A_CPU1_SB_CB<7>
  234  M_A_CPU1_SB_CB<6>  CB_B6  @S9S_MB_2U_LIB.S9S_MB_2U(SCH_1):M_A_CPU1_SB_CB<6>
   91  M_A_CPU1_SB_CB<5>  CB_B5  @S9S_MB_2U_LIB.S9S_MB_2U(SCH_1):M_A_CPU1_SB_CB<5>
   89  M_A_CPU1_SB_CB<4>  CB_B4  @S9S_MB_2U_LIB.S9S_MB_2U(SCH_1):M_A_CPU1_SB_CB<4>
  243  M_A_CPU1_SB_CB<3>  CB_B3  @S9S_MB_2U_LIB.S9S_MB_2U(SCH_1):M_A_CPU1_SB_CB<3>
  241  M_A_CPU1_SB_CB<2>  CB_B2  @S9S_MB_2U_LIB.S9S_MB_2U(SCH_1):M_A_CPU1_SB_CB<2>
   98  M_A_CPU1_SB_CB<1>  CB_B1  @S9S_MB_2U_LIB.S9S_MB_2U(SCH_1):M_A_CPU1_SB_CB<1>
   96  M_A_CPU1_SB_CB<0>  CB_B0  @S9S_MB_2U_LIB.S9S_MB_2U(SCH_1):M_A_CPU1_SB_CB<0>
   82  M_A_CPU1_SB_CA<6>  CA6_B  @S9S_MB_2U_LIB.S9S_MB_2U(SCH_1):M_A_CPU1_SB_CA<6>
  225  M_A_CPU1_SB_CA<5>  CA5_B  @S9S_MB_2U_LIB.S9S_MB_2U(SCH_1):M_A_CPU1_SB_CA<5>
   80  M_A_CPU1_SB_CA<4>  CA4_B  @S9S_MB_2U_LIB.S9S_MB_2U(SCH_1):M_A_CPU1_SB_CA<4>
  223  M_A_CPU1_SB_CA<3>  CA3_B  @S9S_MB_2U_LIB.S9S_MB_2U(SCH_1):M_A_CPU1_SB_CA<3>
   78  M_A_CPU1_SB_CA<2>  CA2_B  @S9S_MB_2U_LIB.S9S_MB_2U(SCH_1):M_A_CPU1_SB_CA<2>
  221  M_A_CPU1_SB_CA<1>  CA1_B  @S9S_MB_2U_LIB.S9S_MB_2U(SCH_1):M_A_CPU1_SB_CA<1>
   76  M_A_CPU1_SB_CA<0>  CA0_B  @S9S_MB_2U_LIB.S9S_MB_2U(SCH_1):M_A_CPU1_SB_CA<0>
   86  M_A_CPU1_SA_RSP<0>  LBD||RSP_N_A  @S9S_MB_2U_LIB.S9S_MB_2U(SCH_1):M_A_CPU1_SA_RSP<0>
   74  M_A_CPU1_SA_PAR  PAR_A  @S9S_MB_2U_LIB.S9S_MB_2U(SCH_1):M_A_CPU1_SA_PAR
   20  M_A_CPU1_SA_DQ<9>  DQ_A9  @S9S_MB_2U_LIB.S9S_MB_2U(SCH_1):M_A_CPU1_SA_DQ<9>
   18  M_A_CPU1_SA_DQ<8>  DQ_A8  @S9S_MB_2U_LIB.S9S_MB_2U(SCH_1):M_A_CPU1_SA_DQ<8>
  161  M_A_CPU1_SA_DQ<7>  DQ_A7  @S9S_MB_2U_LIB.S9S_MB_2U(SCH_1):M_A_CPU1_SA_DQ<7>
  159  M_A_CPU1_SA_DQ<6>  DQ_A6  @S9S_MB_2U_LIB.S9S_MB_2U(SCH_1):M_A_CPU1_SA_DQ<6>
   16  M_A_CPU1_SA_DQ<5>  DQ_A5  @S9S_MB_2U_LIB.S9S_MB_2U(SCH_1):M_A_CPU1_SA_DQ<5>
   14  M_A_CPU1_SA_DQ<4>  DQ_A4  @S9S_MB_2U_LIB.S9S_MB_2U(SCH_1):M_A_CPU1_SA_DQ<4>
  154  M_A_CPU1_SA_DQ<3>  DQ_A3  @S9S_MB_2U_LIB.S9S_MB_2U(SCH_1):M_A_CPU1_SA_DQ<3>
  194  M_A_CPU1_SA_DQ<31>  DQ_A31  @S9S_MB_2U_LIB.S9S_MB_2U(SCH_1):M_A_CPU1_SA_DQ<31>
  192  M_A_CPU1_SA_DQ<30>  DQ_A30  @S9S_MB_2U_LIB.S9S_MB_2U(SCH_1):M_A_CPU1_SA_DQ<30>
  152  M_A_CPU1_SA_DQ<2>  DQ_A2  @S9S_MB_2U_LIB.S9S_MB_2U(SCH_1):M_A_CPU1_SA_DQ<2>
   49  M_A_CPU1_SA_DQ<29>  DQ_A29  @S9S_MB_2U_LIB.S9S_MB_2U(SCH_1):M_A_CPU1_SA_DQ<29>
   47  M_A_CPU1_SA_DQ<28>  DQ_A28  @S9S_MB_2U_LIB.S9S_MB_2U(SCH_1):M_A_CPU1_SA_DQ<28>
  187  M_A_CPU1_SA_DQ<27>  DQ_A27  @S9S_MB_2U_LIB.S9S_MB_2U(SCH_1):M_A_CPU1_SA_DQ<27>
  185  M_A_CPU1_SA_DQ<26>  DQ_A26  @S9S_MB_2U_LIB.S9S_MB_2U(SCH_1):M_A_CPU1_SA_DQ<26>
   42  M_A_CPU1_SA_DQ<25>  DQ_A25  @S9S_MB_2U_LIB.S9S_MB_2U(SCH_1):M_A_CPU1_SA_DQ<25>
   40  M_A_CPU1_SA_DQ<24>  DQ_A24  @S9S_MB_2U_LIB.S9S_MB_2U(SCH_1):M_A_CPU1_SA_DQ<24>
  183  M_A_CPU1_SA_DQ<23>  DQ_A23  @S9S_MB_2U_LIB.S9S_MB_2U(SCH_1):M_A_CPU1_SA_DQ<23>
  181  M_A_CPU1_SA_DQ<22>  DQ_A22  @S9S_MB_2U_LIB.S9S_MB_2U(SCH_1):M_A_CPU1_SA_DQ<22>
   38  M_A_CPU1_SA_DQ<21>  DQ_A21  @S9S_MB_2U_LIB.S9S_MB_2U(SCH_1):M_A_CPU1_SA_DQ<21>
   36  M_A_CPU1_SA_DQ<20>  DQ_A20  @S9S_MB_2U_LIB.S9S_MB_2U(SCH_1):M_A_CPU1_SA_DQ<20>
    9  M_A_CPU1_SA_DQ<1>  DQ_A1  @S9S_MB_2U_LIB.S9S_MB_2U(SCH_1):M_A_CPU1_SA_DQ<1>
  176  M_A_CPU1_SA_DQ<19>  DQ_A19  @S9S_MB_2U_LIB.S9S_MB_2U(SCH_1):M_A_CPU1_SA_DQ<19>
  174  M_A_CPU1_SA_DQ<18>  DQ_A18  @S9S_MB_2U_LIB.S9S_MB_2U(SCH_1):M_A_CPU1_SA_DQ<18>
   31  M_A_CPU1_SA_DQ<17>  DQ_A17  @S9S_MB_2U_LIB.S9S_MB_2U(SCH_1):M_A_CPU1_SA_DQ<17>
   29  M_A_CPU1_SA_DQ<16>  DQ_A16  @S9S_MB_2U_LIB.S9S_MB_2U(SCH_1):M_A_CPU1_SA_DQ<16>
  172  M_A_CPU1_SA_DQ<15>  DQ_A15  @S9S_MB_2U_LIB.S9S_MB_2U(SCH_1):M_A_CPU1_SA_DQ<15>
  170  M_A_CPU1_SA_DQ<14>  DQ_A14  @S9S_MB_2U_LIB.S9S_MB_2U(SCH_1):M_A_CPU1_SA_DQ<14>
   27  M_A_CPU1_SA_DQ<13>  DQ_A13  @S9S_MB_2U_LIB.S9S_MB_2U(SCH_1):M_A_CPU1_SA_DQ<13>
   25  M_A_CPU1_SA_DQ<12>  DQ_A12  @S9S_MB_2U_LIB.S9S_MB_2U(SCH_1):M_A_CPU1_SA_DQ<12>
  165  M_A_CPU1_SA_DQ<11>  DQ_A11  @S9S_MB_2U_LIB.S9S_MB_2U(SCH_1):M_A_CPU1_SA_DQ<11>
  163  M_A_CPU1_SA_DQ<10>  DQ_A10  @S9S_MB_2U_LIB.S9S_MB_2U(SCH_1):M_A_CPU1_SA_DQ<10>
    7  M_A_CPU1_SA_DQ<0>  DQ_A0  @S9S_MB_2U_LIB.S9S_MB_2U(SCH_1):M_A_CPU1_SA_DQ<0>
  209  M_A_CPU1_SA_CS_N<1>  CS1_N_A  @S9S_MB_2U_LIB.S9S_MB_2U(SCH_1):M_A_CPU1_SA_CS_N<1>
   64  M_A_CPU1_SA_CS_N<0>  CS0_N_A  @S9S_MB_2U_LIB.S9S_MB_2U(SCH_1):M_A_CPU1_SA_CS_N<0>
  205  M_A_CPU1_SA_CB<7>  CB_A7  @S9S_MB_2U_LIB.S9S_MB_2U(SCH_1):M_A_CPU1_SA_CB<7>
  203  M_A_CPU1_SA_CB<6>  CB_A6  @S9S_MB_2U_LIB.S9S_MB_2U(SCH_1):M_A_CPU1_SA_CB<6>
   60  M_A_CPU1_SA_CB<5>  CB_A5  @S9S_MB_2U_LIB.S9S_MB_2U(SCH_1):M_A_CPU1_SA_CB<5>
   58  M_A_CPU1_SA_CB<4>  CB_A4  @S9S_MB_2U_LIB.S9S_MB_2U(SCH_1):M_A_CPU1_SA_CB<4>
  198  M_A_CPU1_SA_CB<3>  CB_A3  @S9S_MB_2U_LIB.S9S_MB_2U(SCH_1):M_A_CPU1_SA_CB<3>
  196  M_A_CPU1_SA_CB<2>  CB_A2  @S9S_MB_2U_LIB.S9S_MB_2U(SCH_1):M_A_CPU1_SA_CB<2>
   53  M_A_CPU1_SA_CB<1>  CB_A1  @S9S_MB_2U_LIB.S9S_MB_2U(SCH_1):M_A_CPU1_SA_CB<1>
   51  M_A_CPU1_SA_CB<0>  CB_A0  @S9S_MB_2U_LIB.S9S_MB_2U(SCH_1):M_A_CPU1_SA_CB<0>
   72  M_A_CPU1_SA_CA<6>  CA6_A  @S9S_MB_2U_LIB.S9S_MB_2U(SCH_1):M_A_CPU1_SA_CA<6>
  215  M_A_CPU1_SA_CA<5>  CA5_A  @S9S_MB_2U_LIB.S9S_MB_2U(SCH_1):M_A_CPU1_SA_CA<5>
   70  M_A_CPU1_SA_CA<4>  CA4_A  @S9S_MB_2U_LIB.S9S_MB_2U(SCH_1):M_A_CPU1_SA_CA<4>
  213  M_A_CPU1_SA_CA<3>  CA3_A  @S9S_MB_2U_LIB.S9S_MB_2U(SCH_1):M_A_CPU1_SA_CA<3>
   68  M_A_CPU1_SA_CA<2>  CA2_A  @S9S_MB_2U_LIB.S9S_MB_2U(SCH_1):M_A_CPU1_SA_CA<2>
  211  M_A_CPU1_SA_CA<1>  CA1_A  @S9S_MB_2U_LIB.S9S_MB_2U(SCH_1):M_A_CPU1_SA_CA<1>
   66  M_A_CPU1_SA_CA<0>  CA0_A  @S9S_MB_2U_LIB.S9S_MB_2U(SCH_1):M_A_CPU1_SA_CA<0>
  217  M_A_CPU1_CLK_DP<0>   CK_P  @S9S_MB_2U_LIB.S9S_MB_2U(SCH_1):M_A_CPU1_CLK_DP<0>
  218  M_A_CPU1_CLK_DN<0>   CK_N  @S9S_MB_2U_LIB.S9S_MB_2U(SCH_1):M_A_CPU1_CLK_DN<0>
   62  M_A_CPU1_ALERT_N  ALERT_N  @S9S_MB_2U_LIB.S9S_MB_2U(SCH_1):M_A_CPU1_ALERT_N
    5  I3C_SPD_DDRABCD_CPU1_LVC1_SDA   HSDA  @S9S_MB_2U_LIB.S9S_MB_2U(SCH_1):I3C_SPD_DDRABCD_CPU1_LVC1_SDA
    4  I3C_SPD_DDRABCD_CPU1_LVC1_SCL   HSCL  @S9S_MB_2U_LIB.S9S_MB_2U(SCH_1):I3C_SPD_DDRABCD_CPU1_LVC1_SCL

SCONN288_ADR50001P003C01  I175  J18    [SCONN288_ADR50001P003C01-SCONNA]
  146  P12V_S3_AUX_CPU1_NVDIMM  VIN_BULK2  @S9S_MB_2U_LIB.S9S_MB_2U(SCH_1):P12V_S3_AUX_CPU1_NVDIMM
  145  P12V_S3_AUX_CPU1_NVDIMM  VIN_BULK1  @S9S_MB_2U_LIB.S9S_MB_2U(SCH_1):P12V_S3_AUX_CPU1_NVDIMM
    1  P12V_S3_AUX_CPU1_NVDIMM  VIN_BULK0  @S9S_MB_2U_LIB.S9S_MB_2U(SCH_1):P12V_S3_AUX_CPU1_NVDIMM
  288  GND            VSS126  @S9S_MB_2U_LIB.S9S_MB_2U(SCH_1):GND
  286  GND            VSS125  @S9S_MB_2U_LIB.S9S_MB_2U(SCH_1):GND
  284  GND            VSS124  @S9S_MB_2U_LIB.S9S_MB_2U(SCH_1):GND
  281  GND            VSS123  @S9S_MB_2U_LIB.S9S_MB_2U(SCH_1):GND
  279  GND            VSS122  @S9S_MB_2U_LIB.S9S_MB_2U(SCH_1):GND
  277  GND            VSS121  @S9S_MB_2U_LIB.S9S_MB_2U(SCH_1):GND
  275  GND            VSS120  @S9S_MB_2U_LIB.S9S_MB_2U(SCH_1):GND
  273  GND            VSS119  @S9S_MB_2U_LIB.S9S_MB_2U(SCH_1):GND
  270  GND            VSS118  @S9S_MB_2U_LIB.S9S_MB_2U(SCH_1):GND
  268  GND            VSS117  @S9S_MB_2U_LIB.S9S_MB_2U(SCH_1):GND
  266  GND            VSS116  @S9S_MB_2U_LIB.S9S_MB_2U(SCH_1):GND
  264  GND            VSS115  @S9S_MB_2U_LIB.S9S_MB_2U(SCH_1):GND
  262  GND            VSS114  @S9S_MB_2U_LIB.S9S_MB_2U(SCH_1):GND
  259  GND            VSS113  @S9S_MB_2U_LIB.S9S_MB_2U(SCH_1):GND
  257  GND            VSS112  @S9S_MB_2U_LIB.S9S_MB_2U(SCH_1):GND
  255  GND            VSS111  @S9S_MB_2U_LIB.S9S_MB_2U(SCH_1):GND
  253  GND            VSS110  @S9S_MB_2U_LIB.S9S_MB_2U(SCH_1):GND
  251  GND            VSS109  @S9S_MB_2U_LIB.S9S_MB_2U(SCH_1):GND
  248  GND            VSS108  @S9S_MB_2U_LIB.S9S_MB_2U(SCH_1):GND
  246  GND            VSS107  @S9S_MB_2U_LIB.S9S_MB_2U(SCH_1):GND
  244  GND            VSS106  @S9S_MB_2U_LIB.S9S_MB_2U(SCH_1):GND
  242  GND            VSS105  @S9S_MB_2U_LIB.S9S_MB_2U(SCH_1):GND
  240  GND            VSS104  @S9S_MB_2U_LIB.S9S_MB_2U(SCH_1):GND
  237  GND            VSS103  @S9S_MB_2U_LIB.S9S_MB_2U(SCH_1):GND
  235  GND            VSS102  @S9S_MB_2U_LIB.S9S_MB_2U(SCH_1):GND
  233  GND            VSS101  @S9S_MB_2U_LIB.S9S_MB_2U(SCH_1):GND
  230  GND            VSS100  @S9S_MB_2U_LIB.S9S_MB_2U(SCH_1):GND
  228  GND            VSS99  @S9S_MB_2U_LIB.S9S_MB_2U(SCH_1):GND
  226  GND            VSS98  @S9S_MB_2U_LIB.S9S_MB_2U(SCH_1):GND
  224  GND            VSS97  @S9S_MB_2U_LIB.S9S_MB_2U(SCH_1):GND
  222  GND            VSS96  @S9S_MB_2U_LIB.S9S_MB_2U(SCH_1):GND
  219  GND            VSS95  @S9S_MB_2U_LIB.S9S_MB_2U(SCH_1):GND
  216  GND            VSS94  @S9S_MB_2U_LIB.S9S_MB_2U(SCH_1):GND
  214  GND            VSS93  @S9S_MB_2U_LIB.S9S_MB_2U(SCH_1):GND
  212  GND            VSS92  @S9S_MB_2U_LIB.S9S_MB_2U(SCH_1):GND
  210  GND            VSS91  @S9S_MB_2U_LIB.S9S_MB_2U(SCH_1):GND
  208  GND            VSS90  @S9S_MB_2U_LIB.S9S_MB_2U(SCH_1):GND
  206  GND            VSS89  @S9S_MB_2U_LIB.S9S_MB_2U(SCH_1):GND
  204  GND            VSS88  @S9S_MB_2U_LIB.S9S_MB_2U(SCH_1):GND
  202  GND            VSS87  @S9S_MB_2U_LIB.S9S_MB_2U(SCH_1):GND
  199  GND            VSS86  @S9S_MB_2U_LIB.S9S_MB_2U(SCH_1):GND
  197  GND            VSS85  @S9S_MB_2U_LIB.S9S_MB_2U(SCH_1):GND
  195  GND            VSS84  @S9S_MB_2U_LIB.S9S_MB_2U(SCH_1):GND
  193  GND            VSS83  @S9S_MB_2U_LIB.S9S_MB_2U(SCH_1):GND
  191  GND            VSS82  @S9S_MB_2U_LIB.S9S_MB_2U(SCH_1):GND
  188  GND            VSS81  @S9S_MB_2U_LIB.S9S_MB_2U(SCH_1):GND
  186  GND            VSS80  @S9S_MB_2U_LIB.S9S_MB_2U(SCH_1):GND
  184  GND            VSS79  @S9S_MB_2U_LIB.S9S_MB_2U(SCH_1):GND
  182  GND            VSS78  @S9S_MB_2U_LIB.S9S_MB_2U(SCH_1):GND
  180  GND            VSS77  @S9S_MB_2U_LIB.S9S_MB_2U(SCH_1):GND
  177  GND            VSS76  @S9S_MB_2U_LIB.S9S_MB_2U(SCH_1):GND
  175  GND            VSS75  @S9S_MB_2U_LIB.S9S_MB_2U(SCH_1):GND
  173  GND            VSS74  @S9S_MB_2U_LIB.S9S_MB_2U(SCH_1):GND
  171  GND            VSS73  @S9S_MB_2U_LIB.S9S_MB_2U(SCH_1):GND
  169  GND            VSS72  @S9S_MB_2U_LIB.S9S_MB_2U(SCH_1):GND
  166  GND            VSS71  @S9S_MB_2U_LIB.S9S_MB_2U(SCH_1):GND
  164  GND            VSS70  @S9S_MB_2U_LIB.S9S_MB_2U(SCH_1):GND
  162  GND            VSS69  @S9S_MB_2U_LIB.S9S_MB_2U(SCH_1):GND
  160  GND            VSS68  @S9S_MB_2U_LIB.S9S_MB_2U(SCH_1):GND
  158  GND            VSS67  @S9S_MB_2U_LIB.S9S_MB_2U(SCH_1):GND
  155  GND            VSS66  @S9S_MB_2U_LIB.S9S_MB_2U(SCH_1):GND
  153  GND            VSS65  @S9S_MB_2U_LIB.S9S_MB_2U(SCH_1):GND
  151  GND            VSS64  @S9S_MB_2U_LIB.S9S_MB_2U(SCH_1):GND
  143  GND            VSS63  @S9S_MB_2U_LIB.S9S_MB_2U(SCH_1):GND
  141  GND            VSS62  @S9S_MB_2U_LIB.S9S_MB_2U(SCH_1):GND
  139  GND            VSS61  @S9S_MB_2U_LIB.S9S_MB_2U(SCH_1):GND
  136  GND            VSS60  @S9S_MB_2U_LIB.S9S_MB_2U(SCH_1):GND
  134  GND            VSS59  @S9S_MB_2U_LIB.S9S_MB_2U(SCH_1):GND
  132  GND            VSS58  @S9S_MB_2U_LIB.S9S_MB_2U(SCH_1):GND
  130  GND            VSS57  @S9S_MB_2U_LIB.S9S_MB_2U(SCH_1):GND
  128  GND            VSS56  @S9S_MB_2U_LIB.S9S_MB_2U(SCH_1):GND
  125  GND            VSS55  @S9S_MB_2U_LIB.S9S_MB_2U(SCH_1):GND
  123  GND            VSS54  @S9S_MB_2U_LIB.S9S_MB_2U(SCH_1):GND
  121  GND            VSS53  @S9S_MB_2U_LIB.S9S_MB_2U(SCH_1):GND
  119  GND            VSS52  @S9S_MB_2U_LIB.S9S_MB_2U(SCH_1):GND
  117  GND            VSS51  @S9S_MB_2U_LIB.S9S_MB_2U(SCH_1):GND
  114  GND            VSS50  @S9S_MB_2U_LIB.S9S_MB_2U(SCH_1):GND
  112  GND            VSS49  @S9S_MB_2U_LIB.S9S_MB_2U(SCH_1):GND
  110  GND            VSS48  @S9S_MB_2U_LIB.S9S_MB_2U(SCH_1):GND
  108  GND            VSS47  @S9S_MB_2U_LIB.S9S_MB_2U(SCH_1):GND
  106  GND            VSS46  @S9S_MB_2U_LIB.S9S_MB_2U(SCH_1):GND
  103  GND            VSS45  @S9S_MB_2U_LIB.S9S_MB_2U(SCH_1):GND
  101  GND            VSS44  @S9S_MB_2U_LIB.S9S_MB_2U(SCH_1):GND
   99  GND            VSS43  @S9S_MB_2U_LIB.S9S_MB_2U(SCH_1):GND
   97  GND            VSS42  @S9S_MB_2U_LIB.S9S_MB_2U(SCH_1):GND
   95  GND            VSS41  @S9S_MB_2U_LIB.S9S_MB_2U(SCH_1):GND
   92  GND            VSS40  @S9S_MB_2U_LIB.S9S_MB_2U(SCH_1):GND
   90  GND            VSS39  @S9S_MB_2U_LIB.S9S_MB_2U(SCH_1):GND
   88  GND            VSS38  @S9S_MB_2U_LIB.S9S_MB_2U(SCH_1):GND
   85  GND            VSS37  @S9S_MB_2U_LIB.S9S_MB_2U(SCH_1):GND
   83  GND            VSS36  @S9S_MB_2U_LIB.S9S_MB_2U(SCH_1):GND
   81  GND            VSS35  @S9S_MB_2U_LIB.S9S_MB_2U(SCH_1):GND
   79  GND            VSS34  @S9S_MB_2U_LIB.S9S_MB_2U(SCH_1):GND
   77  GND            VSS33  @S9S_MB_2U_LIB.S9S_MB_2U(SCH_1):GND
   75  GND            VSS32  @S9S_MB_2U_LIB.S9S_MB_2U(SCH_1):GND
   73  GND            VSS31  @S9S_MB_2U_LIB.S9S_MB_2U(SCH_1):GND
   71  GND            VSS30  @S9S_MB_2U_LIB.S9S_MB_2U(SCH_1):GND
   69  GND            VSS29  @S9S_MB_2U_LIB.S9S_MB_2U(SCH_1):GND
   67  GND            VSS28  @S9S_MB_2U_LIB.S9S_MB_2U(SCH_1):GND
   65  GND            VSS27  @S9S_MB_2U_LIB.S9S_MB_2U(SCH_1):GND
   63  GND            VSS26  @S9S_MB_2U_LIB.S9S_MB_2U(SCH_1):GND
   61  GND            VSS25  @S9S_MB_2U_LIB.S9S_MB_2U(SCH_1):GND
   59  GND            VSS24  @S9S_MB_2U_LIB.S9S_MB_2U(SCH_1):GND
   57  GND            VSS23  @S9S_MB_2U_LIB.S9S_MB_2U(SCH_1):GND
   54  GND            VSS22  @S9S_MB_2U_LIB.S9S_MB_2U(SCH_1):GND
   52  GND            VSS21  @S9S_MB_2U_LIB.S9S_MB_2U(SCH_1):GND
   50  GND            VSS20  @S9S_MB_2U_LIB.S9S_MB_2U(SCH_1):GND
   48  GND            VSS19  @S9S_MB_2U_LIB.S9S_MB_2U(SCH_1):GND
   46  GND            VSS18  @S9S_MB_2U_LIB.S9S_MB_2U(SCH_1):GND
   43  GND            VSS17  @S9S_MB_2U_LIB.S9S_MB_2U(SCH_1):GND
   41  GND            VSS16  @S9S_MB_2U_LIB.S9S_MB_2U(SCH_1):GND
   39  GND            VSS15  @S9S_MB_2U_LIB.S9S_MB_2U(SCH_1):GND
   37  GND            VSS14  @S9S_MB_2U_LIB.S9S_MB_2U(SCH_1):GND
   35  GND            VSS13  @S9S_MB_2U_LIB.S9S_MB_2U(SCH_1):GND
   32  GND            VSS12  @S9S_MB_2U_LIB.S9S_MB_2U(SCH_1):GND
   30  GND            VSS11  @S9S_MB_2U_LIB.S9S_MB_2U(SCH_1):GND
   28  GND            VSS10  @S9S_MB_2U_LIB.S9S_MB_2U(SCH_1):GND
   26  GND             VSS9  @S9S_MB_2U_LIB.S9S_MB_2U(SCH_1):GND
   24  GND             VSS8  @S9S_MB_2U_LIB.S9S_MB_2U(SCH_1):GND
   21  GND             VSS7  @S9S_MB_2U_LIB.S9S_MB_2U(SCH_1):GND
   19  GND             VSS6  @S9S_MB_2U_LIB.S9S_MB_2U(SCH_1):GND
   17  GND             VSS5  @S9S_MB_2U_LIB.S9S_MB_2U(SCH_1):GND
   15  GND             VSS4  @S9S_MB_2U_LIB.S9S_MB_2U(SCH_1):GND
   13  GND             VSS3  @S9S_MB_2U_LIB.S9S_MB_2U(SCH_1):GND
   10  GND             VSS2  @S9S_MB_2U_LIB.S9S_MB_2U(SCH_1):GND
    8  GND             VSS1  @S9S_MB_2U_LIB.S9S_MB_2U(SCH_1):GND
    6  GND             VSS0  @S9S_MB_2U_LIB.S9S_MB_2U(SCH_1):GND
   G3  GND               G3  @S9S_MB_2U_LIB.S9S_MB_2U(SCH_1):GND
   G2  GND               G2  @S9S_MB_2U_LIB.S9S_MB_2U(SCH_1):GND
   G1  GND               G1  @S9S_MB_2U_LIB.S9S_MB_2U(SCH_1):GND

SCONN288_ADR50001P003C01  I125  J18    [SCONN288_ADR50001P003C01-SCONNA]
   93  M_A_CPU1_SB_DQS_DP<9>  DQS9_B_P  @S9S_MB_2U_LIB.S9S_MB_2U(SCH_1):M_A_CPU1_SB_DQS_DP<9>
  283  M_A_CPU1_SB_DQS_DP<8>  DQS8_B_P  @S9S_MB_2U_LIB.S9S_MB_2U(SCH_1):M_A_CPU1_SB_DQS_DP<8>
  272  M_A_CPU1_SB_DQS_DP<7>  DQS7_B_P  @S9S_MB_2U_LIB.S9S_MB_2U(SCH_1):M_A_CPU1_SB_DQS_DP<7>
  261  M_A_CPU1_SB_DQS_DP<6>  DQS6_B_P  @S9S_MB_2U_LIB.S9S_MB_2U(SCH_1):M_A_CPU1_SB_DQS_DP<6>
  250  M_A_CPU1_SB_DQS_DP<5>  DQS5_B_P  @S9S_MB_2U_LIB.S9S_MB_2U(SCH_1):M_A_CPU1_SB_DQS_DP<5>
  239  M_A_CPU1_SB_DQS_DP<4>  DQS4_B_P  @S9S_MB_2U_LIB.S9S_MB_2U(SCH_1):M_A_CPU1_SB_DQS_DP<4>
  137  M_A_CPU1_SB_DQS_DP<3>  DQS3_B_P  @S9S_MB_2U_LIB.S9S_MB_2U(SCH_1):M_A_CPU1_SB_DQS_DP<3>
  126  M_A_CPU1_SB_DQS_DP<2>  DQS2_B_P  @S9S_MB_2U_LIB.S9S_MB_2U(SCH_1):M_A_CPU1_SB_DQS_DP<2>
  115  M_A_CPU1_SB_DQS_DP<1>  DQS1_B_P  @S9S_MB_2U_LIB.S9S_MB_2U(SCH_1):M_A_CPU1_SB_DQS_DP<1>
  104  M_A_CPU1_SB_DQS_DP<0>  DQS0_B_P  @S9S_MB_2U_LIB.S9S_MB_2U(SCH_1):M_A_CPU1_SB_DQS_DP<0>
   94  M_A_CPU1_SB_DQS_DN<9>  DQS9_B_N  @S9S_MB_2U_LIB.S9S_MB_2U(SCH_1):M_A_CPU1_SB_DQS_DN<9>
  282  M_A_CPU1_SB_DQS_DN<8>  DQS8_B_N  @S9S_MB_2U_LIB.S9S_MB_2U(SCH_1):M_A_CPU1_SB_DQS_DN<8>
  271  M_A_CPU1_SB_DQS_DN<7>  DQS7_B_N  @S9S_MB_2U_LIB.S9S_MB_2U(SCH_1):M_A_CPU1_SB_DQS_DN<7>
  260  M_A_CPU1_SB_DQS_DN<6>  DQS6_B_N  @S9S_MB_2U_LIB.S9S_MB_2U(SCH_1):M_A_CPU1_SB_DQS_DN<6>
  249  M_A_CPU1_SB_DQS_DN<5>  DQS5_B_N  @S9S_MB_2U_LIB.S9S_MB_2U(SCH_1):M_A_CPU1_SB_DQS_DN<5>
  238  M_A_CPU1_SB_DQS_DN<4>  DQS4_B_N  @S9S_MB_2U_LIB.S9S_MB_2U(SCH_1):M_A_CPU1_SB_DQS_DN<4>
  138  M_A_CPU1_SB_DQS_DN<3>  DQS3_B_N  @S9S_MB_2U_LIB.S9S_MB_2U(SCH_1):M_A_CPU1_SB_DQS_DN<3>
  127  M_A_CPU1_SB_DQS_DN<2>  DQS2_B_N  @S9S_MB_2U_LIB.S9S_MB_2U(SCH_1):M_A_CPU1_SB_DQS_DN<2>
  116  M_A_CPU1_SB_DQS_DN<1>  DQS1_B_N  @S9S_MB_2U_LIB.S9S_MB_2U(SCH_1):M_A_CPU1_SB_DQS_DN<1>
  105  M_A_CPU1_SB_DQS_DN<0>  DQS0_B_N  @S9S_MB_2U_LIB.S9S_MB_2U(SCH_1):M_A_CPU1_SB_DQS_DN<0>
  201  M_A_CPU1_SA_DQS_DP<9>  DQS9_A_P  @S9S_MB_2U_LIB.S9S_MB_2U(SCH_1):M_A_CPU1_SA_DQS_DP<9>
  190  M_A_CPU1_SA_DQS_DP<8>  DQS8_A_P  @S9S_MB_2U_LIB.S9S_MB_2U(SCH_1):M_A_CPU1_SA_DQS_DP<8>
  179  M_A_CPU1_SA_DQS_DP<7>  DQS7_A_P  @S9S_MB_2U_LIB.S9S_MB_2U(SCH_1):M_A_CPU1_SA_DQS_DP<7>
  168  M_A_CPU1_SA_DQS_DP<6>  DQS6_A_P  @S9S_MB_2U_LIB.S9S_MB_2U(SCH_1):M_A_CPU1_SA_DQS_DP<6>
  157  M_A_CPU1_SA_DQS_DP<5>  DQS5_A_P  @S9S_MB_2U_LIB.S9S_MB_2U(SCH_1):M_A_CPU1_SA_DQS_DP<5>
   55  M_A_CPU1_SA_DQS_DP<4>  DQS4_A_P  @S9S_MB_2U_LIB.S9S_MB_2U(SCH_1):M_A_CPU1_SA_DQS_DP<4>
   44  M_A_CPU1_SA_DQS_DP<3>  DQS3_A_P  @S9S_MB_2U_LIB.S9S_MB_2U(SCH_1):M_A_CPU1_SA_DQS_DP<3>
   33  M_A_CPU1_SA_DQS_DP<2>  DQS2_A_P  @S9S_MB_2U_LIB.S9S_MB_2U(SCH_1):M_A_CPU1_SA_DQS_DP<2>
   22  M_A_CPU1_SA_DQS_DP<1>  DQS1_A_P  @S9S_MB_2U_LIB.S9S_MB_2U(SCH_1):M_A_CPU1_SA_DQS_DP<1>
   11  M_A_CPU1_SA_DQS_DP<0>  DQS0_A_P  @S9S_MB_2U_LIB.S9S_MB_2U(SCH_1):M_A_CPU1_SA_DQS_DP<0>
  200  M_A_CPU1_SA_DQS_DN<9>  DQS9_A_N  @S9S_MB_2U_LIB.S9S_MB_2U(SCH_1):M_A_CPU1_SA_DQS_DN<9>
  189  M_A_CPU1_SA_DQS_DN<8>  DQS8_A_N  @S9S_MB_2U_LIB.S9S_MB_2U(SCH_1):M_A_CPU1_SA_DQS_DN<8>
  178  M_A_CPU1_SA_DQS_DN<7>  DQS7_A_N  @S9S_MB_2U_LIB.S9S_MB_2U(SCH_1):M_A_CPU1_SA_DQS_DN<7>
  167  M_A_CPU1_SA_DQS_DN<6>  DQS6_A_N  @S9S_MB_2U_LIB.S9S_MB_2U(SCH_1):M_A_CPU1_SA_DQS_DN<6>
  156  M_A_CPU1_SA_DQS_DN<5>  DQS5_A_N  @S9S_MB_2U_LIB.S9S_MB_2U(SCH_1):M_A_CPU1_SA_DQS_DN<5>
   56  M_A_CPU1_SA_DQS_DN<4>  DQS4_A_N  @S9S_MB_2U_LIB.S9S_MB_2U(SCH_1):M_A_CPU1_SA_DQS_DN<4>
   45  M_A_CPU1_SA_DQS_DN<3>  DQS3_A_N  @S9S_MB_2U_LIB.S9S_MB_2U(SCH_1):M_A_CPU1_SA_DQS_DN<3>
   34  M_A_CPU1_SA_DQS_DN<2>  DQS2_A_N  @S9S_MB_2U_LIB.S9S_MB_2U(SCH_1):M_A_CPU1_SA_DQS_DN<2>
   23  M_A_CPU1_SA_DQS_DN<1>  DQS1_A_N  @S9S_MB_2U_LIB.S9S_MB_2U(SCH_1):M_A_CPU1_SA_DQS_DN<1>
   12  M_A_CPU1_SA_DQS_DN<0>  DQS0_A_N  @S9S_MB_2U_LIB.S9S_MB_2U(SCH_1):M_A_CPU1_SA_DQS_DN<0>

SCONN288_ADR50001P003C01  I24  J18    [SCONN288_ADR50001P003C01-SCONNA]
  232  NC              RFU6  NC
  231  NC              RFU5  NC
  220  NC              RFU4  NC
  150  NC              RFU3  NC
  149  NC              RFU2  NC
  144  NC              RFU1  NC
    2  NC              RFU0  NC
  207  RST_M_AB_CPU1_FPGA_N  RESET_N  @S9S_MB_2U_LIB.S9S_MB_2U(SCH_1):RST_M_AB_CPU1_FPGA_N
  147  PWRGD_CHA_CPU1_DIMM2  PWR_GOOD||FAIL_N  @S9S_MB_2U_LIB.S9S_MB_2U(SCH_1):PWRGD_CHA_CPU1_DIMM2
  148  PD_CHA_CPU1_DIMM2_SAA    HAS  @S9S_MB_2U_LIB.S9S_MB_2U(SCH_1):PD_CHA_CPU1_DIMM2_SAA
    3  P3V3_AUX       VIN_MGMT  @S9S_MB_2U_LIB.S9S_MB_2U(SCH_1):P3V3_AUX
   87  M_A_CPU1_SB_RSP<1>  LBS||RSP_N_B  @S9S_MB_2U_LIB.S9S_MB_2U(SCH_1):M_A_CPU1_SB_RSP<1>
  227  M_A_CPU1_SB_PAR  PAR_B  @S9S_MB_2U_LIB.S9S_MB_2U(SCH_1):M_A_CPU1_SB_PAR
  113  M_A_CPU1_SB_DQ<9>  DQ_B9  @S9S_MB_2U_LIB.S9S_MB_2U(SCH_1):M_A_CPU1_SB_DQ<9>
  111  M_A_CPU1_SB_DQ<8>  DQ_B8  @S9S_MB_2U_LIB.S9S_MB_2U(SCH_1):M_A_CPU1_SB_DQ<8>
  254  M_A_CPU1_SB_DQ<7>  DQ_B7  @S9S_MB_2U_LIB.S9S_MB_2U(SCH_1):M_A_CPU1_SB_DQ<7>
  252  M_A_CPU1_SB_DQ<6>  DQ_B6  @S9S_MB_2U_LIB.S9S_MB_2U(SCH_1):M_A_CPU1_SB_DQ<6>
  109  M_A_CPU1_SB_DQ<5>  DQ_B5  @S9S_MB_2U_LIB.S9S_MB_2U(SCH_1):M_A_CPU1_SB_DQ<5>
  107  M_A_CPU1_SB_DQ<4>  DQ_B4  @S9S_MB_2U_LIB.S9S_MB_2U(SCH_1):M_A_CPU1_SB_DQ<4>
  247  M_A_CPU1_SB_DQ<3>  DQ_B3  @S9S_MB_2U_LIB.S9S_MB_2U(SCH_1):M_A_CPU1_SB_DQ<3>
  287  M_A_CPU1_SB_DQ<31>  DQ_B31  @S9S_MB_2U_LIB.S9S_MB_2U(SCH_1):M_A_CPU1_SB_DQ<31>
  285  M_A_CPU1_SB_DQ<30>  DQ_B30  @S9S_MB_2U_LIB.S9S_MB_2U(SCH_1):M_A_CPU1_SB_DQ<30>
  245  M_A_CPU1_SB_DQ<2>  DQ_B2  @S9S_MB_2U_LIB.S9S_MB_2U(SCH_1):M_A_CPU1_SB_DQ<2>
  142  M_A_CPU1_SB_DQ<29>  DQ_B29  @S9S_MB_2U_LIB.S9S_MB_2U(SCH_1):M_A_CPU1_SB_DQ<29>
  140  M_A_CPU1_SB_DQ<28>  DQ_B28  @S9S_MB_2U_LIB.S9S_MB_2U(SCH_1):M_A_CPU1_SB_DQ<28>
  280  M_A_CPU1_SB_DQ<27>  DQ_B27  @S9S_MB_2U_LIB.S9S_MB_2U(SCH_1):M_A_CPU1_SB_DQ<27>
  278  M_A_CPU1_SB_DQ<26>  DQ_B26  @S9S_MB_2U_LIB.S9S_MB_2U(SCH_1):M_A_CPU1_SB_DQ<26>
  135  M_A_CPU1_SB_DQ<25>  DQ_B25  @S9S_MB_2U_LIB.S9S_MB_2U(SCH_1):M_A_CPU1_SB_DQ<25>
  133  M_A_CPU1_SB_DQ<24>  DQ_B24  @S9S_MB_2U_LIB.S9S_MB_2U(SCH_1):M_A_CPU1_SB_DQ<24>
  276  M_A_CPU1_SB_DQ<23>  DQ_B23  @S9S_MB_2U_LIB.S9S_MB_2U(SCH_1):M_A_CPU1_SB_DQ<23>
  274  M_A_CPU1_SB_DQ<22>  DQ_B22  @S9S_MB_2U_LIB.S9S_MB_2U(SCH_1):M_A_CPU1_SB_DQ<22>
  131  M_A_CPU1_SB_DQ<21>  DQ_B21  @S9S_MB_2U_LIB.S9S_MB_2U(SCH_1):M_A_CPU1_SB_DQ<21>
  129  M_A_CPU1_SB_DQ<20>  DQ_B20  @S9S_MB_2U_LIB.S9S_MB_2U(SCH_1):M_A_CPU1_SB_DQ<20>
  102  M_A_CPU1_SB_DQ<1>  DQ_B1  @S9S_MB_2U_LIB.S9S_MB_2U(SCH_1):M_A_CPU1_SB_DQ<1>
  269  M_A_CPU1_SB_DQ<19>  DQ_B19  @S9S_MB_2U_LIB.S9S_MB_2U(SCH_1):M_A_CPU1_SB_DQ<19>
  267  M_A_CPU1_SB_DQ<18>  DQ_B18  @S9S_MB_2U_LIB.S9S_MB_2U(SCH_1):M_A_CPU1_SB_DQ<18>
  124  M_A_CPU1_SB_DQ<17>  DQ_B17  @S9S_MB_2U_LIB.S9S_MB_2U(SCH_1):M_A_CPU1_SB_DQ<17>
  122  M_A_CPU1_SB_DQ<16>  DQ_B16  @S9S_MB_2U_LIB.S9S_MB_2U(SCH_1):M_A_CPU1_SB_DQ<16>
  265  M_A_CPU1_SB_DQ<15>  DQ_B15  @S9S_MB_2U_LIB.S9S_MB_2U(SCH_1):M_A_CPU1_SB_DQ<15>
  263  M_A_CPU1_SB_DQ<14>  DQ_B14  @S9S_MB_2U_LIB.S9S_MB_2U(SCH_1):M_A_CPU1_SB_DQ<14>
  120  M_A_CPU1_SB_DQ<13>  DQ_B13  @S9S_MB_2U_LIB.S9S_MB_2U(SCH_1):M_A_CPU1_SB_DQ<13>
  118  M_A_CPU1_SB_DQ<12>  DQ_B12  @S9S_MB_2U_LIB.S9S_MB_2U(SCH_1):M_A_CPU1_SB_DQ<12>
  258  M_A_CPU1_SB_DQ<11>  DQ_B11  @S9S_MB_2U_LIB.S9S_MB_2U(SCH_1):M_A_CPU1_SB_DQ<11>
  256  M_A_CPU1_SB_DQ<10>  DQ_B10  @S9S_MB_2U_LIB.S9S_MB_2U(SCH_1):M_A_CPU1_SB_DQ<10>
  100  M_A_CPU1_SB_DQ<0>  DQ_B0  @S9S_MB_2U_LIB.S9S_MB_2U(SCH_1):M_A_CPU1_SB_DQ<0>
  229  M_A_CPU1_SB_CS_N<3>  CS1_N_B  @S9S_MB_2U_LIB.S9S_MB_2U(SCH_1):M_A_CPU1_SB_CS_N<3>
   84  M_A_CPU1_SB_CS_N<2>  CS0_N_B  @S9S_MB_2U_LIB.S9S_MB_2U(SCH_1):M_A_CPU1_SB_CS_N<2>
  236  M_A_CPU1_SB_CB<7>  CB_B7  @S9S_MB_2U_LIB.S9S_MB_2U(SCH_1):M_A_CPU1_SB_CB<7>
  234  M_A_CPU1_SB_CB<6>  CB_B6  @S9S_MB_2U_LIB.S9S_MB_2U(SCH_1):M_A_CPU1_SB_CB<6>
   91  M_A_CPU1_SB_CB<5>  CB_B5  @S9S_MB_2U_LIB.S9S_MB_2U(SCH_1):M_A_CPU1_SB_CB<5>
   89  M_A_CPU1_SB_CB<4>  CB_B4  @S9S_MB_2U_LIB.S9S_MB_2U(SCH_1):M_A_CPU1_SB_CB<4>
  243  M_A_CPU1_SB_CB<3>  CB_B3  @S9S_MB_2U_LIB.S9S_MB_2U(SCH_1):M_A_CPU1_SB_CB<3>
  241  M_A_CPU1_SB_CB<2>  CB_B2  @S9S_MB_2U_LIB.S9S_MB_2U(SCH_1):M_A_CPU1_SB_CB<2>
   98  M_A_CPU1_SB_CB<1>  CB_B1  @S9S_MB_2U_LIB.S9S_MB_2U(SCH_1):M_A_CPU1_SB_CB<1>
   96  M_A_CPU1_SB_CB<0>  CB_B0  @S9S_MB_2U_LIB.S9S_MB_2U(SCH_1):M_A_CPU1_SB_CB<0>
   82  M_A_CPU1_SB_CA<6>  CA6_B  @S9S_MB_2U_LIB.S9S_MB_2U(SCH_1):M_A_CPU1_SB_CA<6>
  225  M_A_CPU1_SB_CA<5>  CA5_B  @S9S_MB_2U_LIB.S9S_MB_2U(SCH_1):M_A_CPU1_SB_CA<5>
   80  M_A_CPU1_SB_CA<4>  CA4_B  @S9S_MB_2U_LIB.S9S_MB_2U(SCH_1):M_A_CPU1_SB_CA<4>
  223  M_A_CPU1_SB_CA<3>  CA3_B  @S9S_MB_2U_LIB.S9S_MB_2U(SCH_1):M_A_CPU1_SB_CA<3>
   78  M_A_CPU1_SB_CA<2>  CA2_B  @S9S_MB_2U_LIB.S9S_MB_2U(SCH_1):M_A_CPU1_SB_CA<2>
  221  M_A_CPU1_SB_CA<1>  CA1_B  @S9S_MB_2U_LIB.S9S_MB_2U(SCH_1):M_A_CPU1_SB_CA<1>
   76  M_A_CPU1_SB_CA<0>  CA0_B  @S9S_MB_2U_LIB.S9S_MB_2U(SCH_1):M_A_CPU1_SB_CA<0>
   86  M_A_CPU1_SA_RSP<1>  LBD||RSP_N_A  @S9S_MB_2U_LIB.S9S_MB_2U(SCH_1):M_A_CPU1_SA_RSP<1>
   74  M_A_CPU1_SA_PAR  PAR_A  @S9S_MB_2U_LIB.S9S_MB_2U(SCH_1):M_A_CPU1_SA_PAR
   20  M_A_CPU1_SA_DQ<9>  DQ_A9  @S9S_MB_2U_LIB.S9S_MB_2U(SCH_1):M_A_CPU1_SA_DQ<9>
   18  M_A_CPU1_SA_DQ<8>  DQ_A8  @S9S_MB_2U_LIB.S9S_MB_2U(SCH_1):M_A_CPU1_SA_DQ<8>
  161  M_A_CPU1_SA_DQ<7>  DQ_A7  @S9S_MB_2U_LIB.S9S_MB_2U(SCH_1):M_A_CPU1_SA_DQ<7>
  159  M_A_CPU1_SA_DQ<6>  DQ_A6  @S9S_MB_2U_LIB.S9S_MB_2U(SCH_1):M_A_CPU1_SA_DQ<6>
   16  M_A_CPU1_SA_DQ<5>  DQ_A5  @S9S_MB_2U_LIB.S9S_MB_2U(SCH_1):M_A_CPU1_SA_DQ<5>
   14  M_A_CPU1_SA_DQ<4>  DQ_A4  @S9S_MB_2U_LIB.S9S_MB_2U(SCH_1):M_A_CPU1_SA_DQ<4>
  154  M_A_CPU1_SA_DQ<3>  DQ_A3  @S9S_MB_2U_LIB.S9S_MB_2U(SCH_1):M_A_CPU1_SA_DQ<3>
  194  M_A_CPU1_SA_DQ<31>  DQ_A31  @S9S_MB_2U_LIB.S9S_MB_2U(SCH_1):M_A_CPU1_SA_DQ<31>
  192  M_A_CPU1_SA_DQ<30>  DQ_A30  @S9S_MB_2U_LIB.S9S_MB_2U(SCH_1):M_A_CPU1_SA_DQ<30>
  152  M_A_CPU1_SA_DQ<2>  DQ_A2  @S9S_MB_2U_LIB.S9S_MB_2U(SCH_1):M_A_CPU1_SA_DQ<2>
   49  M_A_CPU1_SA_DQ<29>  DQ_A29  @S9S_MB_2U_LIB.S9S_MB_2U(SCH_1):M_A_CPU1_SA_DQ<29>
   47  M_A_CPU1_SA_DQ<28>  DQ_A28  @S9S_MB_2U_LIB.S9S_MB_2U(SCH_1):M_A_CPU1_SA_DQ<28>
  187  M_A_CPU1_SA_DQ<27>  DQ_A27  @S9S_MB_2U_LIB.S9S_MB_2U(SCH_1):M_A_CPU1_SA_DQ<27>
  185  M_A_CPU1_SA_DQ<26>  DQ_A26  @S9S_MB_2U_LIB.S9S_MB_2U(SCH_1):M_A_CPU1_SA_DQ<26>
   42  M_A_CPU1_SA_DQ<25>  DQ_A25  @S9S_MB_2U_LIB.S9S_MB_2U(SCH_1):M_A_CPU1_SA_DQ<25>
   40  M_A_CPU1_SA_DQ<24>  DQ_A24  @S9S_MB_2U_LIB.S9S_MB_2U(SCH_1):M_A_CPU1_SA_DQ<24>
  183  M_A_CPU1_SA_DQ<23>  DQ_A23  @S9S_MB_2U_LIB.S9S_MB_2U(SCH_1):M_A_CPU1_SA_DQ<23>
  181  M_A_CPU1_SA_DQ<22>  DQ_A22  @S9S_MB_2U_LIB.S9S_MB_2U(SCH_1):M_A_CPU1_SA_DQ<22>
   38  M_A_CPU1_SA_DQ<21>  DQ_A21  @S9S_MB_2U_LIB.S9S_MB_2U(SCH_1):M_A_CPU1_SA_DQ<21>
   36  M_A_CPU1_SA_DQ<20>  DQ_A20  @S9S_MB_2U_LIB.S9S_MB_2U(SCH_1):M_A_CPU1_SA_DQ<20>
    9  M_A_CPU1_SA_DQ<1>  DQ_A1  @S9S_MB_2U_LIB.S9S_MB_2U(SCH_1):M_A_CPU1_SA_DQ<1>
  176  M_A_CPU1_SA_DQ<19>  DQ_A19  @S9S_MB_2U_LIB.S9S_MB_2U(SCH_1):M_A_CPU1_SA_DQ<19>
  174  M_A_CPU1_SA_DQ<18>  DQ_A18  @S9S_MB_2U_LIB.S9S_MB_2U(SCH_1):M_A_CPU1_SA_DQ<18>
   31  M_A_CPU1_SA_DQ<17>  DQ_A17  @S9S_MB_2U_LIB.S9S_MB_2U(SCH_1):M_A_CPU1_SA_DQ<17>
   29  M_A_CPU1_SA_DQ<16>  DQ_A16  @S9S_MB_2U_LIB.S9S_MB_2U(SCH_1):M_A_CPU1_SA_DQ<16>
  172  M_A_CPU1_SA_DQ<15>  DQ_A15  @S9S_MB_2U_LIB.S9S_MB_2U(SCH_1):M_A_CPU1_SA_DQ<15>
  170  M_A_CPU1_SA_DQ<14>  DQ_A14  @S9S_MB_2U_LIB.S9S_MB_2U(SCH_1):M_A_CPU1_SA_DQ<14>
   27  M_A_CPU1_SA_DQ<13>  DQ_A13  @S9S_MB_2U_LIB.S9S_MB_2U(SCH_1):M_A_CPU1_SA_DQ<13>
   25  M_A_CPU1_SA_DQ<12>  DQ_A12  @S9S_MB_2U_LIB.S9S_MB_2U(SCH_1):M_A_CPU1_SA_DQ<12>
  165  M_A_CPU1_SA_DQ<11>  DQ_A11  @S9S_MB_2U_LIB.S9S_MB_2U(SCH_1):M_A_CPU1_SA_DQ<11>
  163  M_A_CPU1_SA_DQ<10>  DQ_A10  @S9S_MB_2U_LIB.S9S_MB_2U(SCH_1):M_A_CPU1_SA_DQ<10>
    7  M_A_CPU1_SA_DQ<0>  DQ_A0  @S9S_MB_2U_LIB.S9S_MB_2U(SCH_1):M_A_CPU1_SA_DQ<0>
  209  M_A_CPU1_SA_CS_N<3>  CS1_N_A  @S9S_MB_2U_LIB.S9S_MB_2U(SCH_1):M_A_CPU1_SA_CS_N<3>
   64  M_A_CPU1_SA_CS_N<2>  CS0_N_A  @S9S_MB_2U_LIB.S9S_MB_2U(SCH_1):M_A_CPU1_SA_CS_N<2>
  205  M_A_CPU1_SA_CB<7>  CB_A7  @S9S_MB_2U_LIB.S9S_MB_2U(SCH_1):M_A_CPU1_SA_CB<7>
  203  M_A_CPU1_SA_CB<6>  CB_A6  @S9S_MB_2U_LIB.S9S_MB_2U(SCH_1):M_A_CPU1_SA_CB<6>
   60  M_A_CPU1_SA_CB<5>  CB_A5  @S9S_MB_2U_LIB.S9S_MB_2U(SCH_1):M_A_CPU1_SA_CB<5>
   58  M_A_CPU1_SA_CB<4>  CB_A4  @S9S_MB_2U_LIB.S9S_MB_2U(SCH_1):M_A_CPU1_SA_CB<4>
  198  M_A_CPU1_SA_CB<3>  CB_A3  @S9S_MB_2U_LIB.S9S_MB_2U(SCH_1):M_A_CPU1_SA_CB<3>
  196  M_A_CPU1_SA_CB<2>  CB_A2  @S9S_MB_2U_LIB.S9S_MB_2U(SCH_1):M_A_CPU1_SA_CB<2>
   53  M_A_CPU1_SA_CB<1>  CB_A1  @S9S_MB_2U_LIB.S9S_MB_2U(SCH_1):M_A_CPU1_SA_CB<1>
   51  M_A_CPU1_SA_CB<0>  CB_A0  @S9S_MB_2U_LIB.S9S_MB_2U(SCH_1):M_A_CPU1_SA_CB<0>
   72  M_A_CPU1_SA_CA<6>  CA6_A  @S9S_MB_2U_LIB.S9S_MB_2U(SCH_1):M_A_CPU1_SA_CA<6>
  215  M_A_CPU1_SA_CA<5>  CA5_A  @S9S_MB_2U_LIB.S9S_MB_2U(SCH_1):M_A_CPU1_SA_CA<5>
   70  M_A_CPU1_SA_CA<4>  CA4_A  @S9S_MB_2U_LIB.S9S_MB_2U(SCH_1):M_A_CPU1_SA_CA<4>
  213  M_A_CPU1_SA_CA<3>  CA3_A  @S9S_MB_2U_LIB.S9S_MB_2U(SCH_1):M_A_CPU1_SA_CA<3>
   68  M_A_CPU1_SA_CA<2>  CA2_A  @S9S_MB_2U_LIB.S9S_MB_2U(SCH_1):M_A_CPU1_SA_CA<2>
  211  M_A_CPU1_SA_CA<1>  CA1_A  @S9S_MB_2U_LIB.S9S_MB_2U(SCH_1):M_A_CPU1_SA_CA<1>
   66  M_A_CPU1_SA_CA<0>  CA0_A  @S9S_MB_2U_LIB.S9S_MB_2U(SCH_1):M_A_CPU1_SA_CA<0>
  217  M_A_CPU1_CLK_DP<1>   CK_P  @S9S_MB_2U_LIB.S9S_MB_2U(SCH_1):M_A_CPU1_CLK_DP<1>
  218  M_A_CPU1_CLK_DN<1>   CK_N  @S9S_MB_2U_LIB.S9S_MB_2U(SCH_1):M_A_CPU1_CLK_DN<1>
   62  M_A_CPU1_ALERT_N  ALERT_N  @S9S_MB_2U_LIB.S9S_MB_2U(SCH_1):M_A_CPU1_ALERT_N
    5  I3C_SPD_DDRABCD_CPU1_LVC1_SDA   HSDA  @S9S_MB_2U_LIB.S9S_MB_2U(SCH_1):I3C_SPD_DDRABCD_CPU1_LVC1_SDA
    4  I3C_SPD_DDRABCD_CPU1_LVC1_SCL   HSCL  @S9S_MB_2U_LIB.S9S_MB_2U(SCH_1):I3C_SPD_DDRABCD_CPU1_LVC1_SCL

SCONN288_ADR50001P013C01  I175  J19    [SCONN288_ADR50001P013C01-SCONNA]
  146  P12V_S3_AUX_CPU1_NVDIMM  VIN_BULK2  @S9S_MB_2U_LIB.S9S_MB_2U(SCH_1):P12V_S3_AUX_CPU1_NVDIMM
  145  P12V_S3_AUX_CPU1_NVDIMM  VIN_BULK1  @S9S_MB_2U_LIB.S9S_MB_2U(SCH_1):P12V_S3_AUX_CPU1_NVDIMM
    1  P12V_S3_AUX_CPU1_NVDIMM  VIN_BULK0  @S9S_MB_2U_LIB.S9S_MB_2U(SCH_1):P12V_S3_AUX_CPU1_NVDIMM
  288  GND            VSS126  @S9S_MB_2U_LIB.S9S_MB_2U(SCH_1):GND
  286  GND            VSS125  @S9S_MB_2U_LIB.S9S_MB_2U(SCH_1):GND
  284  GND            VSS124  @S9S_MB_2U_LIB.S9S_MB_2U(SCH_1):GND
  281  GND            VSS123  @S9S_MB_2U_LIB.S9S_MB_2U(SCH_1):GND
  279  GND            VSS122  @S9S_MB_2U_LIB.S9S_MB_2U(SCH_1):GND
  277  GND            VSS121  @S9S_MB_2U_LIB.S9S_MB_2U(SCH_1):GND
  275  GND            VSS120  @S9S_MB_2U_LIB.S9S_MB_2U(SCH_1):GND
  273  GND            VSS119  @S9S_MB_2U_LIB.S9S_MB_2U(SCH_1):GND
  270  GND            VSS118  @S9S_MB_2U_LIB.S9S_MB_2U(SCH_1):GND
  268  GND            VSS117  @S9S_MB_2U_LIB.S9S_MB_2U(SCH_1):GND
  266  GND            VSS116  @S9S_MB_2U_LIB.S9S_MB_2U(SCH_1):GND
  264  GND            VSS115  @S9S_MB_2U_LIB.S9S_MB_2U(SCH_1):GND
  262  GND            VSS114  @S9S_MB_2U_LIB.S9S_MB_2U(SCH_1):GND
  259  GND            VSS113  @S9S_MB_2U_LIB.S9S_MB_2U(SCH_1):GND
  257  GND            VSS112  @S9S_MB_2U_LIB.S9S_MB_2U(SCH_1):GND
  255  GND            VSS111  @S9S_MB_2U_LIB.S9S_MB_2U(SCH_1):GND
  253  GND            VSS110  @S9S_MB_2U_LIB.S9S_MB_2U(SCH_1):GND
  251  GND            VSS109  @S9S_MB_2U_LIB.S9S_MB_2U(SCH_1):GND
  248  GND            VSS108  @S9S_MB_2U_LIB.S9S_MB_2U(SCH_1):GND
  246  GND            VSS107  @S9S_MB_2U_LIB.S9S_MB_2U(SCH_1):GND
  244  GND            VSS106  @S9S_MB_2U_LIB.S9S_MB_2U(SCH_1):GND
  242  GND            VSS105  @S9S_MB_2U_LIB.S9S_MB_2U(SCH_1):GND
  240  GND            VSS104  @S9S_MB_2U_LIB.S9S_MB_2U(SCH_1):GND
  237  GND            VSS103  @S9S_MB_2U_LIB.S9S_MB_2U(SCH_1):GND
  235  GND            VSS102  @S9S_MB_2U_LIB.S9S_MB_2U(SCH_1):GND
  233  GND            VSS101  @S9S_MB_2U_LIB.S9S_MB_2U(SCH_1):GND
  230  GND            VSS100  @S9S_MB_2U_LIB.S9S_MB_2U(SCH_1):GND
  228  GND            VSS99  @S9S_MB_2U_LIB.S9S_MB_2U(SCH_1):GND
  226  GND            VSS98  @S9S_MB_2U_LIB.S9S_MB_2U(SCH_1):GND
  224  GND            VSS97  @S9S_MB_2U_LIB.S9S_MB_2U(SCH_1):GND
  222  GND            VSS96  @S9S_MB_2U_LIB.S9S_MB_2U(SCH_1):GND
  219  GND            VSS95  @S9S_MB_2U_LIB.S9S_MB_2U(SCH_1):GND
  216  GND            VSS94  @S9S_MB_2U_LIB.S9S_MB_2U(SCH_1):GND
  214  GND            VSS93  @S9S_MB_2U_LIB.S9S_MB_2U(SCH_1):GND
  212  GND            VSS92  @S9S_MB_2U_LIB.S9S_MB_2U(SCH_1):GND
  210  GND            VSS91  @S9S_MB_2U_LIB.S9S_MB_2U(SCH_1):GND
  208  GND            VSS90  @S9S_MB_2U_LIB.S9S_MB_2U(SCH_1):GND
  206  GND            VSS89  @S9S_MB_2U_LIB.S9S_MB_2U(SCH_1):GND
  204  GND            VSS88  @S9S_MB_2U_LIB.S9S_MB_2U(SCH_1):GND
  202  GND            VSS87  @S9S_MB_2U_LIB.S9S_MB_2U(SCH_1):GND
  199  GND            VSS86  @S9S_MB_2U_LIB.S9S_MB_2U(SCH_1):GND
  197  GND            VSS85  @S9S_MB_2U_LIB.S9S_MB_2U(SCH_1):GND
  195  GND            VSS84  @S9S_MB_2U_LIB.S9S_MB_2U(SCH_1):GND
  193  GND            VSS83  @S9S_MB_2U_LIB.S9S_MB_2U(SCH_1):GND
  191  GND            VSS82  @S9S_MB_2U_LIB.S9S_MB_2U(SCH_1):GND
  188  GND            VSS81  @S9S_MB_2U_LIB.S9S_MB_2U(SCH_1):GND
  186  GND            VSS80  @S9S_MB_2U_LIB.S9S_MB_2U(SCH_1):GND
  184  GND            VSS79  @S9S_MB_2U_LIB.S9S_MB_2U(SCH_1):GND
  182  GND            VSS78  @S9S_MB_2U_LIB.S9S_MB_2U(SCH_1):GND
  180  GND            VSS77  @S9S_MB_2U_LIB.S9S_MB_2U(SCH_1):GND
  177  GND            VSS76  @S9S_MB_2U_LIB.S9S_MB_2U(SCH_1):GND
  175  GND            VSS75  @S9S_MB_2U_LIB.S9S_MB_2U(SCH_1):GND
  173  GND            VSS74  @S9S_MB_2U_LIB.S9S_MB_2U(SCH_1):GND
  171  GND            VSS73  @S9S_MB_2U_LIB.S9S_MB_2U(SCH_1):GND
  169  GND            VSS72  @S9S_MB_2U_LIB.S9S_MB_2U(SCH_1):GND
  166  GND            VSS71  @S9S_MB_2U_LIB.S9S_MB_2U(SCH_1):GND
  164  GND            VSS70  @S9S_MB_2U_LIB.S9S_MB_2U(SCH_1):GND
  162  GND            VSS69  @S9S_MB_2U_LIB.S9S_MB_2U(SCH_1):GND
  160  GND            VSS68  @S9S_MB_2U_LIB.S9S_MB_2U(SCH_1):GND
  158  GND            VSS67  @S9S_MB_2U_LIB.S9S_MB_2U(SCH_1):GND
  155  GND            VSS66  @S9S_MB_2U_LIB.S9S_MB_2U(SCH_1):GND
  153  GND            VSS65  @S9S_MB_2U_LIB.S9S_MB_2U(SCH_1):GND
  151  GND            VSS64  @S9S_MB_2U_LIB.S9S_MB_2U(SCH_1):GND
  143  GND            VSS63  @S9S_MB_2U_LIB.S9S_MB_2U(SCH_1):GND
  141  GND            VSS62  @S9S_MB_2U_LIB.S9S_MB_2U(SCH_1):GND
  139  GND            VSS61  @S9S_MB_2U_LIB.S9S_MB_2U(SCH_1):GND
  136  GND            VSS60  @S9S_MB_2U_LIB.S9S_MB_2U(SCH_1):GND
  134  GND            VSS59  @S9S_MB_2U_LIB.S9S_MB_2U(SCH_1):GND
  132  GND            VSS58  @S9S_MB_2U_LIB.S9S_MB_2U(SCH_1):GND
  130  GND            VSS57  @S9S_MB_2U_LIB.S9S_MB_2U(SCH_1):GND
  128  GND            VSS56  @S9S_MB_2U_LIB.S9S_MB_2U(SCH_1):GND
  125  GND            VSS55  @S9S_MB_2U_LIB.S9S_MB_2U(SCH_1):GND
  123  GND            VSS54  @S9S_MB_2U_LIB.S9S_MB_2U(SCH_1):GND
  121  GND            VSS53  @S9S_MB_2U_LIB.S9S_MB_2U(SCH_1):GND
  119  GND            VSS52  @S9S_MB_2U_LIB.S9S_MB_2U(SCH_1):GND
  117  GND            VSS51  @S9S_MB_2U_LIB.S9S_MB_2U(SCH_1):GND
  114  GND            VSS50  @S9S_MB_2U_LIB.S9S_MB_2U(SCH_1):GND
  112  GND            VSS49  @S9S_MB_2U_LIB.S9S_MB_2U(SCH_1):GND
  110  GND            VSS48  @S9S_MB_2U_LIB.S9S_MB_2U(SCH_1):GND
  108  GND            VSS47  @S9S_MB_2U_LIB.S9S_MB_2U(SCH_1):GND
  106  GND            VSS46  @S9S_MB_2U_LIB.S9S_MB_2U(SCH_1):GND
  103  GND            VSS45  @S9S_MB_2U_LIB.S9S_MB_2U(SCH_1):GND
  101  GND            VSS44  @S9S_MB_2U_LIB.S9S_MB_2U(SCH_1):GND
   99  GND            VSS43  @S9S_MB_2U_LIB.S9S_MB_2U(SCH_1):GND
   97  GND            VSS42  @S9S_MB_2U_LIB.S9S_MB_2U(SCH_1):GND
   95  GND            VSS41  @S9S_MB_2U_LIB.S9S_MB_2U(SCH_1):GND
   92  GND            VSS40  @S9S_MB_2U_LIB.S9S_MB_2U(SCH_1):GND
   90  GND            VSS39  @S9S_MB_2U_LIB.S9S_MB_2U(SCH_1):GND
   88  GND            VSS38  @S9S_MB_2U_LIB.S9S_MB_2U(SCH_1):GND
   85  GND            VSS37  @S9S_MB_2U_LIB.S9S_MB_2U(SCH_1):GND
   83  GND            VSS36  @S9S_MB_2U_LIB.S9S_MB_2U(SCH_1):GND
   81  GND            VSS35  @S9S_MB_2U_LIB.S9S_MB_2U(SCH_1):GND
   79  GND            VSS34  @S9S_MB_2U_LIB.S9S_MB_2U(SCH_1):GND
   77  GND            VSS33  @S9S_MB_2U_LIB.S9S_MB_2U(SCH_1):GND
   75  GND            VSS32  @S9S_MB_2U_LIB.S9S_MB_2U(SCH_1):GND
   73  GND            VSS31  @S9S_MB_2U_LIB.S9S_MB_2U(SCH_1):GND
   71  GND            VSS30  @S9S_MB_2U_LIB.S9S_MB_2U(SCH_1):GND
   69  GND            VSS29  @S9S_MB_2U_LIB.S9S_MB_2U(SCH_1):GND
   67  GND            VSS28  @S9S_MB_2U_LIB.S9S_MB_2U(SCH_1):GND
   65  GND            VSS27  @S9S_MB_2U_LIB.S9S_MB_2U(SCH_1):GND
   63  GND            VSS26  @S9S_MB_2U_LIB.S9S_MB_2U(SCH_1):GND
   61  GND            VSS25  @S9S_MB_2U_LIB.S9S_MB_2U(SCH_1):GND
   59  GND            VSS24  @S9S_MB_2U_LIB.S9S_MB_2U(SCH_1):GND
   57  GND            VSS23  @S9S_MB_2U_LIB.S9S_MB_2U(SCH_1):GND
   54  GND            VSS22  @S9S_MB_2U_LIB.S9S_MB_2U(SCH_1):GND
   52  GND            VSS21  @S9S_MB_2U_LIB.S9S_MB_2U(SCH_1):GND
   50  GND            VSS20  @S9S_MB_2U_LIB.S9S_MB_2U(SCH_1):GND
   48  GND            VSS19  @S9S_MB_2U_LIB.S9S_MB_2U(SCH_1):GND
   46  GND            VSS18  @S9S_MB_2U_LIB.S9S_MB_2U(SCH_1):GND
   43  GND            VSS17  @S9S_MB_2U_LIB.S9S_MB_2U(SCH_1):GND
   41  GND            VSS16  @S9S_MB_2U_LIB.S9S_MB_2U(SCH_1):GND
   39  GND            VSS15  @S9S_MB_2U_LIB.S9S_MB_2U(SCH_1):GND
   37  GND            VSS14  @S9S_MB_2U_LIB.S9S_MB_2U(SCH_1):GND
   35  GND            VSS13  @S9S_MB_2U_LIB.S9S_MB_2U(SCH_1):GND
   32  GND            VSS12  @S9S_MB_2U_LIB.S9S_MB_2U(SCH_1):GND
   30  GND            VSS11  @S9S_MB_2U_LIB.S9S_MB_2U(SCH_1):GND
   28  GND            VSS10  @S9S_MB_2U_LIB.S9S_MB_2U(SCH_1):GND
   26  GND             VSS9  @S9S_MB_2U_LIB.S9S_MB_2U(SCH_1):GND
   24  GND             VSS8  @S9S_MB_2U_LIB.S9S_MB_2U(SCH_1):GND
   21  GND             VSS7  @S9S_MB_2U_LIB.S9S_MB_2U(SCH_1):GND
   19  GND             VSS6  @S9S_MB_2U_LIB.S9S_MB_2U(SCH_1):GND
   17  GND             VSS5  @S9S_MB_2U_LIB.S9S_MB_2U(SCH_1):GND
   15  GND             VSS4  @S9S_MB_2U_LIB.S9S_MB_2U(SCH_1):GND
   13  GND             VSS3  @S9S_MB_2U_LIB.S9S_MB_2U(SCH_1):GND
   10  GND             VSS2  @S9S_MB_2U_LIB.S9S_MB_2U(SCH_1):GND
    8  GND             VSS1  @S9S_MB_2U_LIB.S9S_MB_2U(SCH_1):GND
    6  GND             VSS0  @S9S_MB_2U_LIB.S9S_MB_2U(SCH_1):GND
   G3  GND               G3  @S9S_MB_2U_LIB.S9S_MB_2U(SCH_1):GND
   G2  GND               G2  @S9S_MB_2U_LIB.S9S_MB_2U(SCH_1):GND
   G1  GND               G1  @S9S_MB_2U_LIB.S9S_MB_2U(SCH_1):GND

SCONN288_ADR50001P013C01  I126  J19    [SCONN288_ADR50001P013C01-SCONNA]
   93  M_B_CPU1_SB_DQS_DP<9>  DQS9_B_P  @S9S_MB_2U_LIB.S9S_MB_2U(SCH_1):M_B_CPU1_SB_DQS_DP<9>
  283  M_B_CPU1_SB_DQS_DP<8>  DQS8_B_P  @S9S_MB_2U_LIB.S9S_MB_2U(SCH_1):M_B_CPU1_SB_DQS_DP<8>
  272  M_B_CPU1_SB_DQS_DP<7>  DQS7_B_P  @S9S_MB_2U_LIB.S9S_MB_2U(SCH_1):M_B_CPU1_SB_DQS_DP<7>
  261  M_B_CPU1_SB_DQS_DP<6>  DQS6_B_P  @S9S_MB_2U_LIB.S9S_MB_2U(SCH_1):M_B_CPU1_SB_DQS_DP<6>
  250  M_B_CPU1_SB_DQS_DP<5>  DQS5_B_P  @S9S_MB_2U_LIB.S9S_MB_2U(SCH_1):M_B_CPU1_SB_DQS_DP<5>
  239  M_B_CPU1_SB_DQS_DP<4>  DQS4_B_P  @S9S_MB_2U_LIB.S9S_MB_2U(SCH_1):M_B_CPU1_SB_DQS_DP<4>
  137  M_B_CPU1_SB_DQS_DP<3>  DQS3_B_P  @S9S_MB_2U_LIB.S9S_MB_2U(SCH_1):M_B_CPU1_SB_DQS_DP<3>
  126  M_B_CPU1_SB_DQS_DP<2>  DQS2_B_P  @S9S_MB_2U_LIB.S9S_MB_2U(SCH_1):M_B_CPU1_SB_DQS_DP<2>
  115  M_B_CPU1_SB_DQS_DP<1>  DQS1_B_P  @S9S_MB_2U_LIB.S9S_MB_2U(SCH_1):M_B_CPU1_SB_DQS_DP<1>
  104  M_B_CPU1_SB_DQS_DP<0>  DQS0_B_P  @S9S_MB_2U_LIB.S9S_MB_2U(SCH_1):M_B_CPU1_SB_DQS_DP<0>
   94  M_B_CPU1_SB_DQS_DN<9>  DQS9_B_N  @S9S_MB_2U_LIB.S9S_MB_2U(SCH_1):M_B_CPU1_SB_DQS_DN<9>
  282  M_B_CPU1_SB_DQS_DN<8>  DQS8_B_N  @S9S_MB_2U_LIB.S9S_MB_2U(SCH_1):M_B_CPU1_SB_DQS_DN<8>
  271  M_B_CPU1_SB_DQS_DN<7>  DQS7_B_N  @S9S_MB_2U_LIB.S9S_MB_2U(SCH_1):M_B_CPU1_SB_DQS_DN<7>
  260  M_B_CPU1_SB_DQS_DN<6>  DQS6_B_N  @S9S_MB_2U_LIB.S9S_MB_2U(SCH_1):M_B_CPU1_SB_DQS_DN<6>
  249  M_B_CPU1_SB_DQS_DN<5>  DQS5_B_N  @S9S_MB_2U_LIB.S9S_MB_2U(SCH_1):M_B_CPU1_SB_DQS_DN<5>
  238  M_B_CPU1_SB_DQS_DN<4>  DQS4_B_N  @S9S_MB_2U_LIB.S9S_MB_2U(SCH_1):M_B_CPU1_SB_DQS_DN<4>
  138  M_B_CPU1_SB_DQS_DN<3>  DQS3_B_N  @S9S_MB_2U_LIB.S9S_MB_2U(SCH_1):M_B_CPU1_SB_DQS_DN<3>
  127  M_B_CPU1_SB_DQS_DN<2>  DQS2_B_N  @S9S_MB_2U_LIB.S9S_MB_2U(SCH_1):M_B_CPU1_SB_DQS_DN<2>
  116  M_B_CPU1_SB_DQS_DN<1>  DQS1_B_N  @S9S_MB_2U_LIB.S9S_MB_2U(SCH_1):M_B_CPU1_SB_DQS_DN<1>
  105  M_B_CPU1_SB_DQS_DN<0>  DQS0_B_N  @S9S_MB_2U_LIB.S9S_MB_2U(SCH_1):M_B_CPU1_SB_DQS_DN<0>
  201  M_B_CPU1_SA_DQS_DP<9>  DQS9_A_P  @S9S_MB_2U_LIB.S9S_MB_2U(SCH_1):M_B_CPU1_SA_DQS_DP<9>
  190  M_B_CPU1_SA_DQS_DP<8>  DQS8_A_P  @S9S_MB_2U_LIB.S9S_MB_2U(SCH_1):M_B_CPU1_SA_DQS_DP<8>
  179  M_B_CPU1_SA_DQS_DP<7>  DQS7_A_P  @S9S_MB_2U_LIB.S9S_MB_2U(SCH_1):M_B_CPU1_SA_DQS_DP<7>
  168  M_B_CPU1_SA_DQS_DP<6>  DQS6_A_P  @S9S_MB_2U_LIB.S9S_MB_2U(SCH_1):M_B_CPU1_SA_DQS_DP<6>
  157  M_B_CPU1_SA_DQS_DP<5>  DQS5_A_P  @S9S_MB_2U_LIB.S9S_MB_2U(SCH_1):M_B_CPU1_SA_DQS_DP<5>
   55  M_B_CPU1_SA_DQS_DP<4>  DQS4_A_P  @S9S_MB_2U_LIB.S9S_MB_2U(SCH_1):M_B_CPU1_SA_DQS_DP<4>
   44  M_B_CPU1_SA_DQS_DP<3>  DQS3_A_P  @S9S_MB_2U_LIB.S9S_MB_2U(SCH_1):M_B_CPU1_SA_DQS_DP<3>
   33  M_B_CPU1_SA_DQS_DP<2>  DQS2_A_P  @S9S_MB_2U_LIB.S9S_MB_2U(SCH_1):M_B_CPU1_SA_DQS_DP<2>
   22  M_B_CPU1_SA_DQS_DP<1>  DQS1_A_P  @S9S_MB_2U_LIB.S9S_MB_2U(SCH_1):M_B_CPU1_SA_DQS_DP<1>
   11  M_B_CPU1_SA_DQS_DP<0>  DQS0_A_P  @S9S_MB_2U_LIB.S9S_MB_2U(SCH_1):M_B_CPU1_SA_DQS_DP<0>
  200  M_B_CPU1_SA_DQS_DN<9>  DQS9_A_N  @S9S_MB_2U_LIB.S9S_MB_2U(SCH_1):M_B_CPU1_SA_DQS_DN<9>
  189  M_B_CPU1_SA_DQS_DN<8>  DQS8_A_N  @S9S_MB_2U_LIB.S9S_MB_2U(SCH_1):M_B_CPU1_SA_DQS_DN<8>
  178  M_B_CPU1_SA_DQS_DN<7>  DQS7_A_N  @S9S_MB_2U_LIB.S9S_MB_2U(SCH_1):M_B_CPU1_SA_DQS_DN<7>
  167  M_B_CPU1_SA_DQS_DN<6>  DQS6_A_N  @S9S_MB_2U_LIB.S9S_MB_2U(SCH_1):M_B_CPU1_SA_DQS_DN<6>
  156  M_B_CPU1_SA_DQS_DN<5>  DQS5_A_N  @S9S_MB_2U_LIB.S9S_MB_2U(SCH_1):M_B_CPU1_SA_DQS_DN<5>
   56  M_B_CPU1_SA_DQS_DN<4>  DQS4_A_N  @S9S_MB_2U_LIB.S9S_MB_2U(SCH_1):M_B_CPU1_SA_DQS_DN<4>
   45  M_B_CPU1_SA_DQS_DN<3>  DQS3_A_N  @S9S_MB_2U_LIB.S9S_MB_2U(SCH_1):M_B_CPU1_SA_DQS_DN<3>
   34  M_B_CPU1_SA_DQS_DN<2>  DQS2_A_N  @S9S_MB_2U_LIB.S9S_MB_2U(SCH_1):M_B_CPU1_SA_DQS_DN<2>
   23  M_B_CPU1_SA_DQS_DN<1>  DQS1_A_N  @S9S_MB_2U_LIB.S9S_MB_2U(SCH_1):M_B_CPU1_SA_DQS_DN<1>
   12  M_B_CPU1_SA_DQS_DN<0>  DQS0_A_N  @S9S_MB_2U_LIB.S9S_MB_2U(SCH_1):M_B_CPU1_SA_DQS_DN<0>

SCONN288_ADR50001P013C01  I25  J19    [SCONN288_ADR50001P013C01-SCONNA]
  232  NC              RFU6  NC
  231  NC              RFU5  NC
  220  NC              RFU4  NC
  150  NC              RFU3  NC
  149  NC              RFU2  NC
  144  NC              RFU1  NC
    2  NC              RFU0  NC
  207  RST_M_AB_CPU1_FPGA_N  RESET_N  @S9S_MB_2U_LIB.S9S_MB_2U(SCH_1):RST_M_AB_CPU1_FPGA_N
  147  PWRGD_CHB_CPU1_DIMM1  PWR_GOOD||FAIL_N  @S9S_MB_2U_LIB.S9S_MB_2U(SCH_1):PWRGD_CHB_CPU1_DIMM1
  148  PD_CHB_CPU1_DIMM1_SAA    HAS  @S9S_MB_2U_LIB.S9S_MB_2U(SCH_1):PD_CHB_CPU1_DIMM1_SAA
    3  P3V3_AUX       VIN_MGMT  @S9S_MB_2U_LIB.S9S_MB_2U(SCH_1):P3V3_AUX
   87  M_B_CPU1_SB_RSP<0>  LBS||RSP_N_B  @S9S_MB_2U_LIB.S9S_MB_2U(SCH_1):M_B_CPU1_SB_RSP<0>
  227  M_B_CPU1_SB_PAR  PAR_B  @S9S_MB_2U_LIB.S9S_MB_2U(SCH_1):M_B_CPU1_SB_PAR
  113  M_B_CPU1_SB_DQ<9>  DQ_B9  @S9S_MB_2U_LIB.S9S_MB_2U(SCH_1):M_B_CPU1_SB_DQ<9>
  111  M_B_CPU1_SB_DQ<8>  DQ_B8  @S9S_MB_2U_LIB.S9S_MB_2U(SCH_1):M_B_CPU1_SB_DQ<8>
  254  M_B_CPU1_SB_DQ<7>  DQ_B7  @S9S_MB_2U_LIB.S9S_MB_2U(SCH_1):M_B_CPU1_SB_DQ<7>
  252  M_B_CPU1_SB_DQ<6>  DQ_B6  @S9S_MB_2U_LIB.S9S_MB_2U(SCH_1):M_B_CPU1_SB_DQ<6>
  109  M_B_CPU1_SB_DQ<5>  DQ_B5  @S9S_MB_2U_LIB.S9S_MB_2U(SCH_1):M_B_CPU1_SB_DQ<5>
  107  M_B_CPU1_SB_DQ<4>  DQ_B4  @S9S_MB_2U_LIB.S9S_MB_2U(SCH_1):M_B_CPU1_SB_DQ<4>
  247  M_B_CPU1_SB_DQ<3>  DQ_B3  @S9S_MB_2U_LIB.S9S_MB_2U(SCH_1):M_B_CPU1_SB_DQ<3>
  287  M_B_CPU1_SB_DQ<31>  DQ_B31  @S9S_MB_2U_LIB.S9S_MB_2U(SCH_1):M_B_CPU1_SB_DQ<31>
  285  M_B_CPU1_SB_DQ<30>  DQ_B30  @S9S_MB_2U_LIB.S9S_MB_2U(SCH_1):M_B_CPU1_SB_DQ<30>
  245  M_B_CPU1_SB_DQ<2>  DQ_B2  @S9S_MB_2U_LIB.S9S_MB_2U(SCH_1):M_B_CPU1_SB_DQ<2>
  142  M_B_CPU1_SB_DQ<29>  DQ_B29  @S9S_MB_2U_LIB.S9S_MB_2U(SCH_1):M_B_CPU1_SB_DQ<29>
  140  M_B_CPU1_SB_DQ<28>  DQ_B28  @S9S_MB_2U_LIB.S9S_MB_2U(SCH_1):M_B_CPU1_SB_DQ<28>
  280  M_B_CPU1_SB_DQ<27>  DQ_B27  @S9S_MB_2U_LIB.S9S_MB_2U(SCH_1):M_B_CPU1_SB_DQ<27>
  278  M_B_CPU1_SB_DQ<26>  DQ_B26  @S9S_MB_2U_LIB.S9S_MB_2U(SCH_1):M_B_CPU1_SB_DQ<26>
  135  M_B_CPU1_SB_DQ<25>  DQ_B25  @S9S_MB_2U_LIB.S9S_MB_2U(SCH_1):M_B_CPU1_SB_DQ<25>
  133  M_B_CPU1_SB_DQ<24>  DQ_B24  @S9S_MB_2U_LIB.S9S_MB_2U(SCH_1):M_B_CPU1_SB_DQ<24>
  276  M_B_CPU1_SB_DQ<23>  DQ_B23  @S9S_MB_2U_LIB.S9S_MB_2U(SCH_1):M_B_CPU1_SB_DQ<23>
  274  M_B_CPU1_SB_DQ<22>  DQ_B22  @S9S_MB_2U_LIB.S9S_MB_2U(SCH_1):M_B_CPU1_SB_DQ<22>
  131  M_B_CPU1_SB_DQ<21>  DQ_B21  @S9S_MB_2U_LIB.S9S_MB_2U(SCH_1):M_B_CPU1_SB_DQ<21>
  129  M_B_CPU1_SB_DQ<20>  DQ_B20  @S9S_MB_2U_LIB.S9S_MB_2U(SCH_1):M_B_CPU1_SB_DQ<20>
  102  M_B_CPU1_SB_DQ<1>  DQ_B1  @S9S_MB_2U_LIB.S9S_MB_2U(SCH_1):M_B_CPU1_SB_DQ<1>
  269  M_B_CPU1_SB_DQ<19>  DQ_B19  @S9S_MB_2U_LIB.S9S_MB_2U(SCH_1):M_B_CPU1_SB_DQ<19>
  267  M_B_CPU1_SB_DQ<18>  DQ_B18  @S9S_MB_2U_LIB.S9S_MB_2U(SCH_1):M_B_CPU1_SB_DQ<18>
  124  M_B_CPU1_SB_DQ<17>  DQ_B17  @S9S_MB_2U_LIB.S9S_MB_2U(SCH_1):M_B_CPU1_SB_DQ<17>
  122  M_B_CPU1_SB_DQ<16>  DQ_B16  @S9S_MB_2U_LIB.S9S_MB_2U(SCH_1):M_B_CPU1_SB_DQ<16>
  265  M_B_CPU1_SB_DQ<15>  DQ_B15  @S9S_MB_2U_LIB.S9S_MB_2U(SCH_1):M_B_CPU1_SB_DQ<15>
  263  M_B_CPU1_SB_DQ<14>  DQ_B14  @S9S_MB_2U_LIB.S9S_MB_2U(SCH_1):M_B_CPU1_SB_DQ<14>
  120  M_B_CPU1_SB_DQ<13>  DQ_B13  @S9S_MB_2U_LIB.S9S_MB_2U(SCH_1):M_B_CPU1_SB_DQ<13>
  118  M_B_CPU1_SB_DQ<12>  DQ_B12  @S9S_MB_2U_LIB.S9S_MB_2U(SCH_1):M_B_CPU1_SB_DQ<12>
  258  M_B_CPU1_SB_DQ<11>  DQ_B11  @S9S_MB_2U_LIB.S9S_MB_2U(SCH_1):M_B_CPU1_SB_DQ<11>
  256  M_B_CPU1_SB_DQ<10>  DQ_B10  @S9S_MB_2U_LIB.S9S_MB_2U(SCH_1):M_B_CPU1_SB_DQ<10>
  100  M_B_CPU1_SB_DQ<0>  DQ_B0  @S9S_MB_2U_LIB.S9S_MB_2U(SCH_1):M_B_CPU1_SB_DQ<0>
  229  M_B_CPU1_SB_CS_N<1>  CS1_N_B  @S9S_MB_2U_LIB.S9S_MB_2U(SCH_1):M_B_CPU1_SB_CS_N<1>
   84  M_B_CPU1_SB_CS_N<0>  CS0_N_B  @S9S_MB_2U_LIB.S9S_MB_2U(SCH_1):M_B_CPU1_SB_CS_N<0>
  236  M_B_CPU1_SB_CB<7>  CB_B7  @S9S_MB_2U_LIB.S9S_MB_2U(SCH_1):M_B_CPU1_SB_CB<7>
  234  M_B_CPU1_SB_CB<6>  CB_B6  @S9S_MB_2U_LIB.S9S_MB_2U(SCH_1):M_B_CPU1_SB_CB<6>
   91  M_B_CPU1_SB_CB<5>  CB_B5  @S9S_MB_2U_LIB.S9S_MB_2U(SCH_1):M_B_CPU1_SB_CB<5>
   89  M_B_CPU1_SB_CB<4>  CB_B4  @S9S_MB_2U_LIB.S9S_MB_2U(SCH_1):M_B_CPU1_SB_CB<4>
  243  M_B_CPU1_SB_CB<3>  CB_B3  @S9S_MB_2U_LIB.S9S_MB_2U(SCH_1):M_B_CPU1_SB_CB<3>
  241  M_B_CPU1_SB_CB<2>  CB_B2  @S9S_MB_2U_LIB.S9S_MB_2U(SCH_1):M_B_CPU1_SB_CB<2>
   98  M_B_CPU1_SB_CB<1>  CB_B1  @S9S_MB_2U_LIB.S9S_MB_2U(SCH_1):M_B_CPU1_SB_CB<1>
   96  M_B_CPU1_SB_CB<0>  CB_B0  @S9S_MB_2U_LIB.S9S_MB_2U(SCH_1):M_B_CPU1_SB_CB<0>
   82  M_B_CPU1_SB_CA<6>  CA6_B  @S9S_MB_2U_LIB.S9S_MB_2U(SCH_1):M_B_CPU1_SB_CA<6>
  225  M_B_CPU1_SB_CA<5>  CA5_B  @S9S_MB_2U_LIB.S9S_MB_2U(SCH_1):M_B_CPU1_SB_CA<5>
   80  M_B_CPU1_SB_CA<4>  CA4_B  @S9S_MB_2U_LIB.S9S_MB_2U(SCH_1):M_B_CPU1_SB_CA<4>
  223  M_B_CPU1_SB_CA<3>  CA3_B  @S9S_MB_2U_LIB.S9S_MB_2U(SCH_1):M_B_CPU1_SB_CA<3>
   78  M_B_CPU1_SB_CA<2>  CA2_B  @S9S_MB_2U_LIB.S9S_MB_2U(SCH_1):M_B_CPU1_SB_CA<2>
  221  M_B_CPU1_SB_CA<1>  CA1_B  @S9S_MB_2U_LIB.S9S_MB_2U(SCH_1):M_B_CPU1_SB_CA<1>
   76  M_B_CPU1_SB_CA<0>  CA0_B  @S9S_MB_2U_LIB.S9S_MB_2U(SCH_1):M_B_CPU1_SB_CA<0>
   86  M_B_CPU1_SA_RSP<0>  LBD||RSP_N_A  @S9S_MB_2U_LIB.S9S_MB_2U(SCH_1):M_B_CPU1_SA_RSP<0>
   74  M_B_CPU1_SA_PAR  PAR_A  @S9S_MB_2U_LIB.S9S_MB_2U(SCH_1):M_B_CPU1_SA_PAR
   20  M_B_CPU1_SA_DQ<9>  DQ_A9  @S9S_MB_2U_LIB.S9S_MB_2U(SCH_1):M_B_CPU1_SA_DQ<9>
   18  M_B_CPU1_SA_DQ<8>  DQ_A8  @S9S_MB_2U_LIB.S9S_MB_2U(SCH_1):M_B_CPU1_SA_DQ<8>
  161  M_B_CPU1_SA_DQ<7>  DQ_A7  @S9S_MB_2U_LIB.S9S_MB_2U(SCH_1):M_B_CPU1_SA_DQ<7>
  159  M_B_CPU1_SA_DQ<6>  DQ_A6  @S9S_MB_2U_LIB.S9S_MB_2U(SCH_1):M_B_CPU1_SA_DQ<6>
   16  M_B_CPU1_SA_DQ<5>  DQ_A5  @S9S_MB_2U_LIB.S9S_MB_2U(SCH_1):M_B_CPU1_SA_DQ<5>
   14  M_B_CPU1_SA_DQ<4>  DQ_A4  @S9S_MB_2U_LIB.S9S_MB_2U(SCH_1):M_B_CPU1_SA_DQ<4>
  154  M_B_CPU1_SA_DQ<3>  DQ_A3  @S9S_MB_2U_LIB.S9S_MB_2U(SCH_1):M_B_CPU1_SA_DQ<3>
  194  M_B_CPU1_SA_DQ<31>  DQ_A31  @S9S_MB_2U_LIB.S9S_MB_2U(SCH_1):M_B_CPU1_SA_DQ<31>
  192  M_B_CPU1_SA_DQ<30>  DQ_A30  @S9S_MB_2U_LIB.S9S_MB_2U(SCH_1):M_B_CPU1_SA_DQ<30>
  152  M_B_CPU1_SA_DQ<2>  DQ_A2  @S9S_MB_2U_LIB.S9S_MB_2U(SCH_1):M_B_CPU1_SA_DQ<2>
   49  M_B_CPU1_SA_DQ<29>  DQ_A29  @S9S_MB_2U_LIB.S9S_MB_2U(SCH_1):M_B_CPU1_SA_DQ<29>
   47  M_B_CPU1_SA_DQ<28>  DQ_A28  @S9S_MB_2U_LIB.S9S_MB_2U(SCH_1):M_B_CPU1_SA_DQ<28>
  187  M_B_CPU1_SA_DQ<27>  DQ_A27  @S9S_MB_2U_LIB.S9S_MB_2U(SCH_1):M_B_CPU1_SA_DQ<27>
  185  M_B_CPU1_SA_DQ<26>  DQ_A26  @S9S_MB_2U_LIB.S9S_MB_2U(SCH_1):M_B_CPU1_SA_DQ<26>
   42  M_B_CPU1_SA_DQ<25>  DQ_A25  @S9S_MB_2U_LIB.S9S_MB_2U(SCH_1):M_B_CPU1_SA_DQ<25>
   40  M_B_CPU1_SA_DQ<24>  DQ_A24  @S9S_MB_2U_LIB.S9S_MB_2U(SCH_1):M_B_CPU1_SA_DQ<24>
  183  M_B_CPU1_SA_DQ<23>  DQ_A23  @S9S_MB_2U_LIB.S9S_MB_2U(SCH_1):M_B_CPU1_SA_DQ<23>
  181  M_B_CPU1_SA_DQ<22>  DQ_A22  @S9S_MB_2U_LIB.S9S_MB_2U(SCH_1):M_B_CPU1_SA_DQ<22>
   38  M_B_CPU1_SA_DQ<21>  DQ_A21  @S9S_MB_2U_LIB.S9S_MB_2U(SCH_1):M_B_CPU1_SA_DQ<21>
   36  M_B_CPU1_SA_DQ<20>  DQ_A20  @S9S_MB_2U_LIB.S9S_MB_2U(SCH_1):M_B_CPU1_SA_DQ<20>
    9  M_B_CPU1_SA_DQ<1>  DQ_A1  @S9S_MB_2U_LIB.S9S_MB_2U(SCH_1):M_B_CPU1_SA_DQ<1>
  176  M_B_CPU1_SA_DQ<19>  DQ_A19  @S9S_MB_2U_LIB.S9S_MB_2U(SCH_1):M_B_CPU1_SA_DQ<19>
  174  M_B_CPU1_SA_DQ<18>  DQ_A18  @S9S_MB_2U_LIB.S9S_MB_2U(SCH_1):M_B_CPU1_SA_DQ<18>
   31  M_B_CPU1_SA_DQ<17>  DQ_A17  @S9S_MB_2U_LIB.S9S_MB_2U(SCH_1):M_B_CPU1_SA_DQ<17>
   29  M_B_CPU1_SA_DQ<16>  DQ_A16  @S9S_MB_2U_LIB.S9S_MB_2U(SCH_1):M_B_CPU1_SA_DQ<16>
  172  M_B_CPU1_SA_DQ<15>  DQ_A15  @S9S_MB_2U_LIB.S9S_MB_2U(SCH_1):M_B_CPU1_SA_DQ<15>
  170  M_B_CPU1_SA_DQ<14>  DQ_A14  @S9S_MB_2U_LIB.S9S_MB_2U(SCH_1):M_B_CPU1_SA_DQ<14>
   27  M_B_CPU1_SA_DQ<13>  DQ_A13  @S9S_MB_2U_LIB.S9S_MB_2U(SCH_1):M_B_CPU1_SA_DQ<13>
   25  M_B_CPU1_SA_DQ<12>  DQ_A12  @S9S_MB_2U_LIB.S9S_MB_2U(SCH_1):M_B_CPU1_SA_DQ<12>
  165  M_B_CPU1_SA_DQ<11>  DQ_A11  @S9S_MB_2U_LIB.S9S_MB_2U(SCH_1):M_B_CPU1_SA_DQ<11>
  163  M_B_CPU1_SA_DQ<10>  DQ_A10  @S9S_MB_2U_LIB.S9S_MB_2U(SCH_1):M_B_CPU1_SA_DQ<10>
    7  M_B_CPU1_SA_DQ<0>  DQ_A0  @S9S_MB_2U_LIB.S9S_MB_2U(SCH_1):M_B_CPU1_SA_DQ<0>
  209  M_B_CPU1_SA_CS_N<1>  CS1_N_A  @S9S_MB_2U_LIB.S9S_MB_2U(SCH_1):M_B_CPU1_SA_CS_N<1>
   64  M_B_CPU1_SA_CS_N<0>  CS0_N_A  @S9S_MB_2U_LIB.S9S_MB_2U(SCH_1):M_B_CPU1_SA_CS_N<0>
  205  M_B_CPU1_SA_CB<7>  CB_A7  @S9S_MB_2U_LIB.S9S_MB_2U(SCH_1):M_B_CPU1_SA_CB<7>
  203  M_B_CPU1_SA_CB<6>  CB_A6  @S9S_MB_2U_LIB.S9S_MB_2U(SCH_1):M_B_CPU1_SA_CB<6>
   60  M_B_CPU1_SA_CB<5>  CB_A5  @S9S_MB_2U_LIB.S9S_MB_2U(SCH_1):M_B_CPU1_SA_CB<5>
   58  M_B_CPU1_SA_CB<4>  CB_A4  @S9S_MB_2U_LIB.S9S_MB_2U(SCH_1):M_B_CPU1_SA_CB<4>
  198  M_B_CPU1_SA_CB<3>  CB_A3  @S9S_MB_2U_LIB.S9S_MB_2U(SCH_1):M_B_CPU1_SA_CB<3>
  196  M_B_CPU1_SA_CB<2>  CB_A2  @S9S_MB_2U_LIB.S9S_MB_2U(SCH_1):M_B_CPU1_SA_CB<2>
   53  M_B_CPU1_SA_CB<1>  CB_A1  @S9S_MB_2U_LIB.S9S_MB_2U(SCH_1):M_B_CPU1_SA_CB<1>
   51  M_B_CPU1_SA_CB<0>  CB_A0  @S9S_MB_2U_LIB.S9S_MB_2U(SCH_1):M_B_CPU1_SA_CB<0>
   72  M_B_CPU1_SA_CA<6>  CA6_A  @S9S_MB_2U_LIB.S9S_MB_2U(SCH_1):M_B_CPU1_SA_CA<6>
  215  M_B_CPU1_SA_CA<5>  CA5_A  @S9S_MB_2U_LIB.S9S_MB_2U(SCH_1):M_B_CPU1_SA_CA<5>
   70  M_B_CPU1_SA_CA<4>  CA4_A  @S9S_MB_2U_LIB.S9S_MB_2U(SCH_1):M_B_CPU1_SA_CA<4>
  213  M_B_CPU1_SA_CA<3>  CA3_A  @S9S_MB_2U_LIB.S9S_MB_2U(SCH_1):M_B_CPU1_SA_CA<3>
   68  M_B_CPU1_SA_CA<2>  CA2_A  @S9S_MB_2U_LIB.S9S_MB_2U(SCH_1):M_B_CPU1_SA_CA<2>
  211  M_B_CPU1_SA_CA<1>  CA1_A  @S9S_MB_2U_LIB.S9S_MB_2U(SCH_1):M_B_CPU1_SA_CA<1>
   66  M_B_CPU1_SA_CA<0>  CA0_A  @S9S_MB_2U_LIB.S9S_MB_2U(SCH_1):M_B_CPU1_SA_CA<0>
  217  M_B_CPU1_CLK_DP<0>   CK_P  @S9S_MB_2U_LIB.S9S_MB_2U(SCH_1):M_B_CPU1_CLK_DP<0>
  218  M_B_CPU1_CLK_DN<0>   CK_N  @S9S_MB_2U_LIB.S9S_MB_2U(SCH_1):M_B_CPU1_CLK_DN<0>
   62  M_B_CPU1_ALERT_N  ALERT_N  @S9S_MB_2U_LIB.S9S_MB_2U(SCH_1):M_B_CPU1_ALERT_N
    5  I3C_SPD_DDRABCD_CPU1_LVC1_SDA   HSDA  @S9S_MB_2U_LIB.S9S_MB_2U(SCH_1):I3C_SPD_DDRABCD_CPU1_LVC1_SDA
    4  I3C_SPD_DDRABCD_CPU1_LVC1_SCL   HSCL  @S9S_MB_2U_LIB.S9S_MB_2U(SCH_1):I3C_SPD_DDRABCD_CPU1_LVC1_SCL

SCONN288_ADR50001P003C01  I176  J20    [SCONN288_ADR50001P003C01-SCONNA]
  146  P12V_S3_AUX_CPU1_NVDIMM  VIN_BULK2  @S9S_MB_2U_LIB.S9S_MB_2U(SCH_1):P12V_S3_AUX_CPU1_NVDIMM
  145  P12V_S3_AUX_CPU1_NVDIMM  VIN_BULK1  @S9S_MB_2U_LIB.S9S_MB_2U(SCH_1):P12V_S3_AUX_CPU1_NVDIMM
    1  P12V_S3_AUX_CPU1_NVDIMM  VIN_BULK0  @S9S_MB_2U_LIB.S9S_MB_2U(SCH_1):P12V_S3_AUX_CPU1_NVDIMM
  288  GND            VSS126  @S9S_MB_2U_LIB.S9S_MB_2U(SCH_1):GND
  286  GND            VSS125  @S9S_MB_2U_LIB.S9S_MB_2U(SCH_1):GND
  284  GND            VSS124  @S9S_MB_2U_LIB.S9S_MB_2U(SCH_1):GND
  281  GND            VSS123  @S9S_MB_2U_LIB.S9S_MB_2U(SCH_1):GND
  279  GND            VSS122  @S9S_MB_2U_LIB.S9S_MB_2U(SCH_1):GND
  277  GND            VSS121  @S9S_MB_2U_LIB.S9S_MB_2U(SCH_1):GND
  275  GND            VSS120  @S9S_MB_2U_LIB.S9S_MB_2U(SCH_1):GND
  273  GND            VSS119  @S9S_MB_2U_LIB.S9S_MB_2U(SCH_1):GND
  270  GND            VSS118  @S9S_MB_2U_LIB.S9S_MB_2U(SCH_1):GND
  268  GND            VSS117  @S9S_MB_2U_LIB.S9S_MB_2U(SCH_1):GND
  266  GND            VSS116  @S9S_MB_2U_LIB.S9S_MB_2U(SCH_1):GND
  264  GND            VSS115  @S9S_MB_2U_LIB.S9S_MB_2U(SCH_1):GND
  262  GND            VSS114  @S9S_MB_2U_LIB.S9S_MB_2U(SCH_1):GND
  259  GND            VSS113  @S9S_MB_2U_LIB.S9S_MB_2U(SCH_1):GND
  257  GND            VSS112  @S9S_MB_2U_LIB.S9S_MB_2U(SCH_1):GND
  255  GND            VSS111  @S9S_MB_2U_LIB.S9S_MB_2U(SCH_1):GND
  253  GND            VSS110  @S9S_MB_2U_LIB.S9S_MB_2U(SCH_1):GND
  251  GND            VSS109  @S9S_MB_2U_LIB.S9S_MB_2U(SCH_1):GND
  248  GND            VSS108  @S9S_MB_2U_LIB.S9S_MB_2U(SCH_1):GND
  246  GND            VSS107  @S9S_MB_2U_LIB.S9S_MB_2U(SCH_1):GND
  244  GND            VSS106  @S9S_MB_2U_LIB.S9S_MB_2U(SCH_1):GND
  242  GND            VSS105  @S9S_MB_2U_LIB.S9S_MB_2U(SCH_1):GND
  240  GND            VSS104  @S9S_MB_2U_LIB.S9S_MB_2U(SCH_1):GND
  237  GND            VSS103  @S9S_MB_2U_LIB.S9S_MB_2U(SCH_1):GND
  235  GND            VSS102  @S9S_MB_2U_LIB.S9S_MB_2U(SCH_1):GND
  233  GND            VSS101  @S9S_MB_2U_LIB.S9S_MB_2U(SCH_1):GND
  230  GND            VSS100  @S9S_MB_2U_LIB.S9S_MB_2U(SCH_1):GND
  228  GND            VSS99  @S9S_MB_2U_LIB.S9S_MB_2U(SCH_1):GND
  226  GND            VSS98  @S9S_MB_2U_LIB.S9S_MB_2U(SCH_1):GND
  224  GND            VSS97  @S9S_MB_2U_LIB.S9S_MB_2U(SCH_1):GND
  222  GND            VSS96  @S9S_MB_2U_LIB.S9S_MB_2U(SCH_1):GND
  219  GND            VSS95  @S9S_MB_2U_LIB.S9S_MB_2U(SCH_1):GND
  216  GND            VSS94  @S9S_MB_2U_LIB.S9S_MB_2U(SCH_1):GND
  214  GND            VSS93  @S9S_MB_2U_LIB.S9S_MB_2U(SCH_1):GND
  212  GND            VSS92  @S9S_MB_2U_LIB.S9S_MB_2U(SCH_1):GND
  210  GND            VSS91  @S9S_MB_2U_LIB.S9S_MB_2U(SCH_1):GND
  208  GND            VSS90  @S9S_MB_2U_LIB.S9S_MB_2U(SCH_1):GND
  206  GND            VSS89  @S9S_MB_2U_LIB.S9S_MB_2U(SCH_1):GND
  204  GND            VSS88  @S9S_MB_2U_LIB.S9S_MB_2U(SCH_1):GND
  202  GND            VSS87  @S9S_MB_2U_LIB.S9S_MB_2U(SCH_1):GND
  199  GND            VSS86  @S9S_MB_2U_LIB.S9S_MB_2U(SCH_1):GND
  197  GND            VSS85  @S9S_MB_2U_LIB.S9S_MB_2U(SCH_1):GND
  195  GND            VSS84  @S9S_MB_2U_LIB.S9S_MB_2U(SCH_1):GND
  193  GND            VSS83  @S9S_MB_2U_LIB.S9S_MB_2U(SCH_1):GND
  191  GND            VSS82  @S9S_MB_2U_LIB.S9S_MB_2U(SCH_1):GND
  188  GND            VSS81  @S9S_MB_2U_LIB.S9S_MB_2U(SCH_1):GND
  186  GND            VSS80  @S9S_MB_2U_LIB.S9S_MB_2U(SCH_1):GND
  184  GND            VSS79  @S9S_MB_2U_LIB.S9S_MB_2U(SCH_1):GND
  182  GND            VSS78  @S9S_MB_2U_LIB.S9S_MB_2U(SCH_1):GND
  180  GND            VSS77  @S9S_MB_2U_LIB.S9S_MB_2U(SCH_1):GND
  177  GND            VSS76  @S9S_MB_2U_LIB.S9S_MB_2U(SCH_1):GND
  175  GND            VSS75  @S9S_MB_2U_LIB.S9S_MB_2U(SCH_1):GND
  173  GND            VSS74  @S9S_MB_2U_LIB.S9S_MB_2U(SCH_1):GND
  171  GND            VSS73  @S9S_MB_2U_LIB.S9S_MB_2U(SCH_1):GND
  169  GND            VSS72  @S9S_MB_2U_LIB.S9S_MB_2U(SCH_1):GND
  166  GND            VSS71  @S9S_MB_2U_LIB.S9S_MB_2U(SCH_1):GND
  164  GND            VSS70  @S9S_MB_2U_LIB.S9S_MB_2U(SCH_1):GND
  162  GND            VSS69  @S9S_MB_2U_LIB.S9S_MB_2U(SCH_1):GND
  160  GND            VSS68  @S9S_MB_2U_LIB.S9S_MB_2U(SCH_1):GND
  158  GND            VSS67  @S9S_MB_2U_LIB.S9S_MB_2U(SCH_1):GND
  155  GND            VSS66  @S9S_MB_2U_LIB.S9S_MB_2U(SCH_1):GND
  153  GND            VSS65  @S9S_MB_2U_LIB.S9S_MB_2U(SCH_1):GND
  151  GND            VSS64  @S9S_MB_2U_LIB.S9S_MB_2U(SCH_1):GND
  143  GND            VSS63  @S9S_MB_2U_LIB.S9S_MB_2U(SCH_1):GND
  141  GND            VSS62  @S9S_MB_2U_LIB.S9S_MB_2U(SCH_1):GND
  139  GND            VSS61  @S9S_MB_2U_LIB.S9S_MB_2U(SCH_1):GND
  136  GND            VSS60  @S9S_MB_2U_LIB.S9S_MB_2U(SCH_1):GND
  134  GND            VSS59  @S9S_MB_2U_LIB.S9S_MB_2U(SCH_1):GND
  132  GND            VSS58  @S9S_MB_2U_LIB.S9S_MB_2U(SCH_1):GND
  130  GND            VSS57  @S9S_MB_2U_LIB.S9S_MB_2U(SCH_1):GND
  128  GND            VSS56  @S9S_MB_2U_LIB.S9S_MB_2U(SCH_1):GND
  125  GND            VSS55  @S9S_MB_2U_LIB.S9S_MB_2U(SCH_1):GND
  123  GND            VSS54  @S9S_MB_2U_LIB.S9S_MB_2U(SCH_1):GND
  121  GND            VSS53  @S9S_MB_2U_LIB.S9S_MB_2U(SCH_1):GND
  119  GND            VSS52  @S9S_MB_2U_LIB.S9S_MB_2U(SCH_1):GND
  117  GND            VSS51  @S9S_MB_2U_LIB.S9S_MB_2U(SCH_1):GND
  114  GND            VSS50  @S9S_MB_2U_LIB.S9S_MB_2U(SCH_1):GND
  112  GND            VSS49  @S9S_MB_2U_LIB.S9S_MB_2U(SCH_1):GND
  110  GND            VSS48  @S9S_MB_2U_LIB.S9S_MB_2U(SCH_1):GND
  108  GND            VSS47  @S9S_MB_2U_LIB.S9S_MB_2U(SCH_1):GND
  106  GND            VSS46  @S9S_MB_2U_LIB.S9S_MB_2U(SCH_1):GND
  103  GND            VSS45  @S9S_MB_2U_LIB.S9S_MB_2U(SCH_1):GND
  101  GND            VSS44  @S9S_MB_2U_LIB.S9S_MB_2U(SCH_1):GND
   99  GND            VSS43  @S9S_MB_2U_LIB.S9S_MB_2U(SCH_1):GND
   97  GND            VSS42  @S9S_MB_2U_LIB.S9S_MB_2U(SCH_1):GND
   95  GND            VSS41  @S9S_MB_2U_LIB.S9S_MB_2U(SCH_1):GND
   92  GND            VSS40  @S9S_MB_2U_LIB.S9S_MB_2U(SCH_1):GND
   90  GND            VSS39  @S9S_MB_2U_LIB.S9S_MB_2U(SCH_1):GND
   88  GND            VSS38  @S9S_MB_2U_LIB.S9S_MB_2U(SCH_1):GND
   85  GND            VSS37  @S9S_MB_2U_LIB.S9S_MB_2U(SCH_1):GND
   83  GND            VSS36  @S9S_MB_2U_LIB.S9S_MB_2U(SCH_1):GND
   81  GND            VSS35  @S9S_MB_2U_LIB.S9S_MB_2U(SCH_1):GND
   79  GND            VSS34  @S9S_MB_2U_LIB.S9S_MB_2U(SCH_1):GND
   77  GND            VSS33  @S9S_MB_2U_LIB.S9S_MB_2U(SCH_1):GND
   75  GND            VSS32  @S9S_MB_2U_LIB.S9S_MB_2U(SCH_1):GND
   73  GND            VSS31  @S9S_MB_2U_LIB.S9S_MB_2U(SCH_1):GND
   71  GND            VSS30  @S9S_MB_2U_LIB.S9S_MB_2U(SCH_1):GND
   69  GND            VSS29  @S9S_MB_2U_LIB.S9S_MB_2U(SCH_1):GND
   67  GND            VSS28  @S9S_MB_2U_LIB.S9S_MB_2U(SCH_1):GND
   65  GND            VSS27  @S9S_MB_2U_LIB.S9S_MB_2U(SCH_1):GND
   63  GND            VSS26  @S9S_MB_2U_LIB.S9S_MB_2U(SCH_1):GND
   61  GND            VSS25  @S9S_MB_2U_LIB.S9S_MB_2U(SCH_1):GND
   59  GND            VSS24  @S9S_MB_2U_LIB.S9S_MB_2U(SCH_1):GND
   57  GND            VSS23  @S9S_MB_2U_LIB.S9S_MB_2U(SCH_1):GND
   54  GND            VSS22  @S9S_MB_2U_LIB.S9S_MB_2U(SCH_1):GND
   52  GND            VSS21  @S9S_MB_2U_LIB.S9S_MB_2U(SCH_1):GND
   50  GND            VSS20  @S9S_MB_2U_LIB.S9S_MB_2U(SCH_1):GND
   48  GND            VSS19  @S9S_MB_2U_LIB.S9S_MB_2U(SCH_1):GND
   46  GND            VSS18  @S9S_MB_2U_LIB.S9S_MB_2U(SCH_1):GND
   43  GND            VSS17  @S9S_MB_2U_LIB.S9S_MB_2U(SCH_1):GND
   41  GND            VSS16  @S9S_MB_2U_LIB.S9S_MB_2U(SCH_1):GND
   39  GND            VSS15  @S9S_MB_2U_LIB.S9S_MB_2U(SCH_1):GND
   37  GND            VSS14  @S9S_MB_2U_LIB.S9S_MB_2U(SCH_1):GND
   35  GND            VSS13  @S9S_MB_2U_LIB.S9S_MB_2U(SCH_1):GND
   32  GND            VSS12  @S9S_MB_2U_LIB.S9S_MB_2U(SCH_1):GND
   30  GND            VSS11  @S9S_MB_2U_LIB.S9S_MB_2U(SCH_1):GND
   28  GND            VSS10  @S9S_MB_2U_LIB.S9S_MB_2U(SCH_1):GND
   26  GND             VSS9  @S9S_MB_2U_LIB.S9S_MB_2U(SCH_1):GND
   24  GND             VSS8  @S9S_MB_2U_LIB.S9S_MB_2U(SCH_1):GND
   21  GND             VSS7  @S9S_MB_2U_LIB.S9S_MB_2U(SCH_1):GND
   19  GND             VSS6  @S9S_MB_2U_LIB.S9S_MB_2U(SCH_1):GND
   17  GND             VSS5  @S9S_MB_2U_LIB.S9S_MB_2U(SCH_1):GND
   15  GND             VSS4  @S9S_MB_2U_LIB.S9S_MB_2U(SCH_1):GND
   13  GND             VSS3  @S9S_MB_2U_LIB.S9S_MB_2U(SCH_1):GND
   10  GND             VSS2  @S9S_MB_2U_LIB.S9S_MB_2U(SCH_1):GND
    8  GND             VSS1  @S9S_MB_2U_LIB.S9S_MB_2U(SCH_1):GND
    6  GND             VSS0  @S9S_MB_2U_LIB.S9S_MB_2U(SCH_1):GND
   G3  GND               G3  @S9S_MB_2U_LIB.S9S_MB_2U(SCH_1):GND
   G2  GND               G2  @S9S_MB_2U_LIB.S9S_MB_2U(SCH_1):GND
   G1  GND               G1  @S9S_MB_2U_LIB.S9S_MB_2U(SCH_1):GND

SCONN288_ADR50001P003C01  I124  J20    [SCONN288_ADR50001P003C01-SCONNA]
   93  M_B_CPU1_SB_DQS_DP<9>  DQS9_B_P  @S9S_MB_2U_LIB.S9S_MB_2U(SCH_1):M_B_CPU1_SB_DQS_DP<9>
  283  M_B_CPU1_SB_DQS_DP<8>  DQS8_B_P  @S9S_MB_2U_LIB.S9S_MB_2U(SCH_1):M_B_CPU1_SB_DQS_DP<8>
  272  M_B_CPU1_SB_DQS_DP<7>  DQS7_B_P  @S9S_MB_2U_LIB.S9S_MB_2U(SCH_1):M_B_CPU1_SB_DQS_DP<7>
  261  M_B_CPU1_SB_DQS_DP<6>  DQS6_B_P  @S9S_MB_2U_LIB.S9S_MB_2U(SCH_1):M_B_CPU1_SB_DQS_DP<6>
  250  M_B_CPU1_SB_DQS_DP<5>  DQS5_B_P  @S9S_MB_2U_LIB.S9S_MB_2U(SCH_1):M_B_CPU1_SB_DQS_DP<5>
  239  M_B_CPU1_SB_DQS_DP<4>  DQS4_B_P  @S9S_MB_2U_LIB.S9S_MB_2U(SCH_1):M_B_CPU1_SB_DQS_DP<4>
  137  M_B_CPU1_SB_DQS_DP<3>  DQS3_B_P  @S9S_MB_2U_LIB.S9S_MB_2U(SCH_1):M_B_CPU1_SB_DQS_DP<3>
  126  M_B_CPU1_SB_DQS_DP<2>  DQS2_B_P  @S9S_MB_2U_LIB.S9S_MB_2U(SCH_1):M_B_CPU1_SB_DQS_DP<2>
  115  M_B_CPU1_SB_DQS_DP<1>  DQS1_B_P  @S9S_MB_2U_LIB.S9S_MB_2U(SCH_1):M_B_CPU1_SB_DQS_DP<1>
  104  M_B_CPU1_SB_DQS_DP<0>  DQS0_B_P  @S9S_MB_2U_LIB.S9S_MB_2U(SCH_1):M_B_CPU1_SB_DQS_DP<0>
   94  M_B_CPU1_SB_DQS_DN<9>  DQS9_B_N  @S9S_MB_2U_LIB.S9S_MB_2U(SCH_1):M_B_CPU1_SB_DQS_DN<9>
  282  M_B_CPU1_SB_DQS_DN<8>  DQS8_B_N  @S9S_MB_2U_LIB.S9S_MB_2U(SCH_1):M_B_CPU1_SB_DQS_DN<8>
  271  M_B_CPU1_SB_DQS_DN<7>  DQS7_B_N  @S9S_MB_2U_LIB.S9S_MB_2U(SCH_1):M_B_CPU1_SB_DQS_DN<7>
  260  M_B_CPU1_SB_DQS_DN<6>  DQS6_B_N  @S9S_MB_2U_LIB.S9S_MB_2U(SCH_1):M_B_CPU1_SB_DQS_DN<6>
  249  M_B_CPU1_SB_DQS_DN<5>  DQS5_B_N  @S9S_MB_2U_LIB.S9S_MB_2U(SCH_1):M_B_CPU1_SB_DQS_DN<5>
  238  M_B_CPU1_SB_DQS_DN<4>  DQS4_B_N  @S9S_MB_2U_LIB.S9S_MB_2U(SCH_1):M_B_CPU1_SB_DQS_DN<4>
  138  M_B_CPU1_SB_DQS_DN<3>  DQS3_B_N  @S9S_MB_2U_LIB.S9S_MB_2U(SCH_1):M_B_CPU1_SB_DQS_DN<3>
  127  M_B_CPU1_SB_DQS_DN<2>  DQS2_B_N  @S9S_MB_2U_LIB.S9S_MB_2U(SCH_1):M_B_CPU1_SB_DQS_DN<2>
  116  M_B_CPU1_SB_DQS_DN<1>  DQS1_B_N  @S9S_MB_2U_LIB.S9S_MB_2U(SCH_1):M_B_CPU1_SB_DQS_DN<1>
  105  M_B_CPU1_SB_DQS_DN<0>  DQS0_B_N  @S9S_MB_2U_LIB.S9S_MB_2U(SCH_1):M_B_CPU1_SB_DQS_DN<0>
  201  M_B_CPU1_SA_DQS_DP<9>  DQS9_A_P  @S9S_MB_2U_LIB.S9S_MB_2U(SCH_1):M_B_CPU1_SA_DQS_DP<9>
  190  M_B_CPU1_SA_DQS_DP<8>  DQS8_A_P  @S9S_MB_2U_LIB.S9S_MB_2U(SCH_1):M_B_CPU1_SA_DQS_DP<8>
  179  M_B_CPU1_SA_DQS_DP<7>  DQS7_A_P  @S9S_MB_2U_LIB.S9S_MB_2U(SCH_1):M_B_CPU1_SA_DQS_DP<7>
  168  M_B_CPU1_SA_DQS_DP<6>  DQS6_A_P  @S9S_MB_2U_LIB.S9S_MB_2U(SCH_1):M_B_CPU1_SA_DQS_DP<6>
  157  M_B_CPU1_SA_DQS_DP<5>  DQS5_A_P  @S9S_MB_2U_LIB.S9S_MB_2U(SCH_1):M_B_CPU1_SA_DQS_DP<5>
   55  M_B_CPU1_SA_DQS_DP<4>  DQS4_A_P  @S9S_MB_2U_LIB.S9S_MB_2U(SCH_1):M_B_CPU1_SA_DQS_DP<4>
   44  M_B_CPU1_SA_DQS_DP<3>  DQS3_A_P  @S9S_MB_2U_LIB.S9S_MB_2U(SCH_1):M_B_CPU1_SA_DQS_DP<3>
   33  M_B_CPU1_SA_DQS_DP<2>  DQS2_A_P  @S9S_MB_2U_LIB.S9S_MB_2U(SCH_1):M_B_CPU1_SA_DQS_DP<2>
   22  M_B_CPU1_SA_DQS_DP<1>  DQS1_A_P  @S9S_MB_2U_LIB.S9S_MB_2U(SCH_1):M_B_CPU1_SA_DQS_DP<1>
   11  M_B_CPU1_SA_DQS_DP<0>  DQS0_A_P  @S9S_MB_2U_LIB.S9S_MB_2U(SCH_1):M_B_CPU1_SA_DQS_DP<0>
  200  M_B_CPU1_SA_DQS_DN<9>  DQS9_A_N  @S9S_MB_2U_LIB.S9S_MB_2U(SCH_1):M_B_CPU1_SA_DQS_DN<9>
  189  M_B_CPU1_SA_DQS_DN<8>  DQS8_A_N  @S9S_MB_2U_LIB.S9S_MB_2U(SCH_1):M_B_CPU1_SA_DQS_DN<8>
  178  M_B_CPU1_SA_DQS_DN<7>  DQS7_A_N  @S9S_MB_2U_LIB.S9S_MB_2U(SCH_1):M_B_CPU1_SA_DQS_DN<7>
  167  M_B_CPU1_SA_DQS_DN<6>  DQS6_A_N  @S9S_MB_2U_LIB.S9S_MB_2U(SCH_1):M_B_CPU1_SA_DQS_DN<6>
  156  M_B_CPU1_SA_DQS_DN<5>  DQS5_A_N  @S9S_MB_2U_LIB.S9S_MB_2U(SCH_1):M_B_CPU1_SA_DQS_DN<5>
   56  M_B_CPU1_SA_DQS_DN<4>  DQS4_A_N  @S9S_MB_2U_LIB.S9S_MB_2U(SCH_1):M_B_CPU1_SA_DQS_DN<4>
   45  M_B_CPU1_SA_DQS_DN<3>  DQS3_A_N  @S9S_MB_2U_LIB.S9S_MB_2U(SCH_1):M_B_CPU1_SA_DQS_DN<3>
   34  M_B_CPU1_SA_DQS_DN<2>  DQS2_A_N  @S9S_MB_2U_LIB.S9S_MB_2U(SCH_1):M_B_CPU1_SA_DQS_DN<2>
   23  M_B_CPU1_SA_DQS_DN<1>  DQS1_A_N  @S9S_MB_2U_LIB.S9S_MB_2U(SCH_1):M_B_CPU1_SA_DQS_DN<1>
   12  M_B_CPU1_SA_DQS_DN<0>  DQS0_A_N  @S9S_MB_2U_LIB.S9S_MB_2U(SCH_1):M_B_CPU1_SA_DQS_DN<0>

SCONN288_ADR50001P003C01  I47  J20    [SCONN288_ADR50001P003C01-SCONNA]
  232  NC              RFU6  NC
  231  NC              RFU5  NC
  220  NC              RFU4  NC
  150  NC              RFU3  NC
  149  NC              RFU2  NC
  144  NC              RFU1  NC
    2  NC              RFU0  NC
  207  RST_M_AB_CPU1_FPGA_N  RESET_N  @S9S_MB_2U_LIB.S9S_MB_2U(SCH_1):RST_M_AB_CPU1_FPGA_N
  147  PWRGD_CHB_CPU1_DIMM2  PWR_GOOD||FAIL_N  @S9S_MB_2U_LIB.S9S_MB_2U(SCH_1):PWRGD_CHB_CPU1_DIMM2
  148  PD_CHB_CPU1_DIMM2_SAA    HAS  @S9S_MB_2U_LIB.S9S_MB_2U(SCH_1):PD_CHB_CPU1_DIMM2_SAA
    3  P3V3_AUX       VIN_MGMT  @S9S_MB_2U_LIB.S9S_MB_2U(SCH_1):P3V3_AUX
   87  M_B_CPU1_SB_RSP<1>  LBS||RSP_N_B  @S9S_MB_2U_LIB.S9S_MB_2U(SCH_1):M_B_CPU1_SB_RSP<1>
  227  M_B_CPU1_SB_PAR  PAR_B  @S9S_MB_2U_LIB.S9S_MB_2U(SCH_1):M_B_CPU1_SB_PAR
  113  M_B_CPU1_SB_DQ<9>  DQ_B9  @S9S_MB_2U_LIB.S9S_MB_2U(SCH_1):M_B_CPU1_SB_DQ<9>
  111  M_B_CPU1_SB_DQ<8>  DQ_B8  @S9S_MB_2U_LIB.S9S_MB_2U(SCH_1):M_B_CPU1_SB_DQ<8>
  254  M_B_CPU1_SB_DQ<7>  DQ_B7  @S9S_MB_2U_LIB.S9S_MB_2U(SCH_1):M_B_CPU1_SB_DQ<7>
  252  M_B_CPU1_SB_DQ<6>  DQ_B6  @S9S_MB_2U_LIB.S9S_MB_2U(SCH_1):M_B_CPU1_SB_DQ<6>
  109  M_B_CPU1_SB_DQ<5>  DQ_B5  @S9S_MB_2U_LIB.S9S_MB_2U(SCH_1):M_B_CPU1_SB_DQ<5>
  107  M_B_CPU1_SB_DQ<4>  DQ_B4  @S9S_MB_2U_LIB.S9S_MB_2U(SCH_1):M_B_CPU1_SB_DQ<4>
  247  M_B_CPU1_SB_DQ<3>  DQ_B3  @S9S_MB_2U_LIB.S9S_MB_2U(SCH_1):M_B_CPU1_SB_DQ<3>
  287  M_B_CPU1_SB_DQ<31>  DQ_B31  @S9S_MB_2U_LIB.S9S_MB_2U(SCH_1):M_B_CPU1_SB_DQ<31>
  285  M_B_CPU1_SB_DQ<30>  DQ_B30  @S9S_MB_2U_LIB.S9S_MB_2U(SCH_1):M_B_CPU1_SB_DQ<30>
  245  M_B_CPU1_SB_DQ<2>  DQ_B2  @S9S_MB_2U_LIB.S9S_MB_2U(SCH_1):M_B_CPU1_SB_DQ<2>
  142  M_B_CPU1_SB_DQ<29>  DQ_B29  @S9S_MB_2U_LIB.S9S_MB_2U(SCH_1):M_B_CPU1_SB_DQ<29>
  140  M_B_CPU1_SB_DQ<28>  DQ_B28  @S9S_MB_2U_LIB.S9S_MB_2U(SCH_1):M_B_CPU1_SB_DQ<28>
  280  M_B_CPU1_SB_DQ<27>  DQ_B27  @S9S_MB_2U_LIB.S9S_MB_2U(SCH_1):M_B_CPU1_SB_DQ<27>
  278  M_B_CPU1_SB_DQ<26>  DQ_B26  @S9S_MB_2U_LIB.S9S_MB_2U(SCH_1):M_B_CPU1_SB_DQ<26>
  135  M_B_CPU1_SB_DQ<25>  DQ_B25  @S9S_MB_2U_LIB.S9S_MB_2U(SCH_1):M_B_CPU1_SB_DQ<25>
  133  M_B_CPU1_SB_DQ<24>  DQ_B24  @S9S_MB_2U_LIB.S9S_MB_2U(SCH_1):M_B_CPU1_SB_DQ<24>
  276  M_B_CPU1_SB_DQ<23>  DQ_B23  @S9S_MB_2U_LIB.S9S_MB_2U(SCH_1):M_B_CPU1_SB_DQ<23>
  274  M_B_CPU1_SB_DQ<22>  DQ_B22  @S9S_MB_2U_LIB.S9S_MB_2U(SCH_1):M_B_CPU1_SB_DQ<22>
  131  M_B_CPU1_SB_DQ<21>  DQ_B21  @S9S_MB_2U_LIB.S9S_MB_2U(SCH_1):M_B_CPU1_SB_DQ<21>
  129  M_B_CPU1_SB_DQ<20>  DQ_B20  @S9S_MB_2U_LIB.S9S_MB_2U(SCH_1):M_B_CPU1_SB_DQ<20>
  102  M_B_CPU1_SB_DQ<1>  DQ_B1  @S9S_MB_2U_LIB.S9S_MB_2U(SCH_1):M_B_CPU1_SB_DQ<1>
  269  M_B_CPU1_SB_DQ<19>  DQ_B19  @S9S_MB_2U_LIB.S9S_MB_2U(SCH_1):M_B_CPU1_SB_DQ<19>
  267  M_B_CPU1_SB_DQ<18>  DQ_B18  @S9S_MB_2U_LIB.S9S_MB_2U(SCH_1):M_B_CPU1_SB_DQ<18>
  124  M_B_CPU1_SB_DQ<17>  DQ_B17  @S9S_MB_2U_LIB.S9S_MB_2U(SCH_1):M_B_CPU1_SB_DQ<17>
  122  M_B_CPU1_SB_DQ<16>  DQ_B16  @S9S_MB_2U_LIB.S9S_MB_2U(SCH_1):M_B_CPU1_SB_DQ<16>
  265  M_B_CPU1_SB_DQ<15>  DQ_B15  @S9S_MB_2U_LIB.S9S_MB_2U(SCH_1):M_B_CPU1_SB_DQ<15>
  263  M_B_CPU1_SB_DQ<14>  DQ_B14  @S9S_MB_2U_LIB.S9S_MB_2U(SCH_1):M_B_CPU1_SB_DQ<14>
  120  M_B_CPU1_SB_DQ<13>  DQ_B13  @S9S_MB_2U_LIB.S9S_MB_2U(SCH_1):M_B_CPU1_SB_DQ<13>
  118  M_B_CPU1_SB_DQ<12>  DQ_B12  @S9S_MB_2U_LIB.S9S_MB_2U(SCH_1):M_B_CPU1_SB_DQ<12>
  258  M_B_CPU1_SB_DQ<11>  DQ_B11  @S9S_MB_2U_LIB.S9S_MB_2U(SCH_1):M_B_CPU1_SB_DQ<11>
  256  M_B_CPU1_SB_DQ<10>  DQ_B10  @S9S_MB_2U_LIB.S9S_MB_2U(SCH_1):M_B_CPU1_SB_DQ<10>
  100  M_B_CPU1_SB_DQ<0>  DQ_B0  @S9S_MB_2U_LIB.S9S_MB_2U(SCH_1):M_B_CPU1_SB_DQ<0>
  229  M_B_CPU1_SB_CS_N<3>  CS1_N_B  @S9S_MB_2U_LIB.S9S_MB_2U(SCH_1):M_B_CPU1_SB_CS_N<3>
   84  M_B_CPU1_SB_CS_N<2>  CS0_N_B  @S9S_MB_2U_LIB.S9S_MB_2U(SCH_1):M_B_CPU1_SB_CS_N<2>
  236  M_B_CPU1_SB_CB<7>  CB_B7  @S9S_MB_2U_LIB.S9S_MB_2U(SCH_1):M_B_CPU1_SB_CB<7>
  234  M_B_CPU1_SB_CB<6>  CB_B6  @S9S_MB_2U_LIB.S9S_MB_2U(SCH_1):M_B_CPU1_SB_CB<6>
   91  M_B_CPU1_SB_CB<5>  CB_B5  @S9S_MB_2U_LIB.S9S_MB_2U(SCH_1):M_B_CPU1_SB_CB<5>
   89  M_B_CPU1_SB_CB<4>  CB_B4  @S9S_MB_2U_LIB.S9S_MB_2U(SCH_1):M_B_CPU1_SB_CB<4>
  243  M_B_CPU1_SB_CB<3>  CB_B3  @S9S_MB_2U_LIB.S9S_MB_2U(SCH_1):M_B_CPU1_SB_CB<3>
  241  M_B_CPU1_SB_CB<2>  CB_B2  @S9S_MB_2U_LIB.S9S_MB_2U(SCH_1):M_B_CPU1_SB_CB<2>
   98  M_B_CPU1_SB_CB<1>  CB_B1  @S9S_MB_2U_LIB.S9S_MB_2U(SCH_1):M_B_CPU1_SB_CB<1>
   96  M_B_CPU1_SB_CB<0>  CB_B0  @S9S_MB_2U_LIB.S9S_MB_2U(SCH_1):M_B_CPU1_SB_CB<0>
   82  M_B_CPU1_SB_CA<6>  CA6_B  @S9S_MB_2U_LIB.S9S_MB_2U(SCH_1):M_B_CPU1_SB_CA<6>
  225  M_B_CPU1_SB_CA<5>  CA5_B  @S9S_MB_2U_LIB.S9S_MB_2U(SCH_1):M_B_CPU1_SB_CA<5>
   80  M_B_CPU1_SB_CA<4>  CA4_B  @S9S_MB_2U_LIB.S9S_MB_2U(SCH_1):M_B_CPU1_SB_CA<4>
  223  M_B_CPU1_SB_CA<3>  CA3_B  @S9S_MB_2U_LIB.S9S_MB_2U(SCH_1):M_B_CPU1_SB_CA<3>
   78  M_B_CPU1_SB_CA<2>  CA2_B  @S9S_MB_2U_LIB.S9S_MB_2U(SCH_1):M_B_CPU1_SB_CA<2>
  221  M_B_CPU1_SB_CA<1>  CA1_B  @S9S_MB_2U_LIB.S9S_MB_2U(SCH_1):M_B_CPU1_SB_CA<1>
   76  M_B_CPU1_SB_CA<0>  CA0_B  @S9S_MB_2U_LIB.S9S_MB_2U(SCH_1):M_B_CPU1_SB_CA<0>
   86  M_B_CPU1_SA_RSP<1>  LBD||RSP_N_A  @S9S_MB_2U_LIB.S9S_MB_2U(SCH_1):M_B_CPU1_SA_RSP<1>
   74  M_B_CPU1_SA_PAR  PAR_A  @S9S_MB_2U_LIB.S9S_MB_2U(SCH_1):M_B_CPU1_SA_PAR
   20  M_B_CPU1_SA_DQ<9>  DQ_A9  @S9S_MB_2U_LIB.S9S_MB_2U(SCH_1):M_B_CPU1_SA_DQ<9>
   18  M_B_CPU1_SA_DQ<8>  DQ_A8  @S9S_MB_2U_LIB.S9S_MB_2U(SCH_1):M_B_CPU1_SA_DQ<8>
  161  M_B_CPU1_SA_DQ<7>  DQ_A7  @S9S_MB_2U_LIB.S9S_MB_2U(SCH_1):M_B_CPU1_SA_DQ<7>
  159  M_B_CPU1_SA_DQ<6>  DQ_A6  @S9S_MB_2U_LIB.S9S_MB_2U(SCH_1):M_B_CPU1_SA_DQ<6>
   16  M_B_CPU1_SA_DQ<5>  DQ_A5  @S9S_MB_2U_LIB.S9S_MB_2U(SCH_1):M_B_CPU1_SA_DQ<5>
   14  M_B_CPU1_SA_DQ<4>  DQ_A4  @S9S_MB_2U_LIB.S9S_MB_2U(SCH_1):M_B_CPU1_SA_DQ<4>
  154  M_B_CPU1_SA_DQ<3>  DQ_A3  @S9S_MB_2U_LIB.S9S_MB_2U(SCH_1):M_B_CPU1_SA_DQ<3>
  194  M_B_CPU1_SA_DQ<31>  DQ_A31  @S9S_MB_2U_LIB.S9S_MB_2U(SCH_1):M_B_CPU1_SA_DQ<31>
  192  M_B_CPU1_SA_DQ<30>  DQ_A30  @S9S_MB_2U_LIB.S9S_MB_2U(SCH_1):M_B_CPU1_SA_DQ<30>
  152  M_B_CPU1_SA_DQ<2>  DQ_A2  @S9S_MB_2U_LIB.S9S_MB_2U(SCH_1):M_B_CPU1_SA_DQ<2>
   49  M_B_CPU1_SA_DQ<29>  DQ_A29  @S9S_MB_2U_LIB.S9S_MB_2U(SCH_1):M_B_CPU1_SA_DQ<29>
   47  M_B_CPU1_SA_DQ<28>  DQ_A28  @S9S_MB_2U_LIB.S9S_MB_2U(SCH_1):M_B_CPU1_SA_DQ<28>
  187  M_B_CPU1_SA_DQ<27>  DQ_A27  @S9S_MB_2U_LIB.S9S_MB_2U(SCH_1):M_B_CPU1_SA_DQ<27>
  185  M_B_CPU1_SA_DQ<26>  DQ_A26  @S9S_MB_2U_LIB.S9S_MB_2U(SCH_1):M_B_CPU1_SA_DQ<26>
   42  M_B_CPU1_SA_DQ<25>  DQ_A25  @S9S_MB_2U_LIB.S9S_MB_2U(SCH_1):M_B_CPU1_SA_DQ<25>
   40  M_B_CPU1_SA_DQ<24>  DQ_A24  @S9S_MB_2U_LIB.S9S_MB_2U(SCH_1):M_B_CPU1_SA_DQ<24>
  183  M_B_CPU1_SA_DQ<23>  DQ_A23  @S9S_MB_2U_LIB.S9S_MB_2U(SCH_1):M_B_CPU1_SA_DQ<23>
  181  M_B_CPU1_SA_DQ<22>  DQ_A22  @S9S_MB_2U_LIB.S9S_MB_2U(SCH_1):M_B_CPU1_SA_DQ<22>
   38  M_B_CPU1_SA_DQ<21>  DQ_A21  @S9S_MB_2U_LIB.S9S_MB_2U(SCH_1):M_B_CPU1_SA_DQ<21>
   36  M_B_CPU1_SA_DQ<20>  DQ_A20  @S9S_MB_2U_LIB.S9S_MB_2U(SCH_1):M_B_CPU1_SA_DQ<20>
    9  M_B_CPU1_SA_DQ<1>  DQ_A1  @S9S_MB_2U_LIB.S9S_MB_2U(SCH_1):M_B_CPU1_SA_DQ<1>
  176  M_B_CPU1_SA_DQ<19>  DQ_A19  @S9S_MB_2U_LIB.S9S_MB_2U(SCH_1):M_B_CPU1_SA_DQ<19>
  174  M_B_CPU1_SA_DQ<18>  DQ_A18  @S9S_MB_2U_LIB.S9S_MB_2U(SCH_1):M_B_CPU1_SA_DQ<18>
   31  M_B_CPU1_SA_DQ<17>  DQ_A17  @S9S_MB_2U_LIB.S9S_MB_2U(SCH_1):M_B_CPU1_SA_DQ<17>
   29  M_B_CPU1_SA_DQ<16>  DQ_A16  @S9S_MB_2U_LIB.S9S_MB_2U(SCH_1):M_B_CPU1_SA_DQ<16>
  172  M_B_CPU1_SA_DQ<15>  DQ_A15  @S9S_MB_2U_LIB.S9S_MB_2U(SCH_1):M_B_CPU1_SA_DQ<15>
  170  M_B_CPU1_SA_DQ<14>  DQ_A14  @S9S_MB_2U_LIB.S9S_MB_2U(SCH_1):M_B_CPU1_SA_DQ<14>
   27  M_B_CPU1_SA_DQ<13>  DQ_A13  @S9S_MB_2U_LIB.S9S_MB_2U(SCH_1):M_B_CPU1_SA_DQ<13>
   25  M_B_CPU1_SA_DQ<12>  DQ_A12  @S9S_MB_2U_LIB.S9S_MB_2U(SCH_1):M_B_CPU1_SA_DQ<12>
  165  M_B_CPU1_SA_DQ<11>  DQ_A11  @S9S_MB_2U_LIB.S9S_MB_2U(SCH_1):M_B_CPU1_SA_DQ<11>
  163  M_B_CPU1_SA_DQ<10>  DQ_A10  @S9S_MB_2U_LIB.S9S_MB_2U(SCH_1):M_B_CPU1_SA_DQ<10>
    7  M_B_CPU1_SA_DQ<0>  DQ_A0  @S9S_MB_2U_LIB.S9S_MB_2U(SCH_1):M_B_CPU1_SA_DQ<0>
  209  M_B_CPU1_SA_CS_N<3>  CS1_N_A  @S9S_MB_2U_LIB.S9S_MB_2U(SCH_1):M_B_CPU1_SA_CS_N<3>
   64  M_B_CPU1_SA_CS_N<2>  CS0_N_A  @S9S_MB_2U_LIB.S9S_MB_2U(SCH_1):M_B_CPU1_SA_CS_N<2>
  205  M_B_CPU1_SA_CB<7>  CB_A7  @S9S_MB_2U_LIB.S9S_MB_2U(SCH_1):M_B_CPU1_SA_CB<7>
  203  M_B_CPU1_SA_CB<6>  CB_A6  @S9S_MB_2U_LIB.S9S_MB_2U(SCH_1):M_B_CPU1_SA_CB<6>
   60  M_B_CPU1_SA_CB<5>  CB_A5  @S9S_MB_2U_LIB.S9S_MB_2U(SCH_1):M_B_CPU1_SA_CB<5>
   58  M_B_CPU1_SA_CB<4>  CB_A4  @S9S_MB_2U_LIB.S9S_MB_2U(SCH_1):M_B_CPU1_SA_CB<4>
  198  M_B_CPU1_SA_CB<3>  CB_A3  @S9S_MB_2U_LIB.S9S_MB_2U(SCH_1):M_B_CPU1_SA_CB<3>
  196  M_B_CPU1_SA_CB<2>  CB_A2  @S9S_MB_2U_LIB.S9S_MB_2U(SCH_1):M_B_CPU1_SA_CB<2>
   53  M_B_CPU1_SA_CB<1>  CB_A1  @S9S_MB_2U_LIB.S9S_MB_2U(SCH_1):M_B_CPU1_SA_CB<1>
   51  M_B_CPU1_SA_CB<0>  CB_A0  @S9S_MB_2U_LIB.S9S_MB_2U(SCH_1):M_B_CPU1_SA_CB<0>
   72  M_B_CPU1_SA_CA<6>  CA6_A  @S9S_MB_2U_LIB.S9S_MB_2U(SCH_1):M_B_CPU1_SA_CA<6>
  215  M_B_CPU1_SA_CA<5>  CA5_A  @S9S_MB_2U_LIB.S9S_MB_2U(SCH_1):M_B_CPU1_SA_CA<5>
   70  M_B_CPU1_SA_CA<4>  CA4_A  @S9S_MB_2U_LIB.S9S_MB_2U(SCH_1):M_B_CPU1_SA_CA<4>
  213  M_B_CPU1_SA_CA<3>  CA3_A  @S9S_MB_2U_LIB.S9S_MB_2U(SCH_1):M_B_CPU1_SA_CA<3>
   68  M_B_CPU1_SA_CA<2>  CA2_A  @S9S_MB_2U_LIB.S9S_MB_2U(SCH_1):M_B_CPU1_SA_CA<2>
  211  M_B_CPU1_SA_CA<1>  CA1_A  @S9S_MB_2U_LIB.S9S_MB_2U(SCH_1):M_B_CPU1_SA_CA<1>
   66  M_B_CPU1_SA_CA<0>  CA0_A  @S9S_MB_2U_LIB.S9S_MB_2U(SCH_1):M_B_CPU1_SA_CA<0>
  217  M_B_CPU1_CLK_DP<1>   CK_P  @S9S_MB_2U_LIB.S9S_MB_2U(SCH_1):M_B_CPU1_CLK_DP<1>
  218  M_B_CPU1_CLK_DN<1>   CK_N  @S9S_MB_2U_LIB.S9S_MB_2U(SCH_1):M_B_CPU1_CLK_DN<1>
   62  M_B_CPU1_ALERT_N  ALERT_N  @S9S_MB_2U_LIB.S9S_MB_2U(SCH_1):M_B_CPU1_ALERT_N
    5  I3C_SPD_DDRABCD_CPU1_LVC1_SDA   HSDA  @S9S_MB_2U_LIB.S9S_MB_2U(SCH_1):I3C_SPD_DDRABCD_CPU1_LVC1_SDA
    4  I3C_SPD_DDRABCD_CPU1_LVC1_SCL   HSCL  @S9S_MB_2U_LIB.S9S_MB_2U(SCH_1):I3C_SPD_DDRABCD_CPU1_LVC1_SCL

SCONN288_ADR50001P013C01  I169  J21    [SCONN288_ADR50001P013C01-SCONNA]
  146  P12V_S3_AUX_CPU1_NVDIMM  VIN_BULK2  @S9S_MB_2U_LIB.S9S_MB_2U(SCH_1):P12V_S3_AUX_CPU1_NVDIMM
  145  P12V_S3_AUX_CPU1_NVDIMM  VIN_BULK1  @S9S_MB_2U_LIB.S9S_MB_2U(SCH_1):P12V_S3_AUX_CPU1_NVDIMM
    1  P12V_S3_AUX_CPU1_NVDIMM  VIN_BULK0  @S9S_MB_2U_LIB.S9S_MB_2U(SCH_1):P12V_S3_AUX_CPU1_NVDIMM
  288  GND            VSS126  @S9S_MB_2U_LIB.S9S_MB_2U(SCH_1):GND
  286  GND            VSS125  @S9S_MB_2U_LIB.S9S_MB_2U(SCH_1):GND
  284  GND            VSS124  @S9S_MB_2U_LIB.S9S_MB_2U(SCH_1):GND
  281  GND            VSS123  @S9S_MB_2U_LIB.S9S_MB_2U(SCH_1):GND
  279  GND            VSS122  @S9S_MB_2U_LIB.S9S_MB_2U(SCH_1):GND
  277  GND            VSS121  @S9S_MB_2U_LIB.S9S_MB_2U(SCH_1):GND
  275  GND            VSS120  @S9S_MB_2U_LIB.S9S_MB_2U(SCH_1):GND
  273  GND            VSS119  @S9S_MB_2U_LIB.S9S_MB_2U(SCH_1):GND
  270  GND            VSS118  @S9S_MB_2U_LIB.S9S_MB_2U(SCH_1):GND
  268  GND            VSS117  @S9S_MB_2U_LIB.S9S_MB_2U(SCH_1):GND
  266  GND            VSS116  @S9S_MB_2U_LIB.S9S_MB_2U(SCH_1):GND
  264  GND            VSS115  @S9S_MB_2U_LIB.S9S_MB_2U(SCH_1):GND
  262  GND            VSS114  @S9S_MB_2U_LIB.S9S_MB_2U(SCH_1):GND
  259  GND            VSS113  @S9S_MB_2U_LIB.S9S_MB_2U(SCH_1):GND
  257  GND            VSS112  @S9S_MB_2U_LIB.S9S_MB_2U(SCH_1):GND
  255  GND            VSS111  @S9S_MB_2U_LIB.S9S_MB_2U(SCH_1):GND
  253  GND            VSS110  @S9S_MB_2U_LIB.S9S_MB_2U(SCH_1):GND
  251  GND            VSS109  @S9S_MB_2U_LIB.S9S_MB_2U(SCH_1):GND
  248  GND            VSS108  @S9S_MB_2U_LIB.S9S_MB_2U(SCH_1):GND
  246  GND            VSS107  @S9S_MB_2U_LIB.S9S_MB_2U(SCH_1):GND
  244  GND            VSS106  @S9S_MB_2U_LIB.S9S_MB_2U(SCH_1):GND
  242  GND            VSS105  @S9S_MB_2U_LIB.S9S_MB_2U(SCH_1):GND
  240  GND            VSS104  @S9S_MB_2U_LIB.S9S_MB_2U(SCH_1):GND
  237  GND            VSS103  @S9S_MB_2U_LIB.S9S_MB_2U(SCH_1):GND
  235  GND            VSS102  @S9S_MB_2U_LIB.S9S_MB_2U(SCH_1):GND
  233  GND            VSS101  @S9S_MB_2U_LIB.S9S_MB_2U(SCH_1):GND
  230  GND            VSS100  @S9S_MB_2U_LIB.S9S_MB_2U(SCH_1):GND
  228  GND            VSS99  @S9S_MB_2U_LIB.S9S_MB_2U(SCH_1):GND
  226  GND            VSS98  @S9S_MB_2U_LIB.S9S_MB_2U(SCH_1):GND
  224  GND            VSS97  @S9S_MB_2U_LIB.S9S_MB_2U(SCH_1):GND
  222  GND            VSS96  @S9S_MB_2U_LIB.S9S_MB_2U(SCH_1):GND
  219  GND            VSS95  @S9S_MB_2U_LIB.S9S_MB_2U(SCH_1):GND
  216  GND            VSS94  @S9S_MB_2U_LIB.S9S_MB_2U(SCH_1):GND
  214  GND            VSS93  @S9S_MB_2U_LIB.S9S_MB_2U(SCH_1):GND
  212  GND            VSS92  @S9S_MB_2U_LIB.S9S_MB_2U(SCH_1):GND
  210  GND            VSS91  @S9S_MB_2U_LIB.S9S_MB_2U(SCH_1):GND
  208  GND            VSS90  @S9S_MB_2U_LIB.S9S_MB_2U(SCH_1):GND
  206  GND            VSS89  @S9S_MB_2U_LIB.S9S_MB_2U(SCH_1):GND
  204  GND            VSS88  @S9S_MB_2U_LIB.S9S_MB_2U(SCH_1):GND
  202  GND            VSS87  @S9S_MB_2U_LIB.S9S_MB_2U(SCH_1):GND
  199  GND            VSS86  @S9S_MB_2U_LIB.S9S_MB_2U(SCH_1):GND
  197  GND            VSS85  @S9S_MB_2U_LIB.S9S_MB_2U(SCH_1):GND
  195  GND            VSS84  @S9S_MB_2U_LIB.S9S_MB_2U(SCH_1):GND
  193  GND            VSS83  @S9S_MB_2U_LIB.S9S_MB_2U(SCH_1):GND
  191  GND            VSS82  @S9S_MB_2U_LIB.S9S_MB_2U(SCH_1):GND
  188  GND            VSS81  @S9S_MB_2U_LIB.S9S_MB_2U(SCH_1):GND
  186  GND            VSS80  @S9S_MB_2U_LIB.S9S_MB_2U(SCH_1):GND
  184  GND            VSS79  @S9S_MB_2U_LIB.S9S_MB_2U(SCH_1):GND
  182  GND            VSS78  @S9S_MB_2U_LIB.S9S_MB_2U(SCH_1):GND
  180  GND            VSS77  @S9S_MB_2U_LIB.S9S_MB_2U(SCH_1):GND
  177  GND            VSS76  @S9S_MB_2U_LIB.S9S_MB_2U(SCH_1):GND
  175  GND            VSS75  @S9S_MB_2U_LIB.S9S_MB_2U(SCH_1):GND
  173  GND            VSS74  @S9S_MB_2U_LIB.S9S_MB_2U(SCH_1):GND
  171  GND            VSS73  @S9S_MB_2U_LIB.S9S_MB_2U(SCH_1):GND
  169  GND            VSS72  @S9S_MB_2U_LIB.S9S_MB_2U(SCH_1):GND
  166  GND            VSS71  @S9S_MB_2U_LIB.S9S_MB_2U(SCH_1):GND
  164  GND            VSS70  @S9S_MB_2U_LIB.S9S_MB_2U(SCH_1):GND
  162  GND            VSS69  @S9S_MB_2U_LIB.S9S_MB_2U(SCH_1):GND
  160  GND            VSS68  @S9S_MB_2U_LIB.S9S_MB_2U(SCH_1):GND
  158  GND            VSS67  @S9S_MB_2U_LIB.S9S_MB_2U(SCH_1):GND
  155  GND            VSS66  @S9S_MB_2U_LIB.S9S_MB_2U(SCH_1):GND
  153  GND            VSS65  @S9S_MB_2U_LIB.S9S_MB_2U(SCH_1):GND
  151  GND            VSS64  @S9S_MB_2U_LIB.S9S_MB_2U(SCH_1):GND
  143  GND            VSS63  @S9S_MB_2U_LIB.S9S_MB_2U(SCH_1):GND
  141  GND            VSS62  @S9S_MB_2U_LIB.S9S_MB_2U(SCH_1):GND
  139  GND            VSS61  @S9S_MB_2U_LIB.S9S_MB_2U(SCH_1):GND
  136  GND            VSS60  @S9S_MB_2U_LIB.S9S_MB_2U(SCH_1):GND
  134  GND            VSS59  @S9S_MB_2U_LIB.S9S_MB_2U(SCH_1):GND
  132  GND            VSS58  @S9S_MB_2U_LIB.S9S_MB_2U(SCH_1):GND
  130  GND            VSS57  @S9S_MB_2U_LIB.S9S_MB_2U(SCH_1):GND
  128  GND            VSS56  @S9S_MB_2U_LIB.S9S_MB_2U(SCH_1):GND
  125  GND            VSS55  @S9S_MB_2U_LIB.S9S_MB_2U(SCH_1):GND
  123  GND            VSS54  @S9S_MB_2U_LIB.S9S_MB_2U(SCH_1):GND
  121  GND            VSS53  @S9S_MB_2U_LIB.S9S_MB_2U(SCH_1):GND
  119  GND            VSS52  @S9S_MB_2U_LIB.S9S_MB_2U(SCH_1):GND
  117  GND            VSS51  @S9S_MB_2U_LIB.S9S_MB_2U(SCH_1):GND
  114  GND            VSS50  @S9S_MB_2U_LIB.S9S_MB_2U(SCH_1):GND
  112  GND            VSS49  @S9S_MB_2U_LIB.S9S_MB_2U(SCH_1):GND
  110  GND            VSS48  @S9S_MB_2U_LIB.S9S_MB_2U(SCH_1):GND
  108  GND            VSS47  @S9S_MB_2U_LIB.S9S_MB_2U(SCH_1):GND
  106  GND            VSS46  @S9S_MB_2U_LIB.S9S_MB_2U(SCH_1):GND
  103  GND            VSS45  @S9S_MB_2U_LIB.S9S_MB_2U(SCH_1):GND
  101  GND            VSS44  @S9S_MB_2U_LIB.S9S_MB_2U(SCH_1):GND
   99  GND            VSS43  @S9S_MB_2U_LIB.S9S_MB_2U(SCH_1):GND
   97  GND            VSS42  @S9S_MB_2U_LIB.S9S_MB_2U(SCH_1):GND
   95  GND            VSS41  @S9S_MB_2U_LIB.S9S_MB_2U(SCH_1):GND
   92  GND            VSS40  @S9S_MB_2U_LIB.S9S_MB_2U(SCH_1):GND
   90  GND            VSS39  @S9S_MB_2U_LIB.S9S_MB_2U(SCH_1):GND
   88  GND            VSS38  @S9S_MB_2U_LIB.S9S_MB_2U(SCH_1):GND
   85  GND            VSS37  @S9S_MB_2U_LIB.S9S_MB_2U(SCH_1):GND
   83  GND            VSS36  @S9S_MB_2U_LIB.S9S_MB_2U(SCH_1):GND
   81  GND            VSS35  @S9S_MB_2U_LIB.S9S_MB_2U(SCH_1):GND
   79  GND            VSS34  @S9S_MB_2U_LIB.S9S_MB_2U(SCH_1):GND
   77  GND            VSS33  @S9S_MB_2U_LIB.S9S_MB_2U(SCH_1):GND
   75  GND            VSS32  @S9S_MB_2U_LIB.S9S_MB_2U(SCH_1):GND
   73  GND            VSS31  @S9S_MB_2U_LIB.S9S_MB_2U(SCH_1):GND
   71  GND            VSS30  @S9S_MB_2U_LIB.S9S_MB_2U(SCH_1):GND
   69  GND            VSS29  @S9S_MB_2U_LIB.S9S_MB_2U(SCH_1):GND
   67  GND            VSS28  @S9S_MB_2U_LIB.S9S_MB_2U(SCH_1):GND
   65  GND            VSS27  @S9S_MB_2U_LIB.S9S_MB_2U(SCH_1):GND
   63  GND            VSS26  @S9S_MB_2U_LIB.S9S_MB_2U(SCH_1):GND
   61  GND            VSS25  @S9S_MB_2U_LIB.S9S_MB_2U(SCH_1):GND
   59  GND            VSS24  @S9S_MB_2U_LIB.S9S_MB_2U(SCH_1):GND
   57  GND            VSS23  @S9S_MB_2U_LIB.S9S_MB_2U(SCH_1):GND
   54  GND            VSS22  @S9S_MB_2U_LIB.S9S_MB_2U(SCH_1):GND
   52  GND            VSS21  @S9S_MB_2U_LIB.S9S_MB_2U(SCH_1):GND
   50  GND            VSS20  @S9S_MB_2U_LIB.S9S_MB_2U(SCH_1):GND
   48  GND            VSS19  @S9S_MB_2U_LIB.S9S_MB_2U(SCH_1):GND
   46  GND            VSS18  @S9S_MB_2U_LIB.S9S_MB_2U(SCH_1):GND
   43  GND            VSS17  @S9S_MB_2U_LIB.S9S_MB_2U(SCH_1):GND
   41  GND            VSS16  @S9S_MB_2U_LIB.S9S_MB_2U(SCH_1):GND
   39  GND            VSS15  @S9S_MB_2U_LIB.S9S_MB_2U(SCH_1):GND
   37  GND            VSS14  @S9S_MB_2U_LIB.S9S_MB_2U(SCH_1):GND
   35  GND            VSS13  @S9S_MB_2U_LIB.S9S_MB_2U(SCH_1):GND
   32  GND            VSS12  @S9S_MB_2U_LIB.S9S_MB_2U(SCH_1):GND
   30  GND            VSS11  @S9S_MB_2U_LIB.S9S_MB_2U(SCH_1):GND
   28  GND            VSS10  @S9S_MB_2U_LIB.S9S_MB_2U(SCH_1):GND
   26  GND             VSS9  @S9S_MB_2U_LIB.S9S_MB_2U(SCH_1):GND
   24  GND             VSS8  @S9S_MB_2U_LIB.S9S_MB_2U(SCH_1):GND
   21  GND             VSS7  @S9S_MB_2U_LIB.S9S_MB_2U(SCH_1):GND
   19  GND             VSS6  @S9S_MB_2U_LIB.S9S_MB_2U(SCH_1):GND
   17  GND             VSS5  @S9S_MB_2U_LIB.S9S_MB_2U(SCH_1):GND
   15  GND             VSS4  @S9S_MB_2U_LIB.S9S_MB_2U(SCH_1):GND
   13  GND             VSS3  @S9S_MB_2U_LIB.S9S_MB_2U(SCH_1):GND
   10  GND             VSS2  @S9S_MB_2U_LIB.S9S_MB_2U(SCH_1):GND
    8  GND             VSS1  @S9S_MB_2U_LIB.S9S_MB_2U(SCH_1):GND
    6  GND             VSS0  @S9S_MB_2U_LIB.S9S_MB_2U(SCH_1):GND
   G3  GND               G3  @S9S_MB_2U_LIB.S9S_MB_2U(SCH_1):GND
   G2  GND               G2  @S9S_MB_2U_LIB.S9S_MB_2U(SCH_1):GND
   G1  GND               G1  @S9S_MB_2U_LIB.S9S_MB_2U(SCH_1):GND

SCONN288_ADR50001P013C01  I126  J21    [SCONN288_ADR50001P013C01-SCONNA]
   93  M_C_CPU1_SB_DQS_DP<9>  DQS9_B_P  @S9S_MB_2U_LIB.S9S_MB_2U(SCH_1):M_C_CPU1_SB_DQS_DP<9>
  283  M_C_CPU1_SB_DQS_DP<8>  DQS8_B_P  @S9S_MB_2U_LIB.S9S_MB_2U(SCH_1):M_C_CPU1_SB_DQS_DP<8>
  272  M_C_CPU1_SB_DQS_DP<7>  DQS7_B_P  @S9S_MB_2U_LIB.S9S_MB_2U(SCH_1):M_C_CPU1_SB_DQS_DP<7>
  261  M_C_CPU1_SB_DQS_DP<6>  DQS6_B_P  @S9S_MB_2U_LIB.S9S_MB_2U(SCH_1):M_C_CPU1_SB_DQS_DP<6>
  250  M_C_CPU1_SB_DQS_DP<5>  DQS5_B_P  @S9S_MB_2U_LIB.S9S_MB_2U(SCH_1):M_C_CPU1_SB_DQS_DP<5>
  239  M_C_CPU1_SB_DQS_DP<4>  DQS4_B_P  @S9S_MB_2U_LIB.S9S_MB_2U(SCH_1):M_C_CPU1_SB_DQS_DP<4>
  137  M_C_CPU1_SB_DQS_DP<3>  DQS3_B_P  @S9S_MB_2U_LIB.S9S_MB_2U(SCH_1):M_C_CPU1_SB_DQS_DP<3>
  126  M_C_CPU1_SB_DQS_DP<2>  DQS2_B_P  @S9S_MB_2U_LIB.S9S_MB_2U(SCH_1):M_C_CPU1_SB_DQS_DP<2>
  115  M_C_CPU1_SB_DQS_DP<1>  DQS1_B_P  @S9S_MB_2U_LIB.S9S_MB_2U(SCH_1):M_C_CPU1_SB_DQS_DP<1>
  104  M_C_CPU1_SB_DQS_DP<0>  DQS0_B_P  @S9S_MB_2U_LIB.S9S_MB_2U(SCH_1):M_C_CPU1_SB_DQS_DP<0>
   94  M_C_CPU1_SB_DQS_DN<9>  DQS9_B_N  @S9S_MB_2U_LIB.S9S_MB_2U(SCH_1):M_C_CPU1_SB_DQS_DN<9>
  282  M_C_CPU1_SB_DQS_DN<8>  DQS8_B_N  @S9S_MB_2U_LIB.S9S_MB_2U(SCH_1):M_C_CPU1_SB_DQS_DN<8>
  271  M_C_CPU1_SB_DQS_DN<7>  DQS7_B_N  @S9S_MB_2U_LIB.S9S_MB_2U(SCH_1):M_C_CPU1_SB_DQS_DN<7>
  260  M_C_CPU1_SB_DQS_DN<6>  DQS6_B_N  @S9S_MB_2U_LIB.S9S_MB_2U(SCH_1):M_C_CPU1_SB_DQS_DN<6>
  249  M_C_CPU1_SB_DQS_DN<5>  DQS5_B_N  @S9S_MB_2U_LIB.S9S_MB_2U(SCH_1):M_C_CPU1_SB_DQS_DN<5>
  238  M_C_CPU1_SB_DQS_DN<4>  DQS4_B_N  @S9S_MB_2U_LIB.S9S_MB_2U(SCH_1):M_C_CPU1_SB_DQS_DN<4>
  138  M_C_CPU1_SB_DQS_DN<3>  DQS3_B_N  @S9S_MB_2U_LIB.S9S_MB_2U(SCH_1):M_C_CPU1_SB_DQS_DN<3>
  127  M_C_CPU1_SB_DQS_DN<2>  DQS2_B_N  @S9S_MB_2U_LIB.S9S_MB_2U(SCH_1):M_C_CPU1_SB_DQS_DN<2>
  116  M_C_CPU1_SB_DQS_DN<1>  DQS1_B_N  @S9S_MB_2U_LIB.S9S_MB_2U(SCH_1):M_C_CPU1_SB_DQS_DN<1>
  105  M_C_CPU1_SB_DQS_DN<0>  DQS0_B_N  @S9S_MB_2U_LIB.S9S_MB_2U(SCH_1):M_C_CPU1_SB_DQS_DN<0>
  201  M_C_CPU1_SA_DQS_DP<9>  DQS9_A_P  @S9S_MB_2U_LIB.S9S_MB_2U(SCH_1):M_C_CPU1_SA_DQS_DP<9>
  190  M_C_CPU1_SA_DQS_DP<8>  DQS8_A_P  @S9S_MB_2U_LIB.S9S_MB_2U(SCH_1):M_C_CPU1_SA_DQS_DP<8>
  179  M_C_CPU1_SA_DQS_DP<7>  DQS7_A_P  @S9S_MB_2U_LIB.S9S_MB_2U(SCH_1):M_C_CPU1_SA_DQS_DP<7>
  168  M_C_CPU1_SA_DQS_DP<6>  DQS6_A_P  @S9S_MB_2U_LIB.S9S_MB_2U(SCH_1):M_C_CPU1_SA_DQS_DP<6>
  157  M_C_CPU1_SA_DQS_DP<5>  DQS5_A_P  @S9S_MB_2U_LIB.S9S_MB_2U(SCH_1):M_C_CPU1_SA_DQS_DP<5>
   55  M_C_CPU1_SA_DQS_DP<4>  DQS4_A_P  @S9S_MB_2U_LIB.S9S_MB_2U(SCH_1):M_C_CPU1_SA_DQS_DP<4>
   44  M_C_CPU1_SA_DQS_DP<3>  DQS3_A_P  @S9S_MB_2U_LIB.S9S_MB_2U(SCH_1):M_C_CPU1_SA_DQS_DP<3>
   33  M_C_CPU1_SA_DQS_DP<2>  DQS2_A_P  @S9S_MB_2U_LIB.S9S_MB_2U(SCH_1):M_C_CPU1_SA_DQS_DP<2>
   22  M_C_CPU1_SA_DQS_DP<1>  DQS1_A_P  @S9S_MB_2U_LIB.S9S_MB_2U(SCH_1):M_C_CPU1_SA_DQS_DP<1>
   11  M_C_CPU1_SA_DQS_DP<0>  DQS0_A_P  @S9S_MB_2U_LIB.S9S_MB_2U(SCH_1):M_C_CPU1_SA_DQS_DP<0>
  200  M_C_CPU1_SA_DQS_DN<9>  DQS9_A_N  @S9S_MB_2U_LIB.S9S_MB_2U(SCH_1):M_C_CPU1_SA_DQS_DN<9>
  189  M_C_CPU1_SA_DQS_DN<8>  DQS8_A_N  @S9S_MB_2U_LIB.S9S_MB_2U(SCH_1):M_C_CPU1_SA_DQS_DN<8>
  178  M_C_CPU1_SA_DQS_DN<7>  DQS7_A_N  @S9S_MB_2U_LIB.S9S_MB_2U(SCH_1):M_C_CPU1_SA_DQS_DN<7>
  167  M_C_CPU1_SA_DQS_DN<6>  DQS6_A_N  @S9S_MB_2U_LIB.S9S_MB_2U(SCH_1):M_C_CPU1_SA_DQS_DN<6>
  156  M_C_CPU1_SA_DQS_DN<5>  DQS5_A_N  @S9S_MB_2U_LIB.S9S_MB_2U(SCH_1):M_C_CPU1_SA_DQS_DN<5>
   56  M_C_CPU1_SA_DQS_DN<4>  DQS4_A_N  @S9S_MB_2U_LIB.S9S_MB_2U(SCH_1):M_C_CPU1_SA_DQS_DN<4>
   45  M_C_CPU1_SA_DQS_DN<3>  DQS3_A_N  @S9S_MB_2U_LIB.S9S_MB_2U(SCH_1):M_C_CPU1_SA_DQS_DN<3>
   34  M_C_CPU1_SA_DQS_DN<2>  DQS2_A_N  @S9S_MB_2U_LIB.S9S_MB_2U(SCH_1):M_C_CPU1_SA_DQS_DN<2>
   23  M_C_CPU1_SA_DQS_DN<1>  DQS1_A_N  @S9S_MB_2U_LIB.S9S_MB_2U(SCH_1):M_C_CPU1_SA_DQS_DN<1>
   12  M_C_CPU1_SA_DQS_DN<0>  DQS0_A_N  @S9S_MB_2U_LIB.S9S_MB_2U(SCH_1):M_C_CPU1_SA_DQS_DN<0>

SCONN288_ADR50001P013C01  I13  J21    [SCONN288_ADR50001P013C01-SCONNA]
  232  NC              RFU6  NC
  231  NC              RFU5  NC
  220  NC              RFU4  NC
  150  NC              RFU3  NC
  149  NC              RFU2  NC
  144  NC              RFU1  NC
    2  NC              RFU0  NC
  207  RST_M_CD_CPU1_FPGA_N  RESET_N  @S9S_MB_2U_LIB.S9S_MB_2U(SCH_1):RST_M_CD_CPU1_FPGA_N
  147  PWRGD_CHC_CPU1_DIMM1  PWR_GOOD||FAIL_N  @S9S_MB_2U_LIB.S9S_MB_2U(SCH_1):PWRGD_CHC_CPU1_DIMM1
  148  PD_CHC_CPU1_DIMM1_SAA    HAS  @S9S_MB_2U_LIB.S9S_MB_2U(SCH_1):PD_CHC_CPU1_DIMM1_SAA
    3  P3V3_AUX       VIN_MGMT  @S9S_MB_2U_LIB.S9S_MB_2U(SCH_1):P3V3_AUX
   87  M_C_CPU1_SB_RSP<0>  LBS||RSP_N_B  @S9S_MB_2U_LIB.S9S_MB_2U(SCH_1):M_C_CPU1_SB_RSP<0>
  227  M_C_CPU1_SB_PAR  PAR_B  @S9S_MB_2U_LIB.S9S_MB_2U(SCH_1):M_C_CPU1_SB_PAR
  113  M_C_CPU1_SB_DQ<9>  DQ_B9  @S9S_MB_2U_LIB.S9S_MB_2U(SCH_1):M_C_CPU1_SB_DQ<9>
  111  M_C_CPU1_SB_DQ<8>  DQ_B8  @S9S_MB_2U_LIB.S9S_MB_2U(SCH_1):M_C_CPU1_SB_DQ<8>
  254  M_C_CPU1_SB_DQ<7>  DQ_B7  @S9S_MB_2U_LIB.S9S_MB_2U(SCH_1):M_C_CPU1_SB_DQ<7>
  252  M_C_CPU1_SB_DQ<6>  DQ_B6  @S9S_MB_2U_LIB.S9S_MB_2U(SCH_1):M_C_CPU1_SB_DQ<6>
  109  M_C_CPU1_SB_DQ<5>  DQ_B5  @S9S_MB_2U_LIB.S9S_MB_2U(SCH_1):M_C_CPU1_SB_DQ<5>
  107  M_C_CPU1_SB_DQ<4>  DQ_B4  @S9S_MB_2U_LIB.S9S_MB_2U(SCH_1):M_C_CPU1_SB_DQ<4>
  247  M_C_CPU1_SB_DQ<3>  DQ_B3  @S9S_MB_2U_LIB.S9S_MB_2U(SCH_1):M_C_CPU1_SB_DQ<3>
  287  M_C_CPU1_SB_DQ<31>  DQ_B31  @S9S_MB_2U_LIB.S9S_MB_2U(SCH_1):M_C_CPU1_SB_DQ<31>
  285  M_C_CPU1_SB_DQ<30>  DQ_B30  @S9S_MB_2U_LIB.S9S_MB_2U(SCH_1):M_C_CPU1_SB_DQ<30>
  245  M_C_CPU1_SB_DQ<2>  DQ_B2  @S9S_MB_2U_LIB.S9S_MB_2U(SCH_1):M_C_CPU1_SB_DQ<2>
  142  M_C_CPU1_SB_DQ<29>  DQ_B29  @S9S_MB_2U_LIB.S9S_MB_2U(SCH_1):M_C_CPU1_SB_DQ<29>
  140  M_C_CPU1_SB_DQ<28>  DQ_B28  @S9S_MB_2U_LIB.S9S_MB_2U(SCH_1):M_C_CPU1_SB_DQ<28>
  280  M_C_CPU1_SB_DQ<27>  DQ_B27  @S9S_MB_2U_LIB.S9S_MB_2U(SCH_1):M_C_CPU1_SB_DQ<27>
  278  M_C_CPU1_SB_DQ<26>  DQ_B26  @S9S_MB_2U_LIB.S9S_MB_2U(SCH_1):M_C_CPU1_SB_DQ<26>
  135  M_C_CPU1_SB_DQ<25>  DQ_B25  @S9S_MB_2U_LIB.S9S_MB_2U(SCH_1):M_C_CPU1_SB_DQ<25>
  133  M_C_CPU1_SB_DQ<24>  DQ_B24  @S9S_MB_2U_LIB.S9S_MB_2U(SCH_1):M_C_CPU1_SB_DQ<24>
  276  M_C_CPU1_SB_DQ<23>  DQ_B23  @S9S_MB_2U_LIB.S9S_MB_2U(SCH_1):M_C_CPU1_SB_DQ<23>
  274  M_C_CPU1_SB_DQ<22>  DQ_B22  @S9S_MB_2U_LIB.S9S_MB_2U(SCH_1):M_C_CPU1_SB_DQ<22>
  131  M_C_CPU1_SB_DQ<21>  DQ_B21  @S9S_MB_2U_LIB.S9S_MB_2U(SCH_1):M_C_CPU1_SB_DQ<21>
  129  M_C_CPU1_SB_DQ<20>  DQ_B20  @S9S_MB_2U_LIB.S9S_MB_2U(SCH_1):M_C_CPU1_SB_DQ<20>
  102  M_C_CPU1_SB_DQ<1>  DQ_B1  @S9S_MB_2U_LIB.S9S_MB_2U(SCH_1):M_C_CPU1_SB_DQ<1>
  269  M_C_CPU1_SB_DQ<19>  DQ_B19  @S9S_MB_2U_LIB.S9S_MB_2U(SCH_1):M_C_CPU1_SB_DQ<19>
  267  M_C_CPU1_SB_DQ<18>  DQ_B18  @S9S_MB_2U_LIB.S9S_MB_2U(SCH_1):M_C_CPU1_SB_DQ<18>
  124  M_C_CPU1_SB_DQ<17>  DQ_B17  @S9S_MB_2U_LIB.S9S_MB_2U(SCH_1):M_C_CPU1_SB_DQ<17>
  122  M_C_CPU1_SB_DQ<16>  DQ_B16  @S9S_MB_2U_LIB.S9S_MB_2U(SCH_1):M_C_CPU1_SB_DQ<16>
  265  M_C_CPU1_SB_DQ<15>  DQ_B15  @S9S_MB_2U_LIB.S9S_MB_2U(SCH_1):M_C_CPU1_SB_DQ<15>
  263  M_C_CPU1_SB_DQ<14>  DQ_B14  @S9S_MB_2U_LIB.S9S_MB_2U(SCH_1):M_C_CPU1_SB_DQ<14>
  120  M_C_CPU1_SB_DQ<13>  DQ_B13  @S9S_MB_2U_LIB.S9S_MB_2U(SCH_1):M_C_CPU1_SB_DQ<13>
  118  M_C_CPU1_SB_DQ<12>  DQ_B12  @S9S_MB_2U_LIB.S9S_MB_2U(SCH_1):M_C_CPU1_SB_DQ<12>
  258  M_C_CPU1_SB_DQ<11>  DQ_B11  @S9S_MB_2U_LIB.S9S_MB_2U(SCH_1):M_C_CPU1_SB_DQ<11>
  256  M_C_CPU1_SB_DQ<10>  DQ_B10  @S9S_MB_2U_LIB.S9S_MB_2U(SCH_1):M_C_CPU1_SB_DQ<10>
  100  M_C_CPU1_SB_DQ<0>  DQ_B0  @S9S_MB_2U_LIB.S9S_MB_2U(SCH_1):M_C_CPU1_SB_DQ<0>
  229  M_C_CPU1_SB_CS_N<1>  CS1_N_B  @S9S_MB_2U_LIB.S9S_MB_2U(SCH_1):M_C_CPU1_SB_CS_N<1>
   84  M_C_CPU1_SB_CS_N<0>  CS0_N_B  @S9S_MB_2U_LIB.S9S_MB_2U(SCH_1):M_C_CPU1_SB_CS_N<0>
  236  M_C_CPU1_SB_CB<7>  CB_B7  @S9S_MB_2U_LIB.S9S_MB_2U(SCH_1):M_C_CPU1_SB_CB<7>
  234  M_C_CPU1_SB_CB<6>  CB_B6  @S9S_MB_2U_LIB.S9S_MB_2U(SCH_1):M_C_CPU1_SB_CB<6>
   91  M_C_CPU1_SB_CB<5>  CB_B5  @S9S_MB_2U_LIB.S9S_MB_2U(SCH_1):M_C_CPU1_SB_CB<5>
   89  M_C_CPU1_SB_CB<4>  CB_B4  @S9S_MB_2U_LIB.S9S_MB_2U(SCH_1):M_C_CPU1_SB_CB<4>
  243  M_C_CPU1_SB_CB<3>  CB_B3  @S9S_MB_2U_LIB.S9S_MB_2U(SCH_1):M_C_CPU1_SB_CB<3>
  241  M_C_CPU1_SB_CB<2>  CB_B2  @S9S_MB_2U_LIB.S9S_MB_2U(SCH_1):M_C_CPU1_SB_CB<2>
   98  M_C_CPU1_SB_CB<1>  CB_B1  @S9S_MB_2U_LIB.S9S_MB_2U(SCH_1):M_C_CPU1_SB_CB<1>
   96  M_C_CPU1_SB_CB<0>  CB_B0  @S9S_MB_2U_LIB.S9S_MB_2U(SCH_1):M_C_CPU1_SB_CB<0>
   82  M_C_CPU1_SB_CA<6>  CA6_B  @S9S_MB_2U_LIB.S9S_MB_2U(SCH_1):M_C_CPU1_SB_CA<6>
  225  M_C_CPU1_SB_CA<5>  CA5_B  @S9S_MB_2U_LIB.S9S_MB_2U(SCH_1):M_C_CPU1_SB_CA<5>
   80  M_C_CPU1_SB_CA<4>  CA4_B  @S9S_MB_2U_LIB.S9S_MB_2U(SCH_1):M_C_CPU1_SB_CA<4>
  223  M_C_CPU1_SB_CA<3>  CA3_B  @S9S_MB_2U_LIB.S9S_MB_2U(SCH_1):M_C_CPU1_SB_CA<3>
   78  M_C_CPU1_SB_CA<2>  CA2_B  @S9S_MB_2U_LIB.S9S_MB_2U(SCH_1):M_C_CPU1_SB_CA<2>
  221  M_C_CPU1_SB_CA<1>  CA1_B  @S9S_MB_2U_LIB.S9S_MB_2U(SCH_1):M_C_CPU1_SB_CA<1>
   76  M_C_CPU1_SB_CA<0>  CA0_B  @S9S_MB_2U_LIB.S9S_MB_2U(SCH_1):M_C_CPU1_SB_CA<0>
   86  M_C_CPU1_SA_RSP<0>  LBD||RSP_N_A  @S9S_MB_2U_LIB.S9S_MB_2U(SCH_1):M_C_CPU1_SA_RSP<0>
   74  M_C_CPU1_SA_PAR  PAR_A  @S9S_MB_2U_LIB.S9S_MB_2U(SCH_1):M_C_CPU1_SA_PAR
   20  M_C_CPU1_SA_DQ<9>  DQ_A9  @S9S_MB_2U_LIB.S9S_MB_2U(SCH_1):M_C_CPU1_SA_DQ<9>
   18  M_C_CPU1_SA_DQ<8>  DQ_A8  @S9S_MB_2U_LIB.S9S_MB_2U(SCH_1):M_C_CPU1_SA_DQ<8>
  161  M_C_CPU1_SA_DQ<7>  DQ_A7  @S9S_MB_2U_LIB.S9S_MB_2U(SCH_1):M_C_CPU1_SA_DQ<7>
  159  M_C_CPU1_SA_DQ<6>  DQ_A6  @S9S_MB_2U_LIB.S9S_MB_2U(SCH_1):M_C_CPU1_SA_DQ<6>
   16  M_C_CPU1_SA_DQ<5>  DQ_A5  @S9S_MB_2U_LIB.S9S_MB_2U(SCH_1):M_C_CPU1_SA_DQ<5>
   14  M_C_CPU1_SA_DQ<4>  DQ_A4  @S9S_MB_2U_LIB.S9S_MB_2U(SCH_1):M_C_CPU1_SA_DQ<4>
  154  M_C_CPU1_SA_DQ<3>  DQ_A3  @S9S_MB_2U_LIB.S9S_MB_2U(SCH_1):M_C_CPU1_SA_DQ<3>
  194  M_C_CPU1_SA_DQ<31>  DQ_A31  @S9S_MB_2U_LIB.S9S_MB_2U(SCH_1):M_C_CPU1_SA_DQ<31>
  192  M_C_CPU1_SA_DQ<30>  DQ_A30  @S9S_MB_2U_LIB.S9S_MB_2U(SCH_1):M_C_CPU1_SA_DQ<30>
  152  M_C_CPU1_SA_DQ<2>  DQ_A2  @S9S_MB_2U_LIB.S9S_MB_2U(SCH_1):M_C_CPU1_SA_DQ<2>
   49  M_C_CPU1_SA_DQ<29>  DQ_A29  @S9S_MB_2U_LIB.S9S_MB_2U(SCH_1):M_C_CPU1_SA_DQ<29>
   47  M_C_CPU1_SA_DQ<28>  DQ_A28  @S9S_MB_2U_LIB.S9S_MB_2U(SCH_1):M_C_CPU1_SA_DQ<28>
  187  M_C_CPU1_SA_DQ<27>  DQ_A27  @S9S_MB_2U_LIB.S9S_MB_2U(SCH_1):M_C_CPU1_SA_DQ<27>
  185  M_C_CPU1_SA_DQ<26>  DQ_A26  @S9S_MB_2U_LIB.S9S_MB_2U(SCH_1):M_C_CPU1_SA_DQ<26>
   42  M_C_CPU1_SA_DQ<25>  DQ_A25  @S9S_MB_2U_LIB.S9S_MB_2U(SCH_1):M_C_CPU1_SA_DQ<25>
   40  M_C_CPU1_SA_DQ<24>  DQ_A24  @S9S_MB_2U_LIB.S9S_MB_2U(SCH_1):M_C_CPU1_SA_DQ<24>
  183  M_C_CPU1_SA_DQ<23>  DQ_A23  @S9S_MB_2U_LIB.S9S_MB_2U(SCH_1):M_C_CPU1_SA_DQ<23>
  181  M_C_CPU1_SA_DQ<22>  DQ_A22  @S9S_MB_2U_LIB.S9S_MB_2U(SCH_1):M_C_CPU1_SA_DQ<22>
   38  M_C_CPU1_SA_DQ<21>  DQ_A21  @S9S_MB_2U_LIB.S9S_MB_2U(SCH_1):M_C_CPU1_SA_DQ<21>
   36  M_C_CPU1_SA_DQ<20>  DQ_A20  @S9S_MB_2U_LIB.S9S_MB_2U(SCH_1):M_C_CPU1_SA_DQ<20>
    9  M_C_CPU1_SA_DQ<1>  DQ_A1  @S9S_MB_2U_LIB.S9S_MB_2U(SCH_1):M_C_CPU1_SA_DQ<1>
  176  M_C_CPU1_SA_DQ<19>  DQ_A19  @S9S_MB_2U_LIB.S9S_MB_2U(SCH_1):M_C_CPU1_SA_DQ<19>
  174  M_C_CPU1_SA_DQ<18>  DQ_A18  @S9S_MB_2U_LIB.S9S_MB_2U(SCH_1):M_C_CPU1_SA_DQ<18>
   31  M_C_CPU1_SA_DQ<17>  DQ_A17  @S9S_MB_2U_LIB.S9S_MB_2U(SCH_1):M_C_CPU1_SA_DQ<17>
   29  M_C_CPU1_SA_DQ<16>  DQ_A16  @S9S_MB_2U_LIB.S9S_MB_2U(SCH_1):M_C_CPU1_SA_DQ<16>
  172  M_C_CPU1_SA_DQ<15>  DQ_A15  @S9S_MB_2U_LIB.S9S_MB_2U(SCH_1):M_C_CPU1_SA_DQ<15>
  170  M_C_CPU1_SA_DQ<14>  DQ_A14  @S9S_MB_2U_LIB.S9S_MB_2U(SCH_1):M_C_CPU1_SA_DQ<14>
   27  M_C_CPU1_SA_DQ<13>  DQ_A13  @S9S_MB_2U_LIB.S9S_MB_2U(SCH_1):M_C_CPU1_SA_DQ<13>
   25  M_C_CPU1_SA_DQ<12>  DQ_A12  @S9S_MB_2U_LIB.S9S_MB_2U(SCH_1):M_C_CPU1_SA_DQ<12>
  165  M_C_CPU1_SA_DQ<11>  DQ_A11  @S9S_MB_2U_LIB.S9S_MB_2U(SCH_1):M_C_CPU1_SA_DQ<11>
  163  M_C_CPU1_SA_DQ<10>  DQ_A10  @S9S_MB_2U_LIB.S9S_MB_2U(SCH_1):M_C_CPU1_SA_DQ<10>
    7  M_C_CPU1_SA_DQ<0>  DQ_A0  @S9S_MB_2U_LIB.S9S_MB_2U(SCH_1):M_C_CPU1_SA_DQ<0>
  209  M_C_CPU1_SA_CS_N<1>  CS1_N_A  @S9S_MB_2U_LIB.S9S_MB_2U(SCH_1):M_C_CPU1_SA_CS_N<1>
   64  M_C_CPU1_SA_CS_N<0>  CS0_N_A  @S9S_MB_2U_LIB.S9S_MB_2U(SCH_1):M_C_CPU1_SA_CS_N<0>
  205  M_C_CPU1_SA_CB<7>  CB_A7  @S9S_MB_2U_LIB.S9S_MB_2U(SCH_1):M_C_CPU1_SA_CB<7>
  203  M_C_CPU1_SA_CB<6>  CB_A6  @S9S_MB_2U_LIB.S9S_MB_2U(SCH_1):M_C_CPU1_SA_CB<6>
   60  M_C_CPU1_SA_CB<5>  CB_A5  @S9S_MB_2U_LIB.S9S_MB_2U(SCH_1):M_C_CPU1_SA_CB<5>
   58  M_C_CPU1_SA_CB<4>  CB_A4  @S9S_MB_2U_LIB.S9S_MB_2U(SCH_1):M_C_CPU1_SA_CB<4>
  198  M_C_CPU1_SA_CB<3>  CB_A3  @S9S_MB_2U_LIB.S9S_MB_2U(SCH_1):M_C_CPU1_SA_CB<3>
  196  M_C_CPU1_SA_CB<2>  CB_A2  @S9S_MB_2U_LIB.S9S_MB_2U(SCH_1):M_C_CPU1_SA_CB<2>
   53  M_C_CPU1_SA_CB<1>  CB_A1  @S9S_MB_2U_LIB.S9S_MB_2U(SCH_1):M_C_CPU1_SA_CB<1>
   51  M_C_CPU1_SA_CB<0>  CB_A0  @S9S_MB_2U_LIB.S9S_MB_2U(SCH_1):M_C_CPU1_SA_CB<0>
   72  M_C_CPU1_SA_CA<6>  CA6_A  @S9S_MB_2U_LIB.S9S_MB_2U(SCH_1):M_C_CPU1_SA_CA<6>
  215  M_C_CPU1_SA_CA<5>  CA5_A  @S9S_MB_2U_LIB.S9S_MB_2U(SCH_1):M_C_CPU1_SA_CA<5>
   70  M_C_CPU1_SA_CA<4>  CA4_A  @S9S_MB_2U_LIB.S9S_MB_2U(SCH_1):M_C_CPU1_SA_CA<4>
  213  M_C_CPU1_SA_CA<3>  CA3_A  @S9S_MB_2U_LIB.S9S_MB_2U(SCH_1):M_C_CPU1_SA_CA<3>
   68  M_C_CPU1_SA_CA<2>  CA2_A  @S9S_MB_2U_LIB.S9S_MB_2U(SCH_1):M_C_CPU1_SA_CA<2>
  211  M_C_CPU1_SA_CA<1>  CA1_A  @S9S_MB_2U_LIB.S9S_MB_2U(SCH_1):M_C_CPU1_SA_CA<1>
   66  M_C_CPU1_SA_CA<0>  CA0_A  @S9S_MB_2U_LIB.S9S_MB_2U(SCH_1):M_C_CPU1_SA_CA<0>
  217  M_C_CPU1_CLK_DP<0>   CK_P  @S9S_MB_2U_LIB.S9S_MB_2U(SCH_1):M_C_CPU1_CLK_DP<0>
  218  M_C_CPU1_CLK_DN<0>   CK_N  @S9S_MB_2U_LIB.S9S_MB_2U(SCH_1):M_C_CPU1_CLK_DN<0>
   62  M_C_CPU1_ALERT_N  ALERT_N  @S9S_MB_2U_LIB.S9S_MB_2U(SCH_1):M_C_CPU1_ALERT_N
    5  I3C_SPD_DDRABCD_CPU1_LVC1_SDA   HSDA  @S9S_MB_2U_LIB.S9S_MB_2U(SCH_1):I3C_SPD_DDRABCD_CPU1_LVC1_SDA
    4  I3C_SPD_DDRABCD_CPU1_LVC1_SCL   HSCL  @S9S_MB_2U_LIB.S9S_MB_2U(SCH_1):I3C_SPD_DDRABCD_CPU1_LVC1_SCL

SCONN288_ADR50001P003C01  I176  J22    [SCONN288_ADR50001P003C01-SCONNA]
  146  P12V_S3_AUX_CPU1_NVDIMM  VIN_BULK2  @S9S_MB_2U_LIB.S9S_MB_2U(SCH_1):P12V_S3_AUX_CPU1_NVDIMM
  145  P12V_S3_AUX_CPU1_NVDIMM  VIN_BULK1  @S9S_MB_2U_LIB.S9S_MB_2U(SCH_1):P12V_S3_AUX_CPU1_NVDIMM
    1  P12V_S3_AUX_CPU1_NVDIMM  VIN_BULK0  @S9S_MB_2U_LIB.S9S_MB_2U(SCH_1):P12V_S3_AUX_CPU1_NVDIMM
  288  GND            VSS126  @S9S_MB_2U_LIB.S9S_MB_2U(SCH_1):GND
  286  GND            VSS125  @S9S_MB_2U_LIB.S9S_MB_2U(SCH_1):GND
  284  GND            VSS124  @S9S_MB_2U_LIB.S9S_MB_2U(SCH_1):GND
  281  GND            VSS123  @S9S_MB_2U_LIB.S9S_MB_2U(SCH_1):GND
  279  GND            VSS122  @S9S_MB_2U_LIB.S9S_MB_2U(SCH_1):GND
  277  GND            VSS121  @S9S_MB_2U_LIB.S9S_MB_2U(SCH_1):GND
  275  GND            VSS120  @S9S_MB_2U_LIB.S9S_MB_2U(SCH_1):GND
  273  GND            VSS119  @S9S_MB_2U_LIB.S9S_MB_2U(SCH_1):GND
  270  GND            VSS118  @S9S_MB_2U_LIB.S9S_MB_2U(SCH_1):GND
  268  GND            VSS117  @S9S_MB_2U_LIB.S9S_MB_2U(SCH_1):GND
  266  GND            VSS116  @S9S_MB_2U_LIB.S9S_MB_2U(SCH_1):GND
  264  GND            VSS115  @S9S_MB_2U_LIB.S9S_MB_2U(SCH_1):GND
  262  GND            VSS114  @S9S_MB_2U_LIB.S9S_MB_2U(SCH_1):GND
  259  GND            VSS113  @S9S_MB_2U_LIB.S9S_MB_2U(SCH_1):GND
  257  GND            VSS112  @S9S_MB_2U_LIB.S9S_MB_2U(SCH_1):GND
  255  GND            VSS111  @S9S_MB_2U_LIB.S9S_MB_2U(SCH_1):GND
  253  GND            VSS110  @S9S_MB_2U_LIB.S9S_MB_2U(SCH_1):GND
  251  GND            VSS109  @S9S_MB_2U_LIB.S9S_MB_2U(SCH_1):GND
  248  GND            VSS108  @S9S_MB_2U_LIB.S9S_MB_2U(SCH_1):GND
  246  GND            VSS107  @S9S_MB_2U_LIB.S9S_MB_2U(SCH_1):GND
  244  GND            VSS106  @S9S_MB_2U_LIB.S9S_MB_2U(SCH_1):GND
  242  GND            VSS105  @S9S_MB_2U_LIB.S9S_MB_2U(SCH_1):GND
  240  GND            VSS104  @S9S_MB_2U_LIB.S9S_MB_2U(SCH_1):GND
  237  GND            VSS103  @S9S_MB_2U_LIB.S9S_MB_2U(SCH_1):GND
  235  GND            VSS102  @S9S_MB_2U_LIB.S9S_MB_2U(SCH_1):GND
  233  GND            VSS101  @S9S_MB_2U_LIB.S9S_MB_2U(SCH_1):GND
  230  GND            VSS100  @S9S_MB_2U_LIB.S9S_MB_2U(SCH_1):GND
  228  GND            VSS99  @S9S_MB_2U_LIB.S9S_MB_2U(SCH_1):GND
  226  GND            VSS98  @S9S_MB_2U_LIB.S9S_MB_2U(SCH_1):GND
  224  GND            VSS97  @S9S_MB_2U_LIB.S9S_MB_2U(SCH_1):GND
  222  GND            VSS96  @S9S_MB_2U_LIB.S9S_MB_2U(SCH_1):GND
  219  GND            VSS95  @S9S_MB_2U_LIB.S9S_MB_2U(SCH_1):GND
  216  GND            VSS94  @S9S_MB_2U_LIB.S9S_MB_2U(SCH_1):GND
  214  GND            VSS93  @S9S_MB_2U_LIB.S9S_MB_2U(SCH_1):GND
  212  GND            VSS92  @S9S_MB_2U_LIB.S9S_MB_2U(SCH_1):GND
  210  GND            VSS91  @S9S_MB_2U_LIB.S9S_MB_2U(SCH_1):GND
  208  GND            VSS90  @S9S_MB_2U_LIB.S9S_MB_2U(SCH_1):GND
  206  GND            VSS89  @S9S_MB_2U_LIB.S9S_MB_2U(SCH_1):GND
  204  GND            VSS88  @S9S_MB_2U_LIB.S9S_MB_2U(SCH_1):GND
  202  GND            VSS87  @S9S_MB_2U_LIB.S9S_MB_2U(SCH_1):GND
  199  GND            VSS86  @S9S_MB_2U_LIB.S9S_MB_2U(SCH_1):GND
  197  GND            VSS85  @S9S_MB_2U_LIB.S9S_MB_2U(SCH_1):GND
  195  GND            VSS84  @S9S_MB_2U_LIB.S9S_MB_2U(SCH_1):GND
  193  GND            VSS83  @S9S_MB_2U_LIB.S9S_MB_2U(SCH_1):GND
  191  GND            VSS82  @S9S_MB_2U_LIB.S9S_MB_2U(SCH_1):GND
  188  GND            VSS81  @S9S_MB_2U_LIB.S9S_MB_2U(SCH_1):GND
  186  GND            VSS80  @S9S_MB_2U_LIB.S9S_MB_2U(SCH_1):GND
  184  GND            VSS79  @S9S_MB_2U_LIB.S9S_MB_2U(SCH_1):GND
  182  GND            VSS78  @S9S_MB_2U_LIB.S9S_MB_2U(SCH_1):GND
  180  GND            VSS77  @S9S_MB_2U_LIB.S9S_MB_2U(SCH_1):GND
  177  GND            VSS76  @S9S_MB_2U_LIB.S9S_MB_2U(SCH_1):GND
  175  GND            VSS75  @S9S_MB_2U_LIB.S9S_MB_2U(SCH_1):GND
  173  GND            VSS74  @S9S_MB_2U_LIB.S9S_MB_2U(SCH_1):GND
  171  GND            VSS73  @S9S_MB_2U_LIB.S9S_MB_2U(SCH_1):GND
  169  GND            VSS72  @S9S_MB_2U_LIB.S9S_MB_2U(SCH_1):GND
  166  GND            VSS71  @S9S_MB_2U_LIB.S9S_MB_2U(SCH_1):GND
  164  GND            VSS70  @S9S_MB_2U_LIB.S9S_MB_2U(SCH_1):GND
  162  GND            VSS69  @S9S_MB_2U_LIB.S9S_MB_2U(SCH_1):GND
  160  GND            VSS68  @S9S_MB_2U_LIB.S9S_MB_2U(SCH_1):GND
  158  GND            VSS67  @S9S_MB_2U_LIB.S9S_MB_2U(SCH_1):GND
  155  GND            VSS66  @S9S_MB_2U_LIB.S9S_MB_2U(SCH_1):GND
  153  GND            VSS65  @S9S_MB_2U_LIB.S9S_MB_2U(SCH_1):GND
  151  GND            VSS64  @S9S_MB_2U_LIB.S9S_MB_2U(SCH_1):GND
  143  GND            VSS63  @S9S_MB_2U_LIB.S9S_MB_2U(SCH_1):GND
  141  GND            VSS62  @S9S_MB_2U_LIB.S9S_MB_2U(SCH_1):GND
  139  GND            VSS61  @S9S_MB_2U_LIB.S9S_MB_2U(SCH_1):GND
  136  GND            VSS60  @S9S_MB_2U_LIB.S9S_MB_2U(SCH_1):GND
  134  GND            VSS59  @S9S_MB_2U_LIB.S9S_MB_2U(SCH_1):GND
  132  GND            VSS58  @S9S_MB_2U_LIB.S9S_MB_2U(SCH_1):GND
  130  GND            VSS57  @S9S_MB_2U_LIB.S9S_MB_2U(SCH_1):GND
  128  GND            VSS56  @S9S_MB_2U_LIB.S9S_MB_2U(SCH_1):GND
  125  GND            VSS55  @S9S_MB_2U_LIB.S9S_MB_2U(SCH_1):GND
  123  GND            VSS54  @S9S_MB_2U_LIB.S9S_MB_2U(SCH_1):GND
  121  GND            VSS53  @S9S_MB_2U_LIB.S9S_MB_2U(SCH_1):GND
  119  GND            VSS52  @S9S_MB_2U_LIB.S9S_MB_2U(SCH_1):GND
  117  GND            VSS51  @S9S_MB_2U_LIB.S9S_MB_2U(SCH_1):GND
  114  GND            VSS50  @S9S_MB_2U_LIB.S9S_MB_2U(SCH_1):GND
  112  GND            VSS49  @S9S_MB_2U_LIB.S9S_MB_2U(SCH_1):GND
  110  GND            VSS48  @S9S_MB_2U_LIB.S9S_MB_2U(SCH_1):GND
  108  GND            VSS47  @S9S_MB_2U_LIB.S9S_MB_2U(SCH_1):GND
  106  GND            VSS46  @S9S_MB_2U_LIB.S9S_MB_2U(SCH_1):GND
  103  GND            VSS45  @S9S_MB_2U_LIB.S9S_MB_2U(SCH_1):GND
  101  GND            VSS44  @S9S_MB_2U_LIB.S9S_MB_2U(SCH_1):GND
   99  GND            VSS43  @S9S_MB_2U_LIB.S9S_MB_2U(SCH_1):GND
   97  GND            VSS42  @S9S_MB_2U_LIB.S9S_MB_2U(SCH_1):GND
   95  GND            VSS41  @S9S_MB_2U_LIB.S9S_MB_2U(SCH_1):GND
   92  GND            VSS40  @S9S_MB_2U_LIB.S9S_MB_2U(SCH_1):GND
   90  GND            VSS39  @S9S_MB_2U_LIB.S9S_MB_2U(SCH_1):GND
   88  GND            VSS38  @S9S_MB_2U_LIB.S9S_MB_2U(SCH_1):GND
   85  GND            VSS37  @S9S_MB_2U_LIB.S9S_MB_2U(SCH_1):GND
   83  GND            VSS36  @S9S_MB_2U_LIB.S9S_MB_2U(SCH_1):GND
   81  GND            VSS35  @S9S_MB_2U_LIB.S9S_MB_2U(SCH_1):GND
   79  GND            VSS34  @S9S_MB_2U_LIB.S9S_MB_2U(SCH_1):GND
   77  GND            VSS33  @S9S_MB_2U_LIB.S9S_MB_2U(SCH_1):GND
   75  GND            VSS32  @S9S_MB_2U_LIB.S9S_MB_2U(SCH_1):GND
   73  GND            VSS31  @S9S_MB_2U_LIB.S9S_MB_2U(SCH_1):GND
   71  GND            VSS30  @S9S_MB_2U_LIB.S9S_MB_2U(SCH_1):GND
   69  GND            VSS29  @S9S_MB_2U_LIB.S9S_MB_2U(SCH_1):GND
   67  GND            VSS28  @S9S_MB_2U_LIB.S9S_MB_2U(SCH_1):GND
   65  GND            VSS27  @S9S_MB_2U_LIB.S9S_MB_2U(SCH_1):GND
   63  GND            VSS26  @S9S_MB_2U_LIB.S9S_MB_2U(SCH_1):GND
   61  GND            VSS25  @S9S_MB_2U_LIB.S9S_MB_2U(SCH_1):GND
   59  GND            VSS24  @S9S_MB_2U_LIB.S9S_MB_2U(SCH_1):GND
   57  GND            VSS23  @S9S_MB_2U_LIB.S9S_MB_2U(SCH_1):GND
   54  GND            VSS22  @S9S_MB_2U_LIB.S9S_MB_2U(SCH_1):GND
   52  GND            VSS21  @S9S_MB_2U_LIB.S9S_MB_2U(SCH_1):GND
   50  GND            VSS20  @S9S_MB_2U_LIB.S9S_MB_2U(SCH_1):GND
   48  GND            VSS19  @S9S_MB_2U_LIB.S9S_MB_2U(SCH_1):GND
   46  GND            VSS18  @S9S_MB_2U_LIB.S9S_MB_2U(SCH_1):GND
   43  GND            VSS17  @S9S_MB_2U_LIB.S9S_MB_2U(SCH_1):GND
   41  GND            VSS16  @S9S_MB_2U_LIB.S9S_MB_2U(SCH_1):GND
   39  GND            VSS15  @S9S_MB_2U_LIB.S9S_MB_2U(SCH_1):GND
   37  GND            VSS14  @S9S_MB_2U_LIB.S9S_MB_2U(SCH_1):GND
   35  GND            VSS13  @S9S_MB_2U_LIB.S9S_MB_2U(SCH_1):GND
   32  GND            VSS12  @S9S_MB_2U_LIB.S9S_MB_2U(SCH_1):GND
   30  GND            VSS11  @S9S_MB_2U_LIB.S9S_MB_2U(SCH_1):GND
   28  GND            VSS10  @S9S_MB_2U_LIB.S9S_MB_2U(SCH_1):GND
   26  GND             VSS9  @S9S_MB_2U_LIB.S9S_MB_2U(SCH_1):GND
   24  GND             VSS8  @S9S_MB_2U_LIB.S9S_MB_2U(SCH_1):GND
   21  GND             VSS7  @S9S_MB_2U_LIB.S9S_MB_2U(SCH_1):GND
   19  GND             VSS6  @S9S_MB_2U_LIB.S9S_MB_2U(SCH_1):GND
   17  GND             VSS5  @S9S_MB_2U_LIB.S9S_MB_2U(SCH_1):GND
   15  GND             VSS4  @S9S_MB_2U_LIB.S9S_MB_2U(SCH_1):GND
   13  GND             VSS3  @S9S_MB_2U_LIB.S9S_MB_2U(SCH_1):GND
   10  GND             VSS2  @S9S_MB_2U_LIB.S9S_MB_2U(SCH_1):GND
    8  GND             VSS1  @S9S_MB_2U_LIB.S9S_MB_2U(SCH_1):GND
    6  GND             VSS0  @S9S_MB_2U_LIB.S9S_MB_2U(SCH_1):GND
   G3  GND               G3  @S9S_MB_2U_LIB.S9S_MB_2U(SCH_1):GND
   G2  GND               G2  @S9S_MB_2U_LIB.S9S_MB_2U(SCH_1):GND
   G1  GND               G1  @S9S_MB_2U_LIB.S9S_MB_2U(SCH_1):GND

SCONN288_ADR50001P003C01  I125  J22    [SCONN288_ADR50001P003C01-SCONNA]
   93  M_C_CPU1_SB_DQS_DP<9>  DQS9_B_P  @S9S_MB_2U_LIB.S9S_MB_2U(SCH_1):M_C_CPU1_SB_DQS_DP<9>
  283  M_C_CPU1_SB_DQS_DP<8>  DQS8_B_P  @S9S_MB_2U_LIB.S9S_MB_2U(SCH_1):M_C_CPU1_SB_DQS_DP<8>
  272  M_C_CPU1_SB_DQS_DP<7>  DQS7_B_P  @S9S_MB_2U_LIB.S9S_MB_2U(SCH_1):M_C_CPU1_SB_DQS_DP<7>
  261  M_C_CPU1_SB_DQS_DP<6>  DQS6_B_P  @S9S_MB_2U_LIB.S9S_MB_2U(SCH_1):M_C_CPU1_SB_DQS_DP<6>
  250  M_C_CPU1_SB_DQS_DP<5>  DQS5_B_P  @S9S_MB_2U_LIB.S9S_MB_2U(SCH_1):M_C_CPU1_SB_DQS_DP<5>
  239  M_C_CPU1_SB_DQS_DP<4>  DQS4_B_P  @S9S_MB_2U_LIB.S9S_MB_2U(SCH_1):M_C_CPU1_SB_DQS_DP<4>
  137  M_C_CPU1_SB_DQS_DP<3>  DQS3_B_P  @S9S_MB_2U_LIB.S9S_MB_2U(SCH_1):M_C_CPU1_SB_DQS_DP<3>
  126  M_C_CPU1_SB_DQS_DP<2>  DQS2_B_P  @S9S_MB_2U_LIB.S9S_MB_2U(SCH_1):M_C_CPU1_SB_DQS_DP<2>
  115  M_C_CPU1_SB_DQS_DP<1>  DQS1_B_P  @S9S_MB_2U_LIB.S9S_MB_2U(SCH_1):M_C_CPU1_SB_DQS_DP<1>
  104  M_C_CPU1_SB_DQS_DP<0>  DQS0_B_P  @S9S_MB_2U_LIB.S9S_MB_2U(SCH_1):M_C_CPU1_SB_DQS_DP<0>
   94  M_C_CPU1_SB_DQS_DN<9>  DQS9_B_N  @S9S_MB_2U_LIB.S9S_MB_2U(SCH_1):M_C_CPU1_SB_DQS_DN<9>
  282  M_C_CPU1_SB_DQS_DN<8>  DQS8_B_N  @S9S_MB_2U_LIB.S9S_MB_2U(SCH_1):M_C_CPU1_SB_DQS_DN<8>
  271  M_C_CPU1_SB_DQS_DN<7>  DQS7_B_N  @S9S_MB_2U_LIB.S9S_MB_2U(SCH_1):M_C_CPU1_SB_DQS_DN<7>
  260  M_C_CPU1_SB_DQS_DN<6>  DQS6_B_N  @S9S_MB_2U_LIB.S9S_MB_2U(SCH_1):M_C_CPU1_SB_DQS_DN<6>
  249  M_C_CPU1_SB_DQS_DN<5>  DQS5_B_N  @S9S_MB_2U_LIB.S9S_MB_2U(SCH_1):M_C_CPU1_SB_DQS_DN<5>
  238  M_C_CPU1_SB_DQS_DN<4>  DQS4_B_N  @S9S_MB_2U_LIB.S9S_MB_2U(SCH_1):M_C_CPU1_SB_DQS_DN<4>
  138  M_C_CPU1_SB_DQS_DN<3>  DQS3_B_N  @S9S_MB_2U_LIB.S9S_MB_2U(SCH_1):M_C_CPU1_SB_DQS_DN<3>
  127  M_C_CPU1_SB_DQS_DN<2>  DQS2_B_N  @S9S_MB_2U_LIB.S9S_MB_2U(SCH_1):M_C_CPU1_SB_DQS_DN<2>
  116  M_C_CPU1_SB_DQS_DN<1>  DQS1_B_N  @S9S_MB_2U_LIB.S9S_MB_2U(SCH_1):M_C_CPU1_SB_DQS_DN<1>
  105  M_C_CPU1_SB_DQS_DN<0>  DQS0_B_N  @S9S_MB_2U_LIB.S9S_MB_2U(SCH_1):M_C_CPU1_SB_DQS_DN<0>
  201  M_C_CPU1_SA_DQS_DP<9>  DQS9_A_P  @S9S_MB_2U_LIB.S9S_MB_2U(SCH_1):M_C_CPU1_SA_DQS_DP<9>
  190  M_C_CPU1_SA_DQS_DP<8>  DQS8_A_P  @S9S_MB_2U_LIB.S9S_MB_2U(SCH_1):M_C_CPU1_SA_DQS_DP<8>
  179  M_C_CPU1_SA_DQS_DP<7>  DQS7_A_P  @S9S_MB_2U_LIB.S9S_MB_2U(SCH_1):M_C_CPU1_SA_DQS_DP<7>
  168  M_C_CPU1_SA_DQS_DP<6>  DQS6_A_P  @S9S_MB_2U_LIB.S9S_MB_2U(SCH_1):M_C_CPU1_SA_DQS_DP<6>
  157  M_C_CPU1_SA_DQS_DP<5>  DQS5_A_P  @S9S_MB_2U_LIB.S9S_MB_2U(SCH_1):M_C_CPU1_SA_DQS_DP<5>
   55  M_C_CPU1_SA_DQS_DP<4>  DQS4_A_P  @S9S_MB_2U_LIB.S9S_MB_2U(SCH_1):M_C_CPU1_SA_DQS_DP<4>
   44  M_C_CPU1_SA_DQS_DP<3>  DQS3_A_P  @S9S_MB_2U_LIB.S9S_MB_2U(SCH_1):M_C_CPU1_SA_DQS_DP<3>
   33  M_C_CPU1_SA_DQS_DP<2>  DQS2_A_P  @S9S_MB_2U_LIB.S9S_MB_2U(SCH_1):M_C_CPU1_SA_DQS_DP<2>
   22  M_C_CPU1_SA_DQS_DP<1>  DQS1_A_P  @S9S_MB_2U_LIB.S9S_MB_2U(SCH_1):M_C_CPU1_SA_DQS_DP<1>
   11  M_C_CPU1_SA_DQS_DP<0>  DQS0_A_P  @S9S_MB_2U_LIB.S9S_MB_2U(SCH_1):M_C_CPU1_SA_DQS_DP<0>
  200  M_C_CPU1_SA_DQS_DN<9>  DQS9_A_N  @S9S_MB_2U_LIB.S9S_MB_2U(SCH_1):M_C_CPU1_SA_DQS_DN<9>
  189  M_C_CPU1_SA_DQS_DN<8>  DQS8_A_N  @S9S_MB_2U_LIB.S9S_MB_2U(SCH_1):M_C_CPU1_SA_DQS_DN<8>
  178  M_C_CPU1_SA_DQS_DN<7>  DQS7_A_N  @S9S_MB_2U_LIB.S9S_MB_2U(SCH_1):M_C_CPU1_SA_DQS_DN<7>
  167  M_C_CPU1_SA_DQS_DN<6>  DQS6_A_N  @S9S_MB_2U_LIB.S9S_MB_2U(SCH_1):M_C_CPU1_SA_DQS_DN<6>
  156  M_C_CPU1_SA_DQS_DN<5>  DQS5_A_N  @S9S_MB_2U_LIB.S9S_MB_2U(SCH_1):M_C_CPU1_SA_DQS_DN<5>
   56  M_C_CPU1_SA_DQS_DN<4>  DQS4_A_N  @S9S_MB_2U_LIB.S9S_MB_2U(SCH_1):M_C_CPU1_SA_DQS_DN<4>
   45  M_C_CPU1_SA_DQS_DN<3>  DQS3_A_N  @S9S_MB_2U_LIB.S9S_MB_2U(SCH_1):M_C_CPU1_SA_DQS_DN<3>
   34  M_C_CPU1_SA_DQS_DN<2>  DQS2_A_N  @S9S_MB_2U_LIB.S9S_MB_2U(SCH_1):M_C_CPU1_SA_DQS_DN<2>
   23  M_C_CPU1_SA_DQS_DN<1>  DQS1_A_N  @S9S_MB_2U_LIB.S9S_MB_2U(SCH_1):M_C_CPU1_SA_DQS_DN<1>
   12  M_C_CPU1_SA_DQS_DN<0>  DQS0_A_N  @S9S_MB_2U_LIB.S9S_MB_2U(SCH_1):M_C_CPU1_SA_DQS_DN<0>

SCONN288_ADR50001P003C01  I51  J22    [SCONN288_ADR50001P003C01-SCONNA]
  232  NC              RFU6  NC
  231  NC              RFU5  NC
  220  NC              RFU4  NC
  150  NC              RFU3  NC
  149  NC              RFU2  NC
  144  NC              RFU1  NC
    2  NC              RFU0  NC
  207  RST_M_CD_CPU1_FPGA_N  RESET_N  @S9S_MB_2U_LIB.S9S_MB_2U(SCH_1):RST_M_CD_CPU1_FPGA_N
  147  PWRGD_CHC_CPU1_DIMM2  PWR_GOOD||FAIL_N  @S9S_MB_2U_LIB.S9S_MB_2U(SCH_1):PWRGD_CHC_CPU1_DIMM2
  148  PD_CHC_CPU1_DIMM2_SAA    HAS  @S9S_MB_2U_LIB.S9S_MB_2U(SCH_1):PD_CHC_CPU1_DIMM2_SAA
    3  P3V3_AUX       VIN_MGMT  @S9S_MB_2U_LIB.S9S_MB_2U(SCH_1):P3V3_AUX
   87  M_C_CPU1_SB_RSP<1>  LBS||RSP_N_B  @S9S_MB_2U_LIB.S9S_MB_2U(SCH_1):M_C_CPU1_SB_RSP<1>
  227  M_C_CPU1_SB_PAR  PAR_B  @S9S_MB_2U_LIB.S9S_MB_2U(SCH_1):M_C_CPU1_SB_PAR
  113  M_C_CPU1_SB_DQ<9>  DQ_B9  @S9S_MB_2U_LIB.S9S_MB_2U(SCH_1):M_C_CPU1_SB_DQ<9>
  111  M_C_CPU1_SB_DQ<8>  DQ_B8  @S9S_MB_2U_LIB.S9S_MB_2U(SCH_1):M_C_CPU1_SB_DQ<8>
  254  M_C_CPU1_SB_DQ<7>  DQ_B7  @S9S_MB_2U_LIB.S9S_MB_2U(SCH_1):M_C_CPU1_SB_DQ<7>
  252  M_C_CPU1_SB_DQ<6>  DQ_B6  @S9S_MB_2U_LIB.S9S_MB_2U(SCH_1):M_C_CPU1_SB_DQ<6>
  109  M_C_CPU1_SB_DQ<5>  DQ_B5  @S9S_MB_2U_LIB.S9S_MB_2U(SCH_1):M_C_CPU1_SB_DQ<5>
  107  M_C_CPU1_SB_DQ<4>  DQ_B4  @S9S_MB_2U_LIB.S9S_MB_2U(SCH_1):M_C_CPU1_SB_DQ<4>
  247  M_C_CPU1_SB_DQ<3>  DQ_B3  @S9S_MB_2U_LIB.S9S_MB_2U(SCH_1):M_C_CPU1_SB_DQ<3>
  287  M_C_CPU1_SB_DQ<31>  DQ_B31  @S9S_MB_2U_LIB.S9S_MB_2U(SCH_1):M_C_CPU1_SB_DQ<31>
  285  M_C_CPU1_SB_DQ<30>  DQ_B30  @S9S_MB_2U_LIB.S9S_MB_2U(SCH_1):M_C_CPU1_SB_DQ<30>
  245  M_C_CPU1_SB_DQ<2>  DQ_B2  @S9S_MB_2U_LIB.S9S_MB_2U(SCH_1):M_C_CPU1_SB_DQ<2>
  142  M_C_CPU1_SB_DQ<29>  DQ_B29  @S9S_MB_2U_LIB.S9S_MB_2U(SCH_1):M_C_CPU1_SB_DQ<29>
  140  M_C_CPU1_SB_DQ<28>  DQ_B28  @S9S_MB_2U_LIB.S9S_MB_2U(SCH_1):M_C_CPU1_SB_DQ<28>
  280  M_C_CPU1_SB_DQ<27>  DQ_B27  @S9S_MB_2U_LIB.S9S_MB_2U(SCH_1):M_C_CPU1_SB_DQ<27>
  278  M_C_CPU1_SB_DQ<26>  DQ_B26  @S9S_MB_2U_LIB.S9S_MB_2U(SCH_1):M_C_CPU1_SB_DQ<26>
  135  M_C_CPU1_SB_DQ<25>  DQ_B25  @S9S_MB_2U_LIB.S9S_MB_2U(SCH_1):M_C_CPU1_SB_DQ<25>
  133  M_C_CPU1_SB_DQ<24>  DQ_B24  @S9S_MB_2U_LIB.S9S_MB_2U(SCH_1):M_C_CPU1_SB_DQ<24>
  276  M_C_CPU1_SB_DQ<23>  DQ_B23  @S9S_MB_2U_LIB.S9S_MB_2U(SCH_1):M_C_CPU1_SB_DQ<23>
  274  M_C_CPU1_SB_DQ<22>  DQ_B22  @S9S_MB_2U_LIB.S9S_MB_2U(SCH_1):M_C_CPU1_SB_DQ<22>
  131  M_C_CPU1_SB_DQ<21>  DQ_B21  @S9S_MB_2U_LIB.S9S_MB_2U(SCH_1):M_C_CPU1_SB_DQ<21>
  129  M_C_CPU1_SB_DQ<20>  DQ_B20  @S9S_MB_2U_LIB.S9S_MB_2U(SCH_1):M_C_CPU1_SB_DQ<20>
  102  M_C_CPU1_SB_DQ<1>  DQ_B1  @S9S_MB_2U_LIB.S9S_MB_2U(SCH_1):M_C_CPU1_SB_DQ<1>
  269  M_C_CPU1_SB_DQ<19>  DQ_B19  @S9S_MB_2U_LIB.S9S_MB_2U(SCH_1):M_C_CPU1_SB_DQ<19>
  267  M_C_CPU1_SB_DQ<18>  DQ_B18  @S9S_MB_2U_LIB.S9S_MB_2U(SCH_1):M_C_CPU1_SB_DQ<18>
  124  M_C_CPU1_SB_DQ<17>  DQ_B17  @S9S_MB_2U_LIB.S9S_MB_2U(SCH_1):M_C_CPU1_SB_DQ<17>
  122  M_C_CPU1_SB_DQ<16>  DQ_B16  @S9S_MB_2U_LIB.S9S_MB_2U(SCH_1):M_C_CPU1_SB_DQ<16>
  265  M_C_CPU1_SB_DQ<15>  DQ_B15  @S9S_MB_2U_LIB.S9S_MB_2U(SCH_1):M_C_CPU1_SB_DQ<15>
  263  M_C_CPU1_SB_DQ<14>  DQ_B14  @S9S_MB_2U_LIB.S9S_MB_2U(SCH_1):M_C_CPU1_SB_DQ<14>
  120  M_C_CPU1_SB_DQ<13>  DQ_B13  @S9S_MB_2U_LIB.S9S_MB_2U(SCH_1):M_C_CPU1_SB_DQ<13>
  118  M_C_CPU1_SB_DQ<12>  DQ_B12  @S9S_MB_2U_LIB.S9S_MB_2U(SCH_1):M_C_CPU1_SB_DQ<12>
  258  M_C_CPU1_SB_DQ<11>  DQ_B11  @S9S_MB_2U_LIB.S9S_MB_2U(SCH_1):M_C_CPU1_SB_DQ<11>
  256  M_C_CPU1_SB_DQ<10>  DQ_B10  @S9S_MB_2U_LIB.S9S_MB_2U(SCH_1):M_C_CPU1_SB_DQ<10>
  100  M_C_CPU1_SB_DQ<0>  DQ_B0  @S9S_MB_2U_LIB.S9S_MB_2U(SCH_1):M_C_CPU1_SB_DQ<0>
  229  M_C_CPU1_SB_CS_N<3>  CS1_N_B  @S9S_MB_2U_LIB.S9S_MB_2U(SCH_1):M_C_CPU1_SB_CS_N<3>
   84  M_C_CPU1_SB_CS_N<2>  CS0_N_B  @S9S_MB_2U_LIB.S9S_MB_2U(SCH_1):M_C_CPU1_SB_CS_N<2>
  236  M_C_CPU1_SB_CB<7>  CB_B7  @S9S_MB_2U_LIB.S9S_MB_2U(SCH_1):M_C_CPU1_SB_CB<7>
  234  M_C_CPU1_SB_CB<6>  CB_B6  @S9S_MB_2U_LIB.S9S_MB_2U(SCH_1):M_C_CPU1_SB_CB<6>
   91  M_C_CPU1_SB_CB<5>  CB_B5  @S9S_MB_2U_LIB.S9S_MB_2U(SCH_1):M_C_CPU1_SB_CB<5>
   89  M_C_CPU1_SB_CB<4>  CB_B4  @S9S_MB_2U_LIB.S9S_MB_2U(SCH_1):M_C_CPU1_SB_CB<4>
  243  M_C_CPU1_SB_CB<3>  CB_B3  @S9S_MB_2U_LIB.S9S_MB_2U(SCH_1):M_C_CPU1_SB_CB<3>
  241  M_C_CPU1_SB_CB<2>  CB_B2  @S9S_MB_2U_LIB.S9S_MB_2U(SCH_1):M_C_CPU1_SB_CB<2>
   98  M_C_CPU1_SB_CB<1>  CB_B1  @S9S_MB_2U_LIB.S9S_MB_2U(SCH_1):M_C_CPU1_SB_CB<1>
   96  M_C_CPU1_SB_CB<0>  CB_B0  @S9S_MB_2U_LIB.S9S_MB_2U(SCH_1):M_C_CPU1_SB_CB<0>
   82  M_C_CPU1_SB_CA<6>  CA6_B  @S9S_MB_2U_LIB.S9S_MB_2U(SCH_1):M_C_CPU1_SB_CA<6>
  225  M_C_CPU1_SB_CA<5>  CA5_B  @S9S_MB_2U_LIB.S9S_MB_2U(SCH_1):M_C_CPU1_SB_CA<5>
   80  M_C_CPU1_SB_CA<4>  CA4_B  @S9S_MB_2U_LIB.S9S_MB_2U(SCH_1):M_C_CPU1_SB_CA<4>
  223  M_C_CPU1_SB_CA<3>  CA3_B  @S9S_MB_2U_LIB.S9S_MB_2U(SCH_1):M_C_CPU1_SB_CA<3>
   78  M_C_CPU1_SB_CA<2>  CA2_B  @S9S_MB_2U_LIB.S9S_MB_2U(SCH_1):M_C_CPU1_SB_CA<2>
  221  M_C_CPU1_SB_CA<1>  CA1_B  @S9S_MB_2U_LIB.S9S_MB_2U(SCH_1):M_C_CPU1_SB_CA<1>
   76  M_C_CPU1_SB_CA<0>  CA0_B  @S9S_MB_2U_LIB.S9S_MB_2U(SCH_1):M_C_CPU1_SB_CA<0>
   86  M_C_CPU1_SA_RSP<1>  LBD||RSP_N_A  @S9S_MB_2U_LIB.S9S_MB_2U(SCH_1):M_C_CPU1_SA_RSP<1>
   74  M_C_CPU1_SA_PAR  PAR_A  @S9S_MB_2U_LIB.S9S_MB_2U(SCH_1):M_C_CPU1_SA_PAR
   20  M_C_CPU1_SA_DQ<9>  DQ_A9  @S9S_MB_2U_LIB.S9S_MB_2U(SCH_1):M_C_CPU1_SA_DQ<9>
   18  M_C_CPU1_SA_DQ<8>  DQ_A8  @S9S_MB_2U_LIB.S9S_MB_2U(SCH_1):M_C_CPU1_SA_DQ<8>
  161  M_C_CPU1_SA_DQ<7>  DQ_A7  @S9S_MB_2U_LIB.S9S_MB_2U(SCH_1):M_C_CPU1_SA_DQ<7>
  159  M_C_CPU1_SA_DQ<6>  DQ_A6  @S9S_MB_2U_LIB.S9S_MB_2U(SCH_1):M_C_CPU1_SA_DQ<6>
   16  M_C_CPU1_SA_DQ<5>  DQ_A5  @S9S_MB_2U_LIB.S9S_MB_2U(SCH_1):M_C_CPU1_SA_DQ<5>
   14  M_C_CPU1_SA_DQ<4>  DQ_A4  @S9S_MB_2U_LIB.S9S_MB_2U(SCH_1):M_C_CPU1_SA_DQ<4>
  154  M_C_CPU1_SA_DQ<3>  DQ_A3  @S9S_MB_2U_LIB.S9S_MB_2U(SCH_1):M_C_CPU1_SA_DQ<3>
  194  M_C_CPU1_SA_DQ<31>  DQ_A31  @S9S_MB_2U_LIB.S9S_MB_2U(SCH_1):M_C_CPU1_SA_DQ<31>
  192  M_C_CPU1_SA_DQ<30>  DQ_A30  @S9S_MB_2U_LIB.S9S_MB_2U(SCH_1):M_C_CPU1_SA_DQ<30>
  152  M_C_CPU1_SA_DQ<2>  DQ_A2  @S9S_MB_2U_LIB.S9S_MB_2U(SCH_1):M_C_CPU1_SA_DQ<2>
   49  M_C_CPU1_SA_DQ<29>  DQ_A29  @S9S_MB_2U_LIB.S9S_MB_2U(SCH_1):M_C_CPU1_SA_DQ<29>
   47  M_C_CPU1_SA_DQ<28>  DQ_A28  @S9S_MB_2U_LIB.S9S_MB_2U(SCH_1):M_C_CPU1_SA_DQ<28>
  187  M_C_CPU1_SA_DQ<27>  DQ_A27  @S9S_MB_2U_LIB.S9S_MB_2U(SCH_1):M_C_CPU1_SA_DQ<27>
  185  M_C_CPU1_SA_DQ<26>  DQ_A26  @S9S_MB_2U_LIB.S9S_MB_2U(SCH_1):M_C_CPU1_SA_DQ<26>
   42  M_C_CPU1_SA_DQ<25>  DQ_A25  @S9S_MB_2U_LIB.S9S_MB_2U(SCH_1):M_C_CPU1_SA_DQ<25>
   40  M_C_CPU1_SA_DQ<24>  DQ_A24  @S9S_MB_2U_LIB.S9S_MB_2U(SCH_1):M_C_CPU1_SA_DQ<24>
  183  M_C_CPU1_SA_DQ<23>  DQ_A23  @S9S_MB_2U_LIB.S9S_MB_2U(SCH_1):M_C_CPU1_SA_DQ<23>
  181  M_C_CPU1_SA_DQ<22>  DQ_A22  @S9S_MB_2U_LIB.S9S_MB_2U(SCH_1):M_C_CPU1_SA_DQ<22>
   38  M_C_CPU1_SA_DQ<21>  DQ_A21  @S9S_MB_2U_LIB.S9S_MB_2U(SCH_1):M_C_CPU1_SA_DQ<21>
   36  M_C_CPU1_SA_DQ<20>  DQ_A20  @S9S_MB_2U_LIB.S9S_MB_2U(SCH_1):M_C_CPU1_SA_DQ<20>
    9  M_C_CPU1_SA_DQ<1>  DQ_A1  @S9S_MB_2U_LIB.S9S_MB_2U(SCH_1):M_C_CPU1_SA_DQ<1>
  176  M_C_CPU1_SA_DQ<19>  DQ_A19  @S9S_MB_2U_LIB.S9S_MB_2U(SCH_1):M_C_CPU1_SA_DQ<19>
  174  M_C_CPU1_SA_DQ<18>  DQ_A18  @S9S_MB_2U_LIB.S9S_MB_2U(SCH_1):M_C_CPU1_SA_DQ<18>
   31  M_C_CPU1_SA_DQ<17>  DQ_A17  @S9S_MB_2U_LIB.S9S_MB_2U(SCH_1):M_C_CPU1_SA_DQ<17>
   29  M_C_CPU1_SA_DQ<16>  DQ_A16  @S9S_MB_2U_LIB.S9S_MB_2U(SCH_1):M_C_CPU1_SA_DQ<16>
  172  M_C_CPU1_SA_DQ<15>  DQ_A15  @S9S_MB_2U_LIB.S9S_MB_2U(SCH_1):M_C_CPU1_SA_DQ<15>
  170  M_C_CPU1_SA_DQ<14>  DQ_A14  @S9S_MB_2U_LIB.S9S_MB_2U(SCH_1):M_C_CPU1_SA_DQ<14>
   27  M_C_CPU1_SA_DQ<13>  DQ_A13  @S9S_MB_2U_LIB.S9S_MB_2U(SCH_1):M_C_CPU1_SA_DQ<13>
   25  M_C_CPU1_SA_DQ<12>  DQ_A12  @S9S_MB_2U_LIB.S9S_MB_2U(SCH_1):M_C_CPU1_SA_DQ<12>
  165  M_C_CPU1_SA_DQ<11>  DQ_A11  @S9S_MB_2U_LIB.S9S_MB_2U(SCH_1):M_C_CPU1_SA_DQ<11>
  163  M_C_CPU1_SA_DQ<10>  DQ_A10  @S9S_MB_2U_LIB.S9S_MB_2U(SCH_1):M_C_CPU1_SA_DQ<10>
    7  M_C_CPU1_SA_DQ<0>  DQ_A0  @S9S_MB_2U_LIB.S9S_MB_2U(SCH_1):M_C_CPU1_SA_DQ<0>
  209  M_C_CPU1_SA_CS_N<3>  CS1_N_A  @S9S_MB_2U_LIB.S9S_MB_2U(SCH_1):M_C_CPU1_SA_CS_N<3>
   64  M_C_CPU1_SA_CS_N<2>  CS0_N_A  @S9S_MB_2U_LIB.S9S_MB_2U(SCH_1):M_C_CPU1_SA_CS_N<2>
  205  M_C_CPU1_SA_CB<7>  CB_A7  @S9S_MB_2U_LIB.S9S_MB_2U(SCH_1):M_C_CPU1_SA_CB<7>
  203  M_C_CPU1_SA_CB<6>  CB_A6  @S9S_MB_2U_LIB.S9S_MB_2U(SCH_1):M_C_CPU1_SA_CB<6>
   60  M_C_CPU1_SA_CB<5>  CB_A5  @S9S_MB_2U_LIB.S9S_MB_2U(SCH_1):M_C_CPU1_SA_CB<5>
   58  M_C_CPU1_SA_CB<4>  CB_A4  @S9S_MB_2U_LIB.S9S_MB_2U(SCH_1):M_C_CPU1_SA_CB<4>
  198  M_C_CPU1_SA_CB<3>  CB_A3  @S9S_MB_2U_LIB.S9S_MB_2U(SCH_1):M_C_CPU1_SA_CB<3>
  196  M_C_CPU1_SA_CB<2>  CB_A2  @S9S_MB_2U_LIB.S9S_MB_2U(SCH_1):M_C_CPU1_SA_CB<2>
   53  M_C_CPU1_SA_CB<1>  CB_A1  @S9S_MB_2U_LIB.S9S_MB_2U(SCH_1):M_C_CPU1_SA_CB<1>
   51  M_C_CPU1_SA_CB<0>  CB_A0  @S9S_MB_2U_LIB.S9S_MB_2U(SCH_1):M_C_CPU1_SA_CB<0>
   72  M_C_CPU1_SA_CA<6>  CA6_A  @S9S_MB_2U_LIB.S9S_MB_2U(SCH_1):M_C_CPU1_SA_CA<6>
  215  M_C_CPU1_SA_CA<5>  CA5_A  @S9S_MB_2U_LIB.S9S_MB_2U(SCH_1):M_C_CPU1_SA_CA<5>
   70  M_C_CPU1_SA_CA<4>  CA4_A  @S9S_MB_2U_LIB.S9S_MB_2U(SCH_1):M_C_CPU1_SA_CA<4>
  213  M_C_CPU1_SA_CA<3>  CA3_A  @S9S_MB_2U_LIB.S9S_MB_2U(SCH_1):M_C_CPU1_SA_CA<3>
   68  M_C_CPU1_SA_CA<2>  CA2_A  @S9S_MB_2U_LIB.S9S_MB_2U(SCH_1):M_C_CPU1_SA_CA<2>
  211  M_C_CPU1_SA_CA<1>  CA1_A  @S9S_MB_2U_LIB.S9S_MB_2U(SCH_1):M_C_CPU1_SA_CA<1>
   66  M_C_CPU1_SA_CA<0>  CA0_A  @S9S_MB_2U_LIB.S9S_MB_2U(SCH_1):M_C_CPU1_SA_CA<0>
  217  M_C_CPU1_CLK_DP<1>   CK_P  @S9S_MB_2U_LIB.S9S_MB_2U(SCH_1):M_C_CPU1_CLK_DP<1>
  218  M_C_CPU1_CLK_DN<1>   CK_N  @S9S_MB_2U_LIB.S9S_MB_2U(SCH_1):M_C_CPU1_CLK_DN<1>
   62  M_C_CPU1_ALERT_N  ALERT_N  @S9S_MB_2U_LIB.S9S_MB_2U(SCH_1):M_C_CPU1_ALERT_N
    5  I3C_SPD_DDRABCD_CPU1_LVC1_SDA   HSDA  @S9S_MB_2U_LIB.S9S_MB_2U(SCH_1):I3C_SPD_DDRABCD_CPU1_LVC1_SDA
    4  I3C_SPD_DDRABCD_CPU1_LVC1_SCL   HSCL  @S9S_MB_2U_LIB.S9S_MB_2U(SCH_1):I3C_SPD_DDRABCD_CPU1_LVC1_SCL

SCONN288_ADR50001P013C01  I175  J23    [SCONN288_ADR50001P013C01-SCONNA]
  146  P12V_S3_AUX_CPU1_NVDIMM  VIN_BULK2  @S9S_MB_2U_LIB.S9S_MB_2U(SCH_1):P12V_S3_AUX_CPU1_NVDIMM
  145  P12V_S3_AUX_CPU1_NVDIMM  VIN_BULK1  @S9S_MB_2U_LIB.S9S_MB_2U(SCH_1):P12V_S3_AUX_CPU1_NVDIMM
    1  P12V_S3_AUX_CPU1_NVDIMM  VIN_BULK0  @S9S_MB_2U_LIB.S9S_MB_2U(SCH_1):P12V_S3_AUX_CPU1_NVDIMM
  288  GND            VSS126  @S9S_MB_2U_LIB.S9S_MB_2U(SCH_1):GND
  286  GND            VSS125  @S9S_MB_2U_LIB.S9S_MB_2U(SCH_1):GND
  284  GND            VSS124  @S9S_MB_2U_LIB.S9S_MB_2U(SCH_1):GND
  281  GND            VSS123  @S9S_MB_2U_LIB.S9S_MB_2U(SCH_1):GND
  279  GND            VSS122  @S9S_MB_2U_LIB.S9S_MB_2U(SCH_1):GND
  277  GND            VSS121  @S9S_MB_2U_LIB.S9S_MB_2U(SCH_1):GND
  275  GND            VSS120  @S9S_MB_2U_LIB.S9S_MB_2U(SCH_1):GND
  273  GND            VSS119  @S9S_MB_2U_LIB.S9S_MB_2U(SCH_1):GND
  270  GND            VSS118  @S9S_MB_2U_LIB.S9S_MB_2U(SCH_1):GND
  268  GND            VSS117  @S9S_MB_2U_LIB.S9S_MB_2U(SCH_1):GND
  266  GND            VSS116  @S9S_MB_2U_LIB.S9S_MB_2U(SCH_1):GND
  264  GND            VSS115  @S9S_MB_2U_LIB.S9S_MB_2U(SCH_1):GND
  262  GND            VSS114  @S9S_MB_2U_LIB.S9S_MB_2U(SCH_1):GND
  259  GND            VSS113  @S9S_MB_2U_LIB.S9S_MB_2U(SCH_1):GND
  257  GND            VSS112  @S9S_MB_2U_LIB.S9S_MB_2U(SCH_1):GND
  255  GND            VSS111  @S9S_MB_2U_LIB.S9S_MB_2U(SCH_1):GND
  253  GND            VSS110  @S9S_MB_2U_LIB.S9S_MB_2U(SCH_1):GND
  251  GND            VSS109  @S9S_MB_2U_LIB.S9S_MB_2U(SCH_1):GND
  248  GND            VSS108  @S9S_MB_2U_LIB.S9S_MB_2U(SCH_1):GND
  246  GND            VSS107  @S9S_MB_2U_LIB.S9S_MB_2U(SCH_1):GND
  244  GND            VSS106  @S9S_MB_2U_LIB.S9S_MB_2U(SCH_1):GND
  242  GND            VSS105  @S9S_MB_2U_LIB.S9S_MB_2U(SCH_1):GND
  240  GND            VSS104  @S9S_MB_2U_LIB.S9S_MB_2U(SCH_1):GND
  237  GND            VSS103  @S9S_MB_2U_LIB.S9S_MB_2U(SCH_1):GND
  235  GND            VSS102  @S9S_MB_2U_LIB.S9S_MB_2U(SCH_1):GND
  233  GND            VSS101  @S9S_MB_2U_LIB.S9S_MB_2U(SCH_1):GND
  230  GND            VSS100  @S9S_MB_2U_LIB.S9S_MB_2U(SCH_1):GND
  228  GND            VSS99  @S9S_MB_2U_LIB.S9S_MB_2U(SCH_1):GND
  226  GND            VSS98  @S9S_MB_2U_LIB.S9S_MB_2U(SCH_1):GND
  224  GND            VSS97  @S9S_MB_2U_LIB.S9S_MB_2U(SCH_1):GND
  222  GND            VSS96  @S9S_MB_2U_LIB.S9S_MB_2U(SCH_1):GND
  219  GND            VSS95  @S9S_MB_2U_LIB.S9S_MB_2U(SCH_1):GND
  216  GND            VSS94  @S9S_MB_2U_LIB.S9S_MB_2U(SCH_1):GND
  214  GND            VSS93  @S9S_MB_2U_LIB.S9S_MB_2U(SCH_1):GND
  212  GND            VSS92  @S9S_MB_2U_LIB.S9S_MB_2U(SCH_1):GND
  210  GND            VSS91  @S9S_MB_2U_LIB.S9S_MB_2U(SCH_1):GND
  208  GND            VSS90  @S9S_MB_2U_LIB.S9S_MB_2U(SCH_1):GND
  206  GND            VSS89  @S9S_MB_2U_LIB.S9S_MB_2U(SCH_1):GND
  204  GND            VSS88  @S9S_MB_2U_LIB.S9S_MB_2U(SCH_1):GND
  202  GND            VSS87  @S9S_MB_2U_LIB.S9S_MB_2U(SCH_1):GND
  199  GND            VSS86  @S9S_MB_2U_LIB.S9S_MB_2U(SCH_1):GND
  197  GND            VSS85  @S9S_MB_2U_LIB.S9S_MB_2U(SCH_1):GND
  195  GND            VSS84  @S9S_MB_2U_LIB.S9S_MB_2U(SCH_1):GND
  193  GND            VSS83  @S9S_MB_2U_LIB.S9S_MB_2U(SCH_1):GND
  191  GND            VSS82  @S9S_MB_2U_LIB.S9S_MB_2U(SCH_1):GND
  188  GND            VSS81  @S9S_MB_2U_LIB.S9S_MB_2U(SCH_1):GND
  186  GND            VSS80  @S9S_MB_2U_LIB.S9S_MB_2U(SCH_1):GND
  184  GND            VSS79  @S9S_MB_2U_LIB.S9S_MB_2U(SCH_1):GND
  182  GND            VSS78  @S9S_MB_2U_LIB.S9S_MB_2U(SCH_1):GND
  180  GND            VSS77  @S9S_MB_2U_LIB.S9S_MB_2U(SCH_1):GND
  177  GND            VSS76  @S9S_MB_2U_LIB.S9S_MB_2U(SCH_1):GND
  175  GND            VSS75  @S9S_MB_2U_LIB.S9S_MB_2U(SCH_1):GND
  173  GND            VSS74  @S9S_MB_2U_LIB.S9S_MB_2U(SCH_1):GND
  171  GND            VSS73  @S9S_MB_2U_LIB.S9S_MB_2U(SCH_1):GND
  169  GND            VSS72  @S9S_MB_2U_LIB.S9S_MB_2U(SCH_1):GND
  166  GND            VSS71  @S9S_MB_2U_LIB.S9S_MB_2U(SCH_1):GND
  164  GND            VSS70  @S9S_MB_2U_LIB.S9S_MB_2U(SCH_1):GND
  162  GND            VSS69  @S9S_MB_2U_LIB.S9S_MB_2U(SCH_1):GND
  160  GND            VSS68  @S9S_MB_2U_LIB.S9S_MB_2U(SCH_1):GND
  158  GND            VSS67  @S9S_MB_2U_LIB.S9S_MB_2U(SCH_1):GND
  155  GND            VSS66  @S9S_MB_2U_LIB.S9S_MB_2U(SCH_1):GND
  153  GND            VSS65  @S9S_MB_2U_LIB.S9S_MB_2U(SCH_1):GND
  151  GND            VSS64  @S9S_MB_2U_LIB.S9S_MB_2U(SCH_1):GND
  143  GND            VSS63  @S9S_MB_2U_LIB.S9S_MB_2U(SCH_1):GND
  141  GND            VSS62  @S9S_MB_2U_LIB.S9S_MB_2U(SCH_1):GND
  139  GND            VSS61  @S9S_MB_2U_LIB.S9S_MB_2U(SCH_1):GND
  136  GND            VSS60  @S9S_MB_2U_LIB.S9S_MB_2U(SCH_1):GND
  134  GND            VSS59  @S9S_MB_2U_LIB.S9S_MB_2U(SCH_1):GND
  132  GND            VSS58  @S9S_MB_2U_LIB.S9S_MB_2U(SCH_1):GND
  130  GND            VSS57  @S9S_MB_2U_LIB.S9S_MB_2U(SCH_1):GND
  128  GND            VSS56  @S9S_MB_2U_LIB.S9S_MB_2U(SCH_1):GND
  125  GND            VSS55  @S9S_MB_2U_LIB.S9S_MB_2U(SCH_1):GND
  123  GND            VSS54  @S9S_MB_2U_LIB.S9S_MB_2U(SCH_1):GND
  121  GND            VSS53  @S9S_MB_2U_LIB.S9S_MB_2U(SCH_1):GND
  119  GND            VSS52  @S9S_MB_2U_LIB.S9S_MB_2U(SCH_1):GND
  117  GND            VSS51  @S9S_MB_2U_LIB.S9S_MB_2U(SCH_1):GND
  114  GND            VSS50  @S9S_MB_2U_LIB.S9S_MB_2U(SCH_1):GND
  112  GND            VSS49  @S9S_MB_2U_LIB.S9S_MB_2U(SCH_1):GND
  110  GND            VSS48  @S9S_MB_2U_LIB.S9S_MB_2U(SCH_1):GND
  108  GND            VSS47  @S9S_MB_2U_LIB.S9S_MB_2U(SCH_1):GND
  106  GND            VSS46  @S9S_MB_2U_LIB.S9S_MB_2U(SCH_1):GND
  103  GND            VSS45  @S9S_MB_2U_LIB.S9S_MB_2U(SCH_1):GND
  101  GND            VSS44  @S9S_MB_2U_LIB.S9S_MB_2U(SCH_1):GND
   99  GND            VSS43  @S9S_MB_2U_LIB.S9S_MB_2U(SCH_1):GND
   97  GND            VSS42  @S9S_MB_2U_LIB.S9S_MB_2U(SCH_1):GND
   95  GND            VSS41  @S9S_MB_2U_LIB.S9S_MB_2U(SCH_1):GND
   92  GND            VSS40  @S9S_MB_2U_LIB.S9S_MB_2U(SCH_1):GND
   90  GND            VSS39  @S9S_MB_2U_LIB.S9S_MB_2U(SCH_1):GND
   88  GND            VSS38  @S9S_MB_2U_LIB.S9S_MB_2U(SCH_1):GND
   85  GND            VSS37  @S9S_MB_2U_LIB.S9S_MB_2U(SCH_1):GND
   83  GND            VSS36  @S9S_MB_2U_LIB.S9S_MB_2U(SCH_1):GND
   81  GND            VSS35  @S9S_MB_2U_LIB.S9S_MB_2U(SCH_1):GND
   79  GND            VSS34  @S9S_MB_2U_LIB.S9S_MB_2U(SCH_1):GND
   77  GND            VSS33  @S9S_MB_2U_LIB.S9S_MB_2U(SCH_1):GND
   75  GND            VSS32  @S9S_MB_2U_LIB.S9S_MB_2U(SCH_1):GND
   73  GND            VSS31  @S9S_MB_2U_LIB.S9S_MB_2U(SCH_1):GND
   71  GND            VSS30  @S9S_MB_2U_LIB.S9S_MB_2U(SCH_1):GND
   69  GND            VSS29  @S9S_MB_2U_LIB.S9S_MB_2U(SCH_1):GND
   67  GND            VSS28  @S9S_MB_2U_LIB.S9S_MB_2U(SCH_1):GND
   65  GND            VSS27  @S9S_MB_2U_LIB.S9S_MB_2U(SCH_1):GND
   63  GND            VSS26  @S9S_MB_2U_LIB.S9S_MB_2U(SCH_1):GND
   61  GND            VSS25  @S9S_MB_2U_LIB.S9S_MB_2U(SCH_1):GND
   59  GND            VSS24  @S9S_MB_2U_LIB.S9S_MB_2U(SCH_1):GND
   57  GND            VSS23  @S9S_MB_2U_LIB.S9S_MB_2U(SCH_1):GND
   54  GND            VSS22  @S9S_MB_2U_LIB.S9S_MB_2U(SCH_1):GND
   52  GND            VSS21  @S9S_MB_2U_LIB.S9S_MB_2U(SCH_1):GND
   50  GND            VSS20  @S9S_MB_2U_LIB.S9S_MB_2U(SCH_1):GND
   48  GND            VSS19  @S9S_MB_2U_LIB.S9S_MB_2U(SCH_1):GND
   46  GND            VSS18  @S9S_MB_2U_LIB.S9S_MB_2U(SCH_1):GND
   43  GND            VSS17  @S9S_MB_2U_LIB.S9S_MB_2U(SCH_1):GND
   41  GND            VSS16  @S9S_MB_2U_LIB.S9S_MB_2U(SCH_1):GND
   39  GND            VSS15  @S9S_MB_2U_LIB.S9S_MB_2U(SCH_1):GND
   37  GND            VSS14  @S9S_MB_2U_LIB.S9S_MB_2U(SCH_1):GND
   35  GND            VSS13  @S9S_MB_2U_LIB.S9S_MB_2U(SCH_1):GND
   32  GND            VSS12  @S9S_MB_2U_LIB.S9S_MB_2U(SCH_1):GND
   30  GND            VSS11  @S9S_MB_2U_LIB.S9S_MB_2U(SCH_1):GND
   28  GND            VSS10  @S9S_MB_2U_LIB.S9S_MB_2U(SCH_1):GND
   26  GND             VSS9  @S9S_MB_2U_LIB.S9S_MB_2U(SCH_1):GND
   24  GND             VSS8  @S9S_MB_2U_LIB.S9S_MB_2U(SCH_1):GND
   21  GND             VSS7  @S9S_MB_2U_LIB.S9S_MB_2U(SCH_1):GND
   19  GND             VSS6  @S9S_MB_2U_LIB.S9S_MB_2U(SCH_1):GND
   17  GND             VSS5  @S9S_MB_2U_LIB.S9S_MB_2U(SCH_1):GND
   15  GND             VSS4  @S9S_MB_2U_LIB.S9S_MB_2U(SCH_1):GND
   13  GND             VSS3  @S9S_MB_2U_LIB.S9S_MB_2U(SCH_1):GND
   10  GND             VSS2  @S9S_MB_2U_LIB.S9S_MB_2U(SCH_1):GND
    8  GND             VSS1  @S9S_MB_2U_LIB.S9S_MB_2U(SCH_1):GND
    6  GND             VSS0  @S9S_MB_2U_LIB.S9S_MB_2U(SCH_1):GND
   G3  GND               G3  @S9S_MB_2U_LIB.S9S_MB_2U(SCH_1):GND
   G2  GND               G2  @S9S_MB_2U_LIB.S9S_MB_2U(SCH_1):GND
   G1  GND               G1  @S9S_MB_2U_LIB.S9S_MB_2U(SCH_1):GND

SCONN288_ADR50001P013C01  I126  J23    [SCONN288_ADR50001P013C01-SCONNA]
   93  M_D_CPU1_SB_DQS_DP<9>  DQS9_B_P  @S9S_MB_2U_LIB.S9S_MB_2U(SCH_1):M_D_CPU1_SB_DQS_DP<9>
  283  M_D_CPU1_SB_DQS_DP<8>  DQS8_B_P  @S9S_MB_2U_LIB.S9S_MB_2U(SCH_1):M_D_CPU1_SB_DQS_DP<8>
  272  M_D_CPU1_SB_DQS_DP<7>  DQS7_B_P  @S9S_MB_2U_LIB.S9S_MB_2U(SCH_1):M_D_CPU1_SB_DQS_DP<7>
  261  M_D_CPU1_SB_DQS_DP<6>  DQS6_B_P  @S9S_MB_2U_LIB.S9S_MB_2U(SCH_1):M_D_CPU1_SB_DQS_DP<6>
  250  M_D_CPU1_SB_DQS_DP<5>  DQS5_B_P  @S9S_MB_2U_LIB.S9S_MB_2U(SCH_1):M_D_CPU1_SB_DQS_DP<5>
  239  M_D_CPU1_SB_DQS_DP<4>  DQS4_B_P  @S9S_MB_2U_LIB.S9S_MB_2U(SCH_1):M_D_CPU1_SB_DQS_DP<4>
  137  M_D_CPU1_SB_DQS_DP<3>  DQS3_B_P  @S9S_MB_2U_LIB.S9S_MB_2U(SCH_1):M_D_CPU1_SB_DQS_DP<3>
  126  M_D_CPU1_SB_DQS_DP<2>  DQS2_B_P  @S9S_MB_2U_LIB.S9S_MB_2U(SCH_1):M_D_CPU1_SB_DQS_DP<2>
  115  M_D_CPU1_SB_DQS_DP<1>  DQS1_B_P  @S9S_MB_2U_LIB.S9S_MB_2U(SCH_1):M_D_CPU1_SB_DQS_DP<1>
  104  M_D_CPU1_SB_DQS_DP<0>  DQS0_B_P  @S9S_MB_2U_LIB.S9S_MB_2U(SCH_1):M_D_CPU1_SB_DQS_DP<0>
   94  M_D_CPU1_SB_DQS_DN<9>  DQS9_B_N  @S9S_MB_2U_LIB.S9S_MB_2U(SCH_1):M_D_CPU1_SB_DQS_DN<9>
  282  M_D_CPU1_SB_DQS_DN<8>  DQS8_B_N  @S9S_MB_2U_LIB.S9S_MB_2U(SCH_1):M_D_CPU1_SB_DQS_DN<8>
  271  M_D_CPU1_SB_DQS_DN<7>  DQS7_B_N  @S9S_MB_2U_LIB.S9S_MB_2U(SCH_1):M_D_CPU1_SB_DQS_DN<7>
  260  M_D_CPU1_SB_DQS_DN<6>  DQS6_B_N  @S9S_MB_2U_LIB.S9S_MB_2U(SCH_1):M_D_CPU1_SB_DQS_DN<6>
  249  M_D_CPU1_SB_DQS_DN<5>  DQS5_B_N  @S9S_MB_2U_LIB.S9S_MB_2U(SCH_1):M_D_CPU1_SB_DQS_DN<5>
  238  M_D_CPU1_SB_DQS_DN<4>  DQS4_B_N  @S9S_MB_2U_LIB.S9S_MB_2U(SCH_1):M_D_CPU1_SB_DQS_DN<4>
  138  M_D_CPU1_SB_DQS_DN<3>  DQS3_B_N  @S9S_MB_2U_LIB.S9S_MB_2U(SCH_1):M_D_CPU1_SB_DQS_DN<3>
  127  M_D_CPU1_SB_DQS_DN<2>  DQS2_B_N  @S9S_MB_2U_LIB.S9S_MB_2U(SCH_1):M_D_CPU1_SB_DQS_DN<2>
  116  M_D_CPU1_SB_DQS_DN<1>  DQS1_B_N  @S9S_MB_2U_LIB.S9S_MB_2U(SCH_1):M_D_CPU1_SB_DQS_DN<1>
  105  M_D_CPU1_SB_DQS_DN<0>  DQS0_B_N  @S9S_MB_2U_LIB.S9S_MB_2U(SCH_1):M_D_CPU1_SB_DQS_DN<0>
  201  M_D_CPU1_SA_DQS_DP<9>  DQS9_A_P  @S9S_MB_2U_LIB.S9S_MB_2U(SCH_1):M_D_CPU1_SA_DQS_DP<9>
  190  M_D_CPU1_SA_DQS_DP<8>  DQS8_A_P  @S9S_MB_2U_LIB.S9S_MB_2U(SCH_1):M_D_CPU1_SA_DQS_DP<8>
  179  M_D_CPU1_SA_DQS_DP<7>  DQS7_A_P  @S9S_MB_2U_LIB.S9S_MB_2U(SCH_1):M_D_CPU1_SA_DQS_DP<7>
  168  M_D_CPU1_SA_DQS_DP<6>  DQS6_A_P  @S9S_MB_2U_LIB.S9S_MB_2U(SCH_1):M_D_CPU1_SA_DQS_DP<6>
  157  M_D_CPU1_SA_DQS_DP<5>  DQS5_A_P  @S9S_MB_2U_LIB.S9S_MB_2U(SCH_1):M_D_CPU1_SA_DQS_DP<5>
   55  M_D_CPU1_SA_DQS_DP<4>  DQS4_A_P  @S9S_MB_2U_LIB.S9S_MB_2U(SCH_1):M_D_CPU1_SA_DQS_DP<4>
   44  M_D_CPU1_SA_DQS_DP<3>  DQS3_A_P  @S9S_MB_2U_LIB.S9S_MB_2U(SCH_1):M_D_CPU1_SA_DQS_DP<3>
   33  M_D_CPU1_SA_DQS_DP<2>  DQS2_A_P  @S9S_MB_2U_LIB.S9S_MB_2U(SCH_1):M_D_CPU1_SA_DQS_DP<2>
   22  M_D_CPU1_SA_DQS_DP<1>  DQS1_A_P  @S9S_MB_2U_LIB.S9S_MB_2U(SCH_1):M_D_CPU1_SA_DQS_DP<1>
   11  M_D_CPU1_SA_DQS_DP<0>  DQS0_A_P  @S9S_MB_2U_LIB.S9S_MB_2U(SCH_1):M_D_CPU1_SA_DQS_DP<0>
  200  M_D_CPU1_SA_DQS_DN<9>  DQS9_A_N  @S9S_MB_2U_LIB.S9S_MB_2U(SCH_1):M_D_CPU1_SA_DQS_DN<9>
  189  M_D_CPU1_SA_DQS_DN<8>  DQS8_A_N  @S9S_MB_2U_LIB.S9S_MB_2U(SCH_1):M_D_CPU1_SA_DQS_DN<8>
  178  M_D_CPU1_SA_DQS_DN<7>  DQS7_A_N  @S9S_MB_2U_LIB.S9S_MB_2U(SCH_1):M_D_CPU1_SA_DQS_DN<7>
  167  M_D_CPU1_SA_DQS_DN<6>  DQS6_A_N  @S9S_MB_2U_LIB.S9S_MB_2U(SCH_1):M_D_CPU1_SA_DQS_DN<6>
  156  M_D_CPU1_SA_DQS_DN<5>  DQS5_A_N  @S9S_MB_2U_LIB.S9S_MB_2U(SCH_1):M_D_CPU1_SA_DQS_DN<5>
   56  M_D_CPU1_SA_DQS_DN<4>  DQS4_A_N  @S9S_MB_2U_LIB.S9S_MB_2U(SCH_1):M_D_CPU1_SA_DQS_DN<4>
   45  M_D_CPU1_SA_DQS_DN<3>  DQS3_A_N  @S9S_MB_2U_LIB.S9S_MB_2U(SCH_1):M_D_CPU1_SA_DQS_DN<3>
   34  M_D_CPU1_SA_DQS_DN<2>  DQS2_A_N  @S9S_MB_2U_LIB.S9S_MB_2U(SCH_1):M_D_CPU1_SA_DQS_DN<2>
   23  M_D_CPU1_SA_DQS_DN<1>  DQS1_A_N  @S9S_MB_2U_LIB.S9S_MB_2U(SCH_1):M_D_CPU1_SA_DQS_DN<1>
   12  M_D_CPU1_SA_DQS_DN<0>  DQS0_A_N  @S9S_MB_2U_LIB.S9S_MB_2U(SCH_1):M_D_CPU1_SA_DQS_DN<0>

SCONN288_ADR50001P013C01  I25  J23    [SCONN288_ADR50001P013C01-SCONNA]
  232  NC              RFU6  NC
  231  NC              RFU5  NC
  220  NC              RFU4  NC
  150  NC              RFU3  NC
  149  NC              RFU2  NC
  144  NC              RFU1  NC
    2  NC              RFU0  NC
  207  RST_M_CD_CPU1_FPGA_N  RESET_N  @S9S_MB_2U_LIB.S9S_MB_2U(SCH_1):RST_M_CD_CPU1_FPGA_N
  147  PWRGD_CHD_CPU1_DIMM1  PWR_GOOD||FAIL_N  @S9S_MB_2U_LIB.S9S_MB_2U(SCH_1):PWRGD_CHD_CPU1_DIMM1
  148  PD_CHD_CPU1_DIMM1_SAA    HAS  @S9S_MB_2U_LIB.S9S_MB_2U(SCH_1):PD_CHD_CPU1_DIMM1_SAA
    3  P3V3_AUX       VIN_MGMT  @S9S_MB_2U_LIB.S9S_MB_2U(SCH_1):P3V3_AUX
   87  M_D_CPU1_SB_RSP<0>  LBS||RSP_N_B  @S9S_MB_2U_LIB.S9S_MB_2U(SCH_1):M_D_CPU1_SB_RSP<0>
  227  M_D_CPU1_SB_PAR  PAR_B  @S9S_MB_2U_LIB.S9S_MB_2U(SCH_1):M_D_CPU1_SB_PAR
  113  M_D_CPU1_SB_DQ<9>  DQ_B9  @S9S_MB_2U_LIB.S9S_MB_2U(SCH_1):M_D_CPU1_SB_DQ<9>
  111  M_D_CPU1_SB_DQ<8>  DQ_B8  @S9S_MB_2U_LIB.S9S_MB_2U(SCH_1):M_D_CPU1_SB_DQ<8>
  254  M_D_CPU1_SB_DQ<7>  DQ_B7  @S9S_MB_2U_LIB.S9S_MB_2U(SCH_1):M_D_CPU1_SB_DQ<7>
  252  M_D_CPU1_SB_DQ<6>  DQ_B6  @S9S_MB_2U_LIB.S9S_MB_2U(SCH_1):M_D_CPU1_SB_DQ<6>
  109  M_D_CPU1_SB_DQ<5>  DQ_B5  @S9S_MB_2U_LIB.S9S_MB_2U(SCH_1):M_D_CPU1_SB_DQ<5>
  107  M_D_CPU1_SB_DQ<4>  DQ_B4  @S9S_MB_2U_LIB.S9S_MB_2U(SCH_1):M_D_CPU1_SB_DQ<4>
  247  M_D_CPU1_SB_DQ<3>  DQ_B3  @S9S_MB_2U_LIB.S9S_MB_2U(SCH_1):M_D_CPU1_SB_DQ<3>
  287  M_D_CPU1_SB_DQ<31>  DQ_B31  @S9S_MB_2U_LIB.S9S_MB_2U(SCH_1):M_D_CPU1_SB_DQ<31>
  285  M_D_CPU1_SB_DQ<30>  DQ_B30  @S9S_MB_2U_LIB.S9S_MB_2U(SCH_1):M_D_CPU1_SB_DQ<30>
  245  M_D_CPU1_SB_DQ<2>  DQ_B2  @S9S_MB_2U_LIB.S9S_MB_2U(SCH_1):M_D_CPU1_SB_DQ<2>
  142  M_D_CPU1_SB_DQ<29>  DQ_B29  @S9S_MB_2U_LIB.S9S_MB_2U(SCH_1):M_D_CPU1_SB_DQ<29>
  140  M_D_CPU1_SB_DQ<28>  DQ_B28  @S9S_MB_2U_LIB.S9S_MB_2U(SCH_1):M_D_CPU1_SB_DQ<28>
  280  M_D_CPU1_SB_DQ<27>  DQ_B27  @S9S_MB_2U_LIB.S9S_MB_2U(SCH_1):M_D_CPU1_SB_DQ<27>
  278  M_D_CPU1_SB_DQ<26>  DQ_B26  @S9S_MB_2U_LIB.S9S_MB_2U(SCH_1):M_D_CPU1_SB_DQ<26>
  135  M_D_CPU1_SB_DQ<25>  DQ_B25  @S9S_MB_2U_LIB.S9S_MB_2U(SCH_1):M_D_CPU1_SB_DQ<25>
  133  M_D_CPU1_SB_DQ<24>  DQ_B24  @S9S_MB_2U_LIB.S9S_MB_2U(SCH_1):M_D_CPU1_SB_DQ<24>
  276  M_D_CPU1_SB_DQ<23>  DQ_B23  @S9S_MB_2U_LIB.S9S_MB_2U(SCH_1):M_D_CPU1_SB_DQ<23>
  274  M_D_CPU1_SB_DQ<22>  DQ_B22  @S9S_MB_2U_LIB.S9S_MB_2U(SCH_1):M_D_CPU1_SB_DQ<22>
  131  M_D_CPU1_SB_DQ<21>  DQ_B21  @S9S_MB_2U_LIB.S9S_MB_2U(SCH_1):M_D_CPU1_SB_DQ<21>
  129  M_D_CPU1_SB_DQ<20>  DQ_B20  @S9S_MB_2U_LIB.S9S_MB_2U(SCH_1):M_D_CPU1_SB_DQ<20>
  102  M_D_CPU1_SB_DQ<1>  DQ_B1  @S9S_MB_2U_LIB.S9S_MB_2U(SCH_1):M_D_CPU1_SB_DQ<1>
  269  M_D_CPU1_SB_DQ<19>  DQ_B19  @S9S_MB_2U_LIB.S9S_MB_2U(SCH_1):M_D_CPU1_SB_DQ<19>
  267  M_D_CPU1_SB_DQ<18>  DQ_B18  @S9S_MB_2U_LIB.S9S_MB_2U(SCH_1):M_D_CPU1_SB_DQ<18>
  124  M_D_CPU1_SB_DQ<17>  DQ_B17  @S9S_MB_2U_LIB.S9S_MB_2U(SCH_1):M_D_CPU1_SB_DQ<17>
  122  M_D_CPU1_SB_DQ<16>  DQ_B16  @S9S_MB_2U_LIB.S9S_MB_2U(SCH_1):M_D_CPU1_SB_DQ<16>
  265  M_D_CPU1_SB_DQ<15>  DQ_B15  @S9S_MB_2U_LIB.S9S_MB_2U(SCH_1):M_D_CPU1_SB_DQ<15>
  263  M_D_CPU1_SB_DQ<14>  DQ_B14  @S9S_MB_2U_LIB.S9S_MB_2U(SCH_1):M_D_CPU1_SB_DQ<14>
  120  M_D_CPU1_SB_DQ<13>  DQ_B13  @S9S_MB_2U_LIB.S9S_MB_2U(SCH_1):M_D_CPU1_SB_DQ<13>
  118  M_D_CPU1_SB_DQ<12>  DQ_B12  @S9S_MB_2U_LIB.S9S_MB_2U(SCH_1):M_D_CPU1_SB_DQ<12>
  258  M_D_CPU1_SB_DQ<11>  DQ_B11  @S9S_MB_2U_LIB.S9S_MB_2U(SCH_1):M_D_CPU1_SB_DQ<11>
  256  M_D_CPU1_SB_DQ<10>  DQ_B10  @S9S_MB_2U_LIB.S9S_MB_2U(SCH_1):M_D_CPU1_SB_DQ<10>
  100  M_D_CPU1_SB_DQ<0>  DQ_B0  @S9S_MB_2U_LIB.S9S_MB_2U(SCH_1):M_D_CPU1_SB_DQ<0>
  229  M_D_CPU1_SB_CS_N<1>  CS1_N_B  @S9S_MB_2U_LIB.S9S_MB_2U(SCH_1):M_D_CPU1_SB_CS_N<1>
   84  M_D_CPU1_SB_CS_N<0>  CS0_N_B  @S9S_MB_2U_LIB.S9S_MB_2U(SCH_1):M_D_CPU1_SB_CS_N<0>
  236  M_D_CPU1_SB_CB<7>  CB_B7  @S9S_MB_2U_LIB.S9S_MB_2U(SCH_1):M_D_CPU1_SB_CB<7>
  234  M_D_CPU1_SB_CB<6>  CB_B6  @S9S_MB_2U_LIB.S9S_MB_2U(SCH_1):M_D_CPU1_SB_CB<6>
   91  M_D_CPU1_SB_CB<5>  CB_B5  @S9S_MB_2U_LIB.S9S_MB_2U(SCH_1):M_D_CPU1_SB_CB<5>
   89  M_D_CPU1_SB_CB<4>  CB_B4  @S9S_MB_2U_LIB.S9S_MB_2U(SCH_1):M_D_CPU1_SB_CB<4>
  243  M_D_CPU1_SB_CB<3>  CB_B3  @S9S_MB_2U_LIB.S9S_MB_2U(SCH_1):M_D_CPU1_SB_CB<3>
  241  M_D_CPU1_SB_CB<2>  CB_B2  @S9S_MB_2U_LIB.S9S_MB_2U(SCH_1):M_D_CPU1_SB_CB<2>
   98  M_D_CPU1_SB_CB<1>  CB_B1  @S9S_MB_2U_LIB.S9S_MB_2U(SCH_1):M_D_CPU1_SB_CB<1>
   96  M_D_CPU1_SB_CB<0>  CB_B0  @S9S_MB_2U_LIB.S9S_MB_2U(SCH_1):M_D_CPU1_SB_CB<0>
   82  M_D_CPU1_SB_CA<6>  CA6_B  @S9S_MB_2U_LIB.S9S_MB_2U(SCH_1):M_D_CPU1_SB_CA<6>
  225  M_D_CPU1_SB_CA<5>  CA5_B  @S9S_MB_2U_LIB.S9S_MB_2U(SCH_1):M_D_CPU1_SB_CA<5>
   80  M_D_CPU1_SB_CA<4>  CA4_B  @S9S_MB_2U_LIB.S9S_MB_2U(SCH_1):M_D_CPU1_SB_CA<4>
  223  M_D_CPU1_SB_CA<3>  CA3_B  @S9S_MB_2U_LIB.S9S_MB_2U(SCH_1):M_D_CPU1_SB_CA<3>
   78  M_D_CPU1_SB_CA<2>  CA2_B  @S9S_MB_2U_LIB.S9S_MB_2U(SCH_1):M_D_CPU1_SB_CA<2>
  221  M_D_CPU1_SB_CA<1>  CA1_B  @S9S_MB_2U_LIB.S9S_MB_2U(SCH_1):M_D_CPU1_SB_CA<1>
   76  M_D_CPU1_SB_CA<0>  CA0_B  @S9S_MB_2U_LIB.S9S_MB_2U(SCH_1):M_D_CPU1_SB_CA<0>
   86  M_D_CPU1_SA_RSP<0>  LBD||RSP_N_A  @S9S_MB_2U_LIB.S9S_MB_2U(SCH_1):M_D_CPU1_SA_RSP<0>
   74  M_D_CPU1_SA_PAR  PAR_A  @S9S_MB_2U_LIB.S9S_MB_2U(SCH_1):M_D_CPU1_SA_PAR
   20  M_D_CPU1_SA_DQ<9>  DQ_A9  @S9S_MB_2U_LIB.S9S_MB_2U(SCH_1):M_D_CPU1_SA_DQ<9>
   18  M_D_CPU1_SA_DQ<8>  DQ_A8  @S9S_MB_2U_LIB.S9S_MB_2U(SCH_1):M_D_CPU1_SA_DQ<8>
  161  M_D_CPU1_SA_DQ<7>  DQ_A7  @S9S_MB_2U_LIB.S9S_MB_2U(SCH_1):M_D_CPU1_SA_DQ<7>
  159  M_D_CPU1_SA_DQ<6>  DQ_A6  @S9S_MB_2U_LIB.S9S_MB_2U(SCH_1):M_D_CPU1_SA_DQ<6>
   16  M_D_CPU1_SA_DQ<5>  DQ_A5  @S9S_MB_2U_LIB.S9S_MB_2U(SCH_1):M_D_CPU1_SA_DQ<5>
   14  M_D_CPU1_SA_DQ<4>  DQ_A4  @S9S_MB_2U_LIB.S9S_MB_2U(SCH_1):M_D_CPU1_SA_DQ<4>
  154  M_D_CPU1_SA_DQ<3>  DQ_A3  @S9S_MB_2U_LIB.S9S_MB_2U(SCH_1):M_D_CPU1_SA_DQ<3>
  194  M_D_CPU1_SA_DQ<31>  DQ_A31  @S9S_MB_2U_LIB.S9S_MB_2U(SCH_1):M_D_CPU1_SA_DQ<31>
  192  M_D_CPU1_SA_DQ<30>  DQ_A30  @S9S_MB_2U_LIB.S9S_MB_2U(SCH_1):M_D_CPU1_SA_DQ<30>
  152  M_D_CPU1_SA_DQ<2>  DQ_A2  @S9S_MB_2U_LIB.S9S_MB_2U(SCH_1):M_D_CPU1_SA_DQ<2>
   49  M_D_CPU1_SA_DQ<29>  DQ_A29  @S9S_MB_2U_LIB.S9S_MB_2U(SCH_1):M_D_CPU1_SA_DQ<29>
   47  M_D_CPU1_SA_DQ<28>  DQ_A28  @S9S_MB_2U_LIB.S9S_MB_2U(SCH_1):M_D_CPU1_SA_DQ<28>
  187  M_D_CPU1_SA_DQ<27>  DQ_A27  @S9S_MB_2U_LIB.S9S_MB_2U(SCH_1):M_D_CPU1_SA_DQ<27>
  185  M_D_CPU1_SA_DQ<26>  DQ_A26  @S9S_MB_2U_LIB.S9S_MB_2U(SCH_1):M_D_CPU1_SA_DQ<26>
   42  M_D_CPU1_SA_DQ<25>  DQ_A25  @S9S_MB_2U_LIB.S9S_MB_2U(SCH_1):M_D_CPU1_SA_DQ<25>
   40  M_D_CPU1_SA_DQ<24>  DQ_A24  @S9S_MB_2U_LIB.S9S_MB_2U(SCH_1):M_D_CPU1_SA_DQ<24>
  183  M_D_CPU1_SA_DQ<23>  DQ_A23  @S9S_MB_2U_LIB.S9S_MB_2U(SCH_1):M_D_CPU1_SA_DQ<23>
  181  M_D_CPU1_SA_DQ<22>  DQ_A22  @S9S_MB_2U_LIB.S9S_MB_2U(SCH_1):M_D_CPU1_SA_DQ<22>
   38  M_D_CPU1_SA_DQ<21>  DQ_A21  @S9S_MB_2U_LIB.S9S_MB_2U(SCH_1):M_D_CPU1_SA_DQ<21>
   36  M_D_CPU1_SA_DQ<20>  DQ_A20  @S9S_MB_2U_LIB.S9S_MB_2U(SCH_1):M_D_CPU1_SA_DQ<20>
    9  M_D_CPU1_SA_DQ<1>  DQ_A1  @S9S_MB_2U_LIB.S9S_MB_2U(SCH_1):M_D_CPU1_SA_DQ<1>
  176  M_D_CPU1_SA_DQ<19>  DQ_A19  @S9S_MB_2U_LIB.S9S_MB_2U(SCH_1):M_D_CPU1_SA_DQ<19>
  174  M_D_CPU1_SA_DQ<18>  DQ_A18  @S9S_MB_2U_LIB.S9S_MB_2U(SCH_1):M_D_CPU1_SA_DQ<18>
   31  M_D_CPU1_SA_DQ<17>  DQ_A17  @S9S_MB_2U_LIB.S9S_MB_2U(SCH_1):M_D_CPU1_SA_DQ<17>
   29  M_D_CPU1_SA_DQ<16>  DQ_A16  @S9S_MB_2U_LIB.S9S_MB_2U(SCH_1):M_D_CPU1_SA_DQ<16>
  172  M_D_CPU1_SA_DQ<15>  DQ_A15  @S9S_MB_2U_LIB.S9S_MB_2U(SCH_1):M_D_CPU1_SA_DQ<15>
  170  M_D_CPU1_SA_DQ<14>  DQ_A14  @S9S_MB_2U_LIB.S9S_MB_2U(SCH_1):M_D_CPU1_SA_DQ<14>
   27  M_D_CPU1_SA_DQ<13>  DQ_A13  @S9S_MB_2U_LIB.S9S_MB_2U(SCH_1):M_D_CPU1_SA_DQ<13>
   25  M_D_CPU1_SA_DQ<12>  DQ_A12  @S9S_MB_2U_LIB.S9S_MB_2U(SCH_1):M_D_CPU1_SA_DQ<12>
  165  M_D_CPU1_SA_DQ<11>  DQ_A11  @S9S_MB_2U_LIB.S9S_MB_2U(SCH_1):M_D_CPU1_SA_DQ<11>
  163  M_D_CPU1_SA_DQ<10>  DQ_A10  @S9S_MB_2U_LIB.S9S_MB_2U(SCH_1):M_D_CPU1_SA_DQ<10>
    7  M_D_CPU1_SA_DQ<0>  DQ_A0  @S9S_MB_2U_LIB.S9S_MB_2U(SCH_1):M_D_CPU1_SA_DQ<0>
  209  M_D_CPU1_SA_CS_N<1>  CS1_N_A  @S9S_MB_2U_LIB.S9S_MB_2U(SCH_1):M_D_CPU1_SA_CS_N<1>
   64  M_D_CPU1_SA_CS_N<0>  CS0_N_A  @S9S_MB_2U_LIB.S9S_MB_2U(SCH_1):M_D_CPU1_SA_CS_N<0>
  205  M_D_CPU1_SA_CB<7>  CB_A7  @S9S_MB_2U_LIB.S9S_MB_2U(SCH_1):M_D_CPU1_SA_CB<7>
  203  M_D_CPU1_SA_CB<6>  CB_A6  @S9S_MB_2U_LIB.S9S_MB_2U(SCH_1):M_D_CPU1_SA_CB<6>
   60  M_D_CPU1_SA_CB<5>  CB_A5  @S9S_MB_2U_LIB.S9S_MB_2U(SCH_1):M_D_CPU1_SA_CB<5>
   58  M_D_CPU1_SA_CB<4>  CB_A4  @S9S_MB_2U_LIB.S9S_MB_2U(SCH_1):M_D_CPU1_SA_CB<4>
  198  M_D_CPU1_SA_CB<3>  CB_A3  @S9S_MB_2U_LIB.S9S_MB_2U(SCH_1):M_D_CPU1_SA_CB<3>
  196  M_D_CPU1_SA_CB<2>  CB_A2  @S9S_MB_2U_LIB.S9S_MB_2U(SCH_1):M_D_CPU1_SA_CB<2>
   53  M_D_CPU1_SA_CB<1>  CB_A1  @S9S_MB_2U_LIB.S9S_MB_2U(SCH_1):M_D_CPU1_SA_CB<1>
   51  M_D_CPU1_SA_CB<0>  CB_A0  @S9S_MB_2U_LIB.S9S_MB_2U(SCH_1):M_D_CPU1_SA_CB<0>
   72  M_D_CPU1_SA_CA<6>  CA6_A  @S9S_MB_2U_LIB.S9S_MB_2U(SCH_1):M_D_CPU1_SA_CA<6>
  215  M_D_CPU1_SA_CA<5>  CA5_A  @S9S_MB_2U_LIB.S9S_MB_2U(SCH_1):M_D_CPU1_SA_CA<5>
   70  M_D_CPU1_SA_CA<4>  CA4_A  @S9S_MB_2U_LIB.S9S_MB_2U(SCH_1):M_D_CPU1_SA_CA<4>
  213  M_D_CPU1_SA_CA<3>  CA3_A  @S9S_MB_2U_LIB.S9S_MB_2U(SCH_1):M_D_CPU1_SA_CA<3>
   68  M_D_CPU1_SA_CA<2>  CA2_A  @S9S_MB_2U_LIB.S9S_MB_2U(SCH_1):M_D_CPU1_SA_CA<2>
  211  M_D_CPU1_SA_CA<1>  CA1_A  @S9S_MB_2U_LIB.S9S_MB_2U(SCH_1):M_D_CPU1_SA_CA<1>
   66  M_D_CPU1_SA_CA<0>  CA0_A  @S9S_MB_2U_LIB.S9S_MB_2U(SCH_1):M_D_CPU1_SA_CA<0>
  217  M_D_CPU1_CLK_DP<0>   CK_P  @S9S_MB_2U_LIB.S9S_MB_2U(SCH_1):M_D_CPU1_CLK_DP<0>
  218  M_D_CPU1_CLK_DN<0>   CK_N  @S9S_MB_2U_LIB.S9S_MB_2U(SCH_1):M_D_CPU1_CLK_DN<0>
   62  M_D_CPU1_ALERT_N  ALERT_N  @S9S_MB_2U_LIB.S9S_MB_2U(SCH_1):M_D_CPU1_ALERT_N
    5  I3C_SPD_DDRABCD_CPU1_LVC1_SDA   HSDA  @S9S_MB_2U_LIB.S9S_MB_2U(SCH_1):I3C_SPD_DDRABCD_CPU1_LVC1_SDA
    4  I3C_SPD_DDRABCD_CPU1_LVC1_SCL   HSCL  @S9S_MB_2U_LIB.S9S_MB_2U(SCH_1):I3C_SPD_DDRABCD_CPU1_LVC1_SCL

SCONN288_ADR50001P003C01  I180  J24    [SCONN288_ADR50001P003C01-SCONNA]
  146  P12V_S3_AUX_CPU1_NVDIMM  VIN_BULK2  @S9S_MB_2U_LIB.S9S_MB_2U(SCH_1):P12V_S3_AUX_CPU1_NVDIMM
  145  P12V_S3_AUX_CPU1_NVDIMM  VIN_BULK1  @S9S_MB_2U_LIB.S9S_MB_2U(SCH_1):P12V_S3_AUX_CPU1_NVDIMM
    1  P12V_S3_AUX_CPU1_NVDIMM  VIN_BULK0  @S9S_MB_2U_LIB.S9S_MB_2U(SCH_1):P12V_S3_AUX_CPU1_NVDIMM
  288  GND            VSS126  @S9S_MB_2U_LIB.S9S_MB_2U(SCH_1):GND
  286  GND            VSS125  @S9S_MB_2U_LIB.S9S_MB_2U(SCH_1):GND
  284  GND            VSS124  @S9S_MB_2U_LIB.S9S_MB_2U(SCH_1):GND
  281  GND            VSS123  @S9S_MB_2U_LIB.S9S_MB_2U(SCH_1):GND
  279  GND            VSS122  @S9S_MB_2U_LIB.S9S_MB_2U(SCH_1):GND
  277  GND            VSS121  @S9S_MB_2U_LIB.S9S_MB_2U(SCH_1):GND
  275  GND            VSS120  @S9S_MB_2U_LIB.S9S_MB_2U(SCH_1):GND
  273  GND            VSS119  @S9S_MB_2U_LIB.S9S_MB_2U(SCH_1):GND
  270  GND            VSS118  @S9S_MB_2U_LIB.S9S_MB_2U(SCH_1):GND
  268  GND            VSS117  @S9S_MB_2U_LIB.S9S_MB_2U(SCH_1):GND
  266  GND            VSS116  @S9S_MB_2U_LIB.S9S_MB_2U(SCH_1):GND
  264  GND            VSS115  @S9S_MB_2U_LIB.S9S_MB_2U(SCH_1):GND
  262  GND            VSS114  @S9S_MB_2U_LIB.S9S_MB_2U(SCH_1):GND
  259  GND            VSS113  @S9S_MB_2U_LIB.S9S_MB_2U(SCH_1):GND
  257  GND            VSS112  @S9S_MB_2U_LIB.S9S_MB_2U(SCH_1):GND
  255  GND            VSS111  @S9S_MB_2U_LIB.S9S_MB_2U(SCH_1):GND
  253  GND            VSS110  @S9S_MB_2U_LIB.S9S_MB_2U(SCH_1):GND
  251  GND            VSS109  @S9S_MB_2U_LIB.S9S_MB_2U(SCH_1):GND
  248  GND            VSS108  @S9S_MB_2U_LIB.S9S_MB_2U(SCH_1):GND
  246  GND            VSS107  @S9S_MB_2U_LIB.S9S_MB_2U(SCH_1):GND
  244  GND            VSS106  @S9S_MB_2U_LIB.S9S_MB_2U(SCH_1):GND
  242  GND            VSS105  @S9S_MB_2U_LIB.S9S_MB_2U(SCH_1):GND
  240  GND            VSS104  @S9S_MB_2U_LIB.S9S_MB_2U(SCH_1):GND
  237  GND            VSS103  @S9S_MB_2U_LIB.S9S_MB_2U(SCH_1):GND
  235  GND            VSS102  @S9S_MB_2U_LIB.S9S_MB_2U(SCH_1):GND
  233  GND            VSS101  @S9S_MB_2U_LIB.S9S_MB_2U(SCH_1):GND
  230  GND            VSS100  @S9S_MB_2U_LIB.S9S_MB_2U(SCH_1):GND
  228  GND            VSS99  @S9S_MB_2U_LIB.S9S_MB_2U(SCH_1):GND
  226  GND            VSS98  @S9S_MB_2U_LIB.S9S_MB_2U(SCH_1):GND
  224  GND            VSS97  @S9S_MB_2U_LIB.S9S_MB_2U(SCH_1):GND
  222  GND            VSS96  @S9S_MB_2U_LIB.S9S_MB_2U(SCH_1):GND
  219  GND            VSS95  @S9S_MB_2U_LIB.S9S_MB_2U(SCH_1):GND
  216  GND            VSS94  @S9S_MB_2U_LIB.S9S_MB_2U(SCH_1):GND
  214  GND            VSS93  @S9S_MB_2U_LIB.S9S_MB_2U(SCH_1):GND
  212  GND            VSS92  @S9S_MB_2U_LIB.S9S_MB_2U(SCH_1):GND
  210  GND            VSS91  @S9S_MB_2U_LIB.S9S_MB_2U(SCH_1):GND
  208  GND            VSS90  @S9S_MB_2U_LIB.S9S_MB_2U(SCH_1):GND
  206  GND            VSS89  @S9S_MB_2U_LIB.S9S_MB_2U(SCH_1):GND
  204  GND            VSS88  @S9S_MB_2U_LIB.S9S_MB_2U(SCH_1):GND
  202  GND            VSS87  @S9S_MB_2U_LIB.S9S_MB_2U(SCH_1):GND
  199  GND            VSS86  @S9S_MB_2U_LIB.S9S_MB_2U(SCH_1):GND
  197  GND            VSS85  @S9S_MB_2U_LIB.S9S_MB_2U(SCH_1):GND
  195  GND            VSS84  @S9S_MB_2U_LIB.S9S_MB_2U(SCH_1):GND
  193  GND            VSS83  @S9S_MB_2U_LIB.S9S_MB_2U(SCH_1):GND
  191  GND            VSS82  @S9S_MB_2U_LIB.S9S_MB_2U(SCH_1):GND
  188  GND            VSS81  @S9S_MB_2U_LIB.S9S_MB_2U(SCH_1):GND
  186  GND            VSS80  @S9S_MB_2U_LIB.S9S_MB_2U(SCH_1):GND
  184  GND            VSS79  @S9S_MB_2U_LIB.S9S_MB_2U(SCH_1):GND
  182  GND            VSS78  @S9S_MB_2U_LIB.S9S_MB_2U(SCH_1):GND
  180  GND            VSS77  @S9S_MB_2U_LIB.S9S_MB_2U(SCH_1):GND
  177  GND            VSS76  @S9S_MB_2U_LIB.S9S_MB_2U(SCH_1):GND
  175  GND            VSS75  @S9S_MB_2U_LIB.S9S_MB_2U(SCH_1):GND
  173  GND            VSS74  @S9S_MB_2U_LIB.S9S_MB_2U(SCH_1):GND
  171  GND            VSS73  @S9S_MB_2U_LIB.S9S_MB_2U(SCH_1):GND
  169  GND            VSS72  @S9S_MB_2U_LIB.S9S_MB_2U(SCH_1):GND
  166  GND            VSS71  @S9S_MB_2U_LIB.S9S_MB_2U(SCH_1):GND
  164  GND            VSS70  @S9S_MB_2U_LIB.S9S_MB_2U(SCH_1):GND
  162  GND            VSS69  @S9S_MB_2U_LIB.S9S_MB_2U(SCH_1):GND
  160  GND            VSS68  @S9S_MB_2U_LIB.S9S_MB_2U(SCH_1):GND
  158  GND            VSS67  @S9S_MB_2U_LIB.S9S_MB_2U(SCH_1):GND
  155  GND            VSS66  @S9S_MB_2U_LIB.S9S_MB_2U(SCH_1):GND
  153  GND            VSS65  @S9S_MB_2U_LIB.S9S_MB_2U(SCH_1):GND
  151  GND            VSS64  @S9S_MB_2U_LIB.S9S_MB_2U(SCH_1):GND
  143  GND            VSS63  @S9S_MB_2U_LIB.S9S_MB_2U(SCH_1):GND
  141  GND            VSS62  @S9S_MB_2U_LIB.S9S_MB_2U(SCH_1):GND
  139  GND            VSS61  @S9S_MB_2U_LIB.S9S_MB_2U(SCH_1):GND
  136  GND            VSS60  @S9S_MB_2U_LIB.S9S_MB_2U(SCH_1):GND
  134  GND            VSS59  @S9S_MB_2U_LIB.S9S_MB_2U(SCH_1):GND
  132  GND            VSS58  @S9S_MB_2U_LIB.S9S_MB_2U(SCH_1):GND
  130  GND            VSS57  @S9S_MB_2U_LIB.S9S_MB_2U(SCH_1):GND
  128  GND            VSS56  @S9S_MB_2U_LIB.S9S_MB_2U(SCH_1):GND
  125  GND            VSS55  @S9S_MB_2U_LIB.S9S_MB_2U(SCH_1):GND
  123  GND            VSS54  @S9S_MB_2U_LIB.S9S_MB_2U(SCH_1):GND
  121  GND            VSS53  @S9S_MB_2U_LIB.S9S_MB_2U(SCH_1):GND
  119  GND            VSS52  @S9S_MB_2U_LIB.S9S_MB_2U(SCH_1):GND
  117  GND            VSS51  @S9S_MB_2U_LIB.S9S_MB_2U(SCH_1):GND
  114  GND            VSS50  @S9S_MB_2U_LIB.S9S_MB_2U(SCH_1):GND
  112  GND            VSS49  @S9S_MB_2U_LIB.S9S_MB_2U(SCH_1):GND
  110  GND            VSS48  @S9S_MB_2U_LIB.S9S_MB_2U(SCH_1):GND
  108  GND            VSS47  @S9S_MB_2U_LIB.S9S_MB_2U(SCH_1):GND
  106  GND            VSS46  @S9S_MB_2U_LIB.S9S_MB_2U(SCH_1):GND
  103  GND            VSS45  @S9S_MB_2U_LIB.S9S_MB_2U(SCH_1):GND
  101  GND            VSS44  @S9S_MB_2U_LIB.S9S_MB_2U(SCH_1):GND
   99  GND            VSS43  @S9S_MB_2U_LIB.S9S_MB_2U(SCH_1):GND
   97  GND            VSS42  @S9S_MB_2U_LIB.S9S_MB_2U(SCH_1):GND
   95  GND            VSS41  @S9S_MB_2U_LIB.S9S_MB_2U(SCH_1):GND
   92  GND            VSS40  @S9S_MB_2U_LIB.S9S_MB_2U(SCH_1):GND
   90  GND            VSS39  @S9S_MB_2U_LIB.S9S_MB_2U(SCH_1):GND
   88  GND            VSS38  @S9S_MB_2U_LIB.S9S_MB_2U(SCH_1):GND
   85  GND            VSS37  @S9S_MB_2U_LIB.S9S_MB_2U(SCH_1):GND
   83  GND            VSS36  @S9S_MB_2U_LIB.S9S_MB_2U(SCH_1):GND
   81  GND            VSS35  @S9S_MB_2U_LIB.S9S_MB_2U(SCH_1):GND
   79  GND            VSS34  @S9S_MB_2U_LIB.S9S_MB_2U(SCH_1):GND
   77  GND            VSS33  @S9S_MB_2U_LIB.S9S_MB_2U(SCH_1):GND
   75  GND            VSS32  @S9S_MB_2U_LIB.S9S_MB_2U(SCH_1):GND
   73  GND            VSS31  @S9S_MB_2U_LIB.S9S_MB_2U(SCH_1):GND
   71  GND            VSS30  @S9S_MB_2U_LIB.S9S_MB_2U(SCH_1):GND
   69  GND            VSS29  @S9S_MB_2U_LIB.S9S_MB_2U(SCH_1):GND
   67  GND            VSS28  @S9S_MB_2U_LIB.S9S_MB_2U(SCH_1):GND
   65  GND            VSS27  @S9S_MB_2U_LIB.S9S_MB_2U(SCH_1):GND
   63  GND            VSS26  @S9S_MB_2U_LIB.S9S_MB_2U(SCH_1):GND
   61  GND            VSS25  @S9S_MB_2U_LIB.S9S_MB_2U(SCH_1):GND
   59  GND            VSS24  @S9S_MB_2U_LIB.S9S_MB_2U(SCH_1):GND
   57  GND            VSS23  @S9S_MB_2U_LIB.S9S_MB_2U(SCH_1):GND
   54  GND            VSS22  @S9S_MB_2U_LIB.S9S_MB_2U(SCH_1):GND
   52  GND            VSS21  @S9S_MB_2U_LIB.S9S_MB_2U(SCH_1):GND
   50  GND            VSS20  @S9S_MB_2U_LIB.S9S_MB_2U(SCH_1):GND
   48  GND            VSS19  @S9S_MB_2U_LIB.S9S_MB_2U(SCH_1):GND
   46  GND            VSS18  @S9S_MB_2U_LIB.S9S_MB_2U(SCH_1):GND
   43  GND            VSS17  @S9S_MB_2U_LIB.S9S_MB_2U(SCH_1):GND
   41  GND            VSS16  @S9S_MB_2U_LIB.S9S_MB_2U(SCH_1):GND
   39  GND            VSS15  @S9S_MB_2U_LIB.S9S_MB_2U(SCH_1):GND
   37  GND            VSS14  @S9S_MB_2U_LIB.S9S_MB_2U(SCH_1):GND
   35  GND            VSS13  @S9S_MB_2U_LIB.S9S_MB_2U(SCH_1):GND
   32  GND            VSS12  @S9S_MB_2U_LIB.S9S_MB_2U(SCH_1):GND
   30  GND            VSS11  @S9S_MB_2U_LIB.S9S_MB_2U(SCH_1):GND
   28  GND            VSS10  @S9S_MB_2U_LIB.S9S_MB_2U(SCH_1):GND
   26  GND             VSS9  @S9S_MB_2U_LIB.S9S_MB_2U(SCH_1):GND
   24  GND             VSS8  @S9S_MB_2U_LIB.S9S_MB_2U(SCH_1):GND
   21  GND             VSS7  @S9S_MB_2U_LIB.S9S_MB_2U(SCH_1):GND
   19  GND             VSS6  @S9S_MB_2U_LIB.S9S_MB_2U(SCH_1):GND
   17  GND             VSS5  @S9S_MB_2U_LIB.S9S_MB_2U(SCH_1):GND
   15  GND             VSS4  @S9S_MB_2U_LIB.S9S_MB_2U(SCH_1):GND
   13  GND             VSS3  @S9S_MB_2U_LIB.S9S_MB_2U(SCH_1):GND
   10  GND             VSS2  @S9S_MB_2U_LIB.S9S_MB_2U(SCH_1):GND
    8  GND             VSS1  @S9S_MB_2U_LIB.S9S_MB_2U(SCH_1):GND
    6  GND             VSS0  @S9S_MB_2U_LIB.S9S_MB_2U(SCH_1):GND
   G3  GND               G3  @S9S_MB_2U_LIB.S9S_MB_2U(SCH_1):GND
   G2  GND               G2  @S9S_MB_2U_LIB.S9S_MB_2U(SCH_1):GND
   G1  GND               G1  @S9S_MB_2U_LIB.S9S_MB_2U(SCH_1):GND

SCONN288_ADR50001P003C01  I179  J24    [SCONN288_ADR50001P003C01-SCONNA]
   93  M_D_CPU1_SB_DQS_DP<9>  DQS9_B_P  @S9S_MB_2U_LIB.S9S_MB_2U(SCH_1):M_D_CPU1_SB_DQS_DP<9>
  283  M_D_CPU1_SB_DQS_DP<8>  DQS8_B_P  @S9S_MB_2U_LIB.S9S_MB_2U(SCH_1):M_D_CPU1_SB_DQS_DP<8>
  272  M_D_CPU1_SB_DQS_DP<7>  DQS7_B_P  @S9S_MB_2U_LIB.S9S_MB_2U(SCH_1):M_D_CPU1_SB_DQS_DP<7>
  261  M_D_CPU1_SB_DQS_DP<6>  DQS6_B_P  @S9S_MB_2U_LIB.S9S_MB_2U(SCH_1):M_D_CPU1_SB_DQS_DP<6>
  250  M_D_CPU1_SB_DQS_DP<5>  DQS5_B_P  @S9S_MB_2U_LIB.S9S_MB_2U(SCH_1):M_D_CPU1_SB_DQS_DP<5>
  239  M_D_CPU1_SB_DQS_DP<4>  DQS4_B_P  @S9S_MB_2U_LIB.S9S_MB_2U(SCH_1):M_D_CPU1_SB_DQS_DP<4>
  137  M_D_CPU1_SB_DQS_DP<3>  DQS3_B_P  @S9S_MB_2U_LIB.S9S_MB_2U(SCH_1):M_D_CPU1_SB_DQS_DP<3>
  126  M_D_CPU1_SB_DQS_DP<2>  DQS2_B_P  @S9S_MB_2U_LIB.S9S_MB_2U(SCH_1):M_D_CPU1_SB_DQS_DP<2>
  115  M_D_CPU1_SB_DQS_DP<1>  DQS1_B_P  @S9S_MB_2U_LIB.S9S_MB_2U(SCH_1):M_D_CPU1_SB_DQS_DP<1>
  104  M_D_CPU1_SB_DQS_DP<0>  DQS0_B_P  @S9S_MB_2U_LIB.S9S_MB_2U(SCH_1):M_D_CPU1_SB_DQS_DP<0>
   94  M_D_CPU1_SB_DQS_DN<9>  DQS9_B_N  @S9S_MB_2U_LIB.S9S_MB_2U(SCH_1):M_D_CPU1_SB_DQS_DN<9>
  282  M_D_CPU1_SB_DQS_DN<8>  DQS8_B_N  @S9S_MB_2U_LIB.S9S_MB_2U(SCH_1):M_D_CPU1_SB_DQS_DN<8>
  271  M_D_CPU1_SB_DQS_DN<7>  DQS7_B_N  @S9S_MB_2U_LIB.S9S_MB_2U(SCH_1):M_D_CPU1_SB_DQS_DN<7>
  260  M_D_CPU1_SB_DQS_DN<6>  DQS6_B_N  @S9S_MB_2U_LIB.S9S_MB_2U(SCH_1):M_D_CPU1_SB_DQS_DN<6>
  249  M_D_CPU1_SB_DQS_DN<5>  DQS5_B_N  @S9S_MB_2U_LIB.S9S_MB_2U(SCH_1):M_D_CPU1_SB_DQS_DN<5>
  238  M_D_CPU1_SB_DQS_DN<4>  DQS4_B_N  @S9S_MB_2U_LIB.S9S_MB_2U(SCH_1):M_D_CPU1_SB_DQS_DN<4>
  138  M_D_CPU1_SB_DQS_DN<3>  DQS3_B_N  @S9S_MB_2U_LIB.S9S_MB_2U(SCH_1):M_D_CPU1_SB_DQS_DN<3>
  127  M_D_CPU1_SB_DQS_DN<2>  DQS2_B_N  @S9S_MB_2U_LIB.S9S_MB_2U(SCH_1):M_D_CPU1_SB_DQS_DN<2>
  116  M_D_CPU1_SB_DQS_DN<1>  DQS1_B_N  @S9S_MB_2U_LIB.S9S_MB_2U(SCH_1):M_D_CPU1_SB_DQS_DN<1>
  105  M_D_CPU1_SB_DQS_DN<0>  DQS0_B_N  @S9S_MB_2U_LIB.S9S_MB_2U(SCH_1):M_D_CPU1_SB_DQS_DN<0>
  201  M_D_CPU1_SA_DQS_DP<9>  DQS9_A_P  @S9S_MB_2U_LIB.S9S_MB_2U(SCH_1):M_D_CPU1_SA_DQS_DP<9>
  190  M_D_CPU1_SA_DQS_DP<8>  DQS8_A_P  @S9S_MB_2U_LIB.S9S_MB_2U(SCH_1):M_D_CPU1_SA_DQS_DP<8>
  179  M_D_CPU1_SA_DQS_DP<7>  DQS7_A_P  @S9S_MB_2U_LIB.S9S_MB_2U(SCH_1):M_D_CPU1_SA_DQS_DP<7>
  168  M_D_CPU1_SA_DQS_DP<6>  DQS6_A_P  @S9S_MB_2U_LIB.S9S_MB_2U(SCH_1):M_D_CPU1_SA_DQS_DP<6>
  157  M_D_CPU1_SA_DQS_DP<5>  DQS5_A_P  @S9S_MB_2U_LIB.S9S_MB_2U(SCH_1):M_D_CPU1_SA_DQS_DP<5>
   55  M_D_CPU1_SA_DQS_DP<4>  DQS4_A_P  @S9S_MB_2U_LIB.S9S_MB_2U(SCH_1):M_D_CPU1_SA_DQS_DP<4>
   44  M_D_CPU1_SA_DQS_DP<3>  DQS3_A_P  @S9S_MB_2U_LIB.S9S_MB_2U(SCH_1):M_D_CPU1_SA_DQS_DP<3>
   33  M_D_CPU1_SA_DQS_DP<2>  DQS2_A_P  @S9S_MB_2U_LIB.S9S_MB_2U(SCH_1):M_D_CPU1_SA_DQS_DP<2>
   22  M_D_CPU1_SA_DQS_DP<1>  DQS1_A_P  @S9S_MB_2U_LIB.S9S_MB_2U(SCH_1):M_D_CPU1_SA_DQS_DP<1>
   11  M_D_CPU1_SA_DQS_DP<0>  DQS0_A_P  @S9S_MB_2U_LIB.S9S_MB_2U(SCH_1):M_D_CPU1_SA_DQS_DP<0>
  200  M_D_CPU1_SA_DQS_DN<9>  DQS9_A_N  @S9S_MB_2U_LIB.S9S_MB_2U(SCH_1):M_D_CPU1_SA_DQS_DN<9>
  189  M_D_CPU1_SA_DQS_DN<8>  DQS8_A_N  @S9S_MB_2U_LIB.S9S_MB_2U(SCH_1):M_D_CPU1_SA_DQS_DN<8>
  178  M_D_CPU1_SA_DQS_DN<7>  DQS7_A_N  @S9S_MB_2U_LIB.S9S_MB_2U(SCH_1):M_D_CPU1_SA_DQS_DN<7>
  167  M_D_CPU1_SA_DQS_DN<6>  DQS6_A_N  @S9S_MB_2U_LIB.S9S_MB_2U(SCH_1):M_D_CPU1_SA_DQS_DN<6>
  156  M_D_CPU1_SA_DQS_DN<5>  DQS5_A_N  @S9S_MB_2U_LIB.S9S_MB_2U(SCH_1):M_D_CPU1_SA_DQS_DN<5>
   56  M_D_CPU1_SA_DQS_DN<4>  DQS4_A_N  @S9S_MB_2U_LIB.S9S_MB_2U(SCH_1):M_D_CPU1_SA_DQS_DN<4>
   45  M_D_CPU1_SA_DQS_DN<3>  DQS3_A_N  @S9S_MB_2U_LIB.S9S_MB_2U(SCH_1):M_D_CPU1_SA_DQS_DN<3>
   34  M_D_CPU1_SA_DQS_DN<2>  DQS2_A_N  @S9S_MB_2U_LIB.S9S_MB_2U(SCH_1):M_D_CPU1_SA_DQS_DN<2>
   23  M_D_CPU1_SA_DQS_DN<1>  DQS1_A_N  @S9S_MB_2U_LIB.S9S_MB_2U(SCH_1):M_D_CPU1_SA_DQS_DN<1>
   12  M_D_CPU1_SA_DQS_DN<0>  DQS0_A_N  @S9S_MB_2U_LIB.S9S_MB_2U(SCH_1):M_D_CPU1_SA_DQS_DN<0>

SCONN288_ADR50001P003C01  I178  J24    [SCONN288_ADR50001P003C01-SCONNA]
  232  NC              RFU6  NC
  231  NC              RFU5  NC
  220  NC              RFU4  NC
  150  NC              RFU3  NC
  149  NC              RFU2  NC
  144  NC              RFU1  NC
    2  NC              RFU0  NC
  207  RST_M_CD_CPU1_FPGA_N  RESET_N  @S9S_MB_2U_LIB.S9S_MB_2U(SCH_1):RST_M_CD_CPU1_FPGA_N
  147  PWRGD_CHD_CPU1_DIMM2  PWR_GOOD||FAIL_N  @S9S_MB_2U_LIB.S9S_MB_2U(SCH_1):PWRGD_CHD_CPU1_DIMM2
  148  PD_CHD_CPU1_DIMM2_SAA    HAS  @S9S_MB_2U_LIB.S9S_MB_2U(SCH_1):PD_CHD_CPU1_DIMM2_SAA
    3  P3V3_AUX       VIN_MGMT  @S9S_MB_2U_LIB.S9S_MB_2U(SCH_1):P3V3_AUX
   87  M_D_CPU1_SB_RSP<1>  LBS||RSP_N_B  @S9S_MB_2U_LIB.S9S_MB_2U(SCH_1):M_D_CPU1_SB_RSP<1>
  227  M_D_CPU1_SB_PAR  PAR_B  @S9S_MB_2U_LIB.S9S_MB_2U(SCH_1):M_D_CPU1_SB_PAR
  113  M_D_CPU1_SB_DQ<9>  DQ_B9  @S9S_MB_2U_LIB.S9S_MB_2U(SCH_1):M_D_CPU1_SB_DQ<9>
  111  M_D_CPU1_SB_DQ<8>  DQ_B8  @S9S_MB_2U_LIB.S9S_MB_2U(SCH_1):M_D_CPU1_SB_DQ<8>
  254  M_D_CPU1_SB_DQ<7>  DQ_B7  @S9S_MB_2U_LIB.S9S_MB_2U(SCH_1):M_D_CPU1_SB_DQ<7>
  252  M_D_CPU1_SB_DQ<6>  DQ_B6  @S9S_MB_2U_LIB.S9S_MB_2U(SCH_1):M_D_CPU1_SB_DQ<6>
  109  M_D_CPU1_SB_DQ<5>  DQ_B5  @S9S_MB_2U_LIB.S9S_MB_2U(SCH_1):M_D_CPU1_SB_DQ<5>
  107  M_D_CPU1_SB_DQ<4>  DQ_B4  @S9S_MB_2U_LIB.S9S_MB_2U(SCH_1):M_D_CPU1_SB_DQ<4>
  247  M_D_CPU1_SB_DQ<3>  DQ_B3  @S9S_MB_2U_LIB.S9S_MB_2U(SCH_1):M_D_CPU1_SB_DQ<3>
  287  M_D_CPU1_SB_DQ<31>  DQ_B31  @S9S_MB_2U_LIB.S9S_MB_2U(SCH_1):M_D_CPU1_SB_DQ<31>
  285  M_D_CPU1_SB_DQ<30>  DQ_B30  @S9S_MB_2U_LIB.S9S_MB_2U(SCH_1):M_D_CPU1_SB_DQ<30>
  245  M_D_CPU1_SB_DQ<2>  DQ_B2  @S9S_MB_2U_LIB.S9S_MB_2U(SCH_1):M_D_CPU1_SB_DQ<2>
  142  M_D_CPU1_SB_DQ<29>  DQ_B29  @S9S_MB_2U_LIB.S9S_MB_2U(SCH_1):M_D_CPU1_SB_DQ<29>
  140  M_D_CPU1_SB_DQ<28>  DQ_B28  @S9S_MB_2U_LIB.S9S_MB_2U(SCH_1):M_D_CPU1_SB_DQ<28>
  280  M_D_CPU1_SB_DQ<27>  DQ_B27  @S9S_MB_2U_LIB.S9S_MB_2U(SCH_1):M_D_CPU1_SB_DQ<27>
  278  M_D_CPU1_SB_DQ<26>  DQ_B26  @S9S_MB_2U_LIB.S9S_MB_2U(SCH_1):M_D_CPU1_SB_DQ<26>
  135  M_D_CPU1_SB_DQ<25>  DQ_B25  @S9S_MB_2U_LIB.S9S_MB_2U(SCH_1):M_D_CPU1_SB_DQ<25>
  133  M_D_CPU1_SB_DQ<24>  DQ_B24  @S9S_MB_2U_LIB.S9S_MB_2U(SCH_1):M_D_CPU1_SB_DQ<24>
  276  M_D_CPU1_SB_DQ<23>  DQ_B23  @S9S_MB_2U_LIB.S9S_MB_2U(SCH_1):M_D_CPU1_SB_DQ<23>
  274  M_D_CPU1_SB_DQ<22>  DQ_B22  @S9S_MB_2U_LIB.S9S_MB_2U(SCH_1):M_D_CPU1_SB_DQ<22>
  131  M_D_CPU1_SB_DQ<21>  DQ_B21  @S9S_MB_2U_LIB.S9S_MB_2U(SCH_1):M_D_CPU1_SB_DQ<21>
  129  M_D_CPU1_SB_DQ<20>  DQ_B20  @S9S_MB_2U_LIB.S9S_MB_2U(SCH_1):M_D_CPU1_SB_DQ<20>
  102  M_D_CPU1_SB_DQ<1>  DQ_B1  @S9S_MB_2U_LIB.S9S_MB_2U(SCH_1):M_D_CPU1_SB_DQ<1>
  269  M_D_CPU1_SB_DQ<19>  DQ_B19  @S9S_MB_2U_LIB.S9S_MB_2U(SCH_1):M_D_CPU1_SB_DQ<19>
  267  M_D_CPU1_SB_DQ<18>  DQ_B18  @S9S_MB_2U_LIB.S9S_MB_2U(SCH_1):M_D_CPU1_SB_DQ<18>
  124  M_D_CPU1_SB_DQ<17>  DQ_B17  @S9S_MB_2U_LIB.S9S_MB_2U(SCH_1):M_D_CPU1_SB_DQ<17>
  122  M_D_CPU1_SB_DQ<16>  DQ_B16  @S9S_MB_2U_LIB.S9S_MB_2U(SCH_1):M_D_CPU1_SB_DQ<16>
  265  M_D_CPU1_SB_DQ<15>  DQ_B15  @S9S_MB_2U_LIB.S9S_MB_2U(SCH_1):M_D_CPU1_SB_DQ<15>
  263  M_D_CPU1_SB_DQ<14>  DQ_B14  @S9S_MB_2U_LIB.S9S_MB_2U(SCH_1):M_D_CPU1_SB_DQ<14>
  120  M_D_CPU1_SB_DQ<13>  DQ_B13  @S9S_MB_2U_LIB.S9S_MB_2U(SCH_1):M_D_CPU1_SB_DQ<13>
  118  M_D_CPU1_SB_DQ<12>  DQ_B12  @S9S_MB_2U_LIB.S9S_MB_2U(SCH_1):M_D_CPU1_SB_DQ<12>
  258  M_D_CPU1_SB_DQ<11>  DQ_B11  @S9S_MB_2U_LIB.S9S_MB_2U(SCH_1):M_D_CPU1_SB_DQ<11>
  256  M_D_CPU1_SB_DQ<10>  DQ_B10  @S9S_MB_2U_LIB.S9S_MB_2U(SCH_1):M_D_CPU1_SB_DQ<10>
  100  M_D_CPU1_SB_DQ<0>  DQ_B0  @S9S_MB_2U_LIB.S9S_MB_2U(SCH_1):M_D_CPU1_SB_DQ<0>
  229  M_D_CPU1_SB_CS_N<3>  CS1_N_B  @S9S_MB_2U_LIB.S9S_MB_2U(SCH_1):M_D_CPU1_SB_CS_N<3>
   84  M_D_CPU1_SB_CS_N<2>  CS0_N_B  @S9S_MB_2U_LIB.S9S_MB_2U(SCH_1):M_D_CPU1_SB_CS_N<2>
  236  M_D_CPU1_SB_CB<7>  CB_B7  @S9S_MB_2U_LIB.S9S_MB_2U(SCH_1):M_D_CPU1_SB_CB<7>
  234  M_D_CPU1_SB_CB<6>  CB_B6  @S9S_MB_2U_LIB.S9S_MB_2U(SCH_1):M_D_CPU1_SB_CB<6>
   91  M_D_CPU1_SB_CB<5>  CB_B5  @S9S_MB_2U_LIB.S9S_MB_2U(SCH_1):M_D_CPU1_SB_CB<5>
   89  M_D_CPU1_SB_CB<4>  CB_B4  @S9S_MB_2U_LIB.S9S_MB_2U(SCH_1):M_D_CPU1_SB_CB<4>
  243  M_D_CPU1_SB_CB<3>  CB_B3  @S9S_MB_2U_LIB.S9S_MB_2U(SCH_1):M_D_CPU1_SB_CB<3>
  241  M_D_CPU1_SB_CB<2>  CB_B2  @S9S_MB_2U_LIB.S9S_MB_2U(SCH_1):M_D_CPU1_SB_CB<2>
   98  M_D_CPU1_SB_CB<1>  CB_B1  @S9S_MB_2U_LIB.S9S_MB_2U(SCH_1):M_D_CPU1_SB_CB<1>
   96  M_D_CPU1_SB_CB<0>  CB_B0  @S9S_MB_2U_LIB.S9S_MB_2U(SCH_1):M_D_CPU1_SB_CB<0>
   82  M_D_CPU1_SB_CA<6>  CA6_B  @S9S_MB_2U_LIB.S9S_MB_2U(SCH_1):M_D_CPU1_SB_CA<6>
  225  M_D_CPU1_SB_CA<5>  CA5_B  @S9S_MB_2U_LIB.S9S_MB_2U(SCH_1):M_D_CPU1_SB_CA<5>
   80  M_D_CPU1_SB_CA<4>  CA4_B  @S9S_MB_2U_LIB.S9S_MB_2U(SCH_1):M_D_CPU1_SB_CA<4>
  223  M_D_CPU1_SB_CA<3>  CA3_B  @S9S_MB_2U_LIB.S9S_MB_2U(SCH_1):M_D_CPU1_SB_CA<3>
   78  M_D_CPU1_SB_CA<2>  CA2_B  @S9S_MB_2U_LIB.S9S_MB_2U(SCH_1):M_D_CPU1_SB_CA<2>
  221  M_D_CPU1_SB_CA<1>  CA1_B  @S9S_MB_2U_LIB.S9S_MB_2U(SCH_1):M_D_CPU1_SB_CA<1>
   76  M_D_CPU1_SB_CA<0>  CA0_B  @S9S_MB_2U_LIB.S9S_MB_2U(SCH_1):M_D_CPU1_SB_CA<0>
   86  M_D_CPU1_SA_RSP<1>  LBD||RSP_N_A  @S9S_MB_2U_LIB.S9S_MB_2U(SCH_1):M_D_CPU1_SA_RSP<1>
   74  M_D_CPU1_SA_PAR  PAR_A  @S9S_MB_2U_LIB.S9S_MB_2U(SCH_1):M_D_CPU1_SA_PAR
   20  M_D_CPU1_SA_DQ<9>  DQ_A9  @S9S_MB_2U_LIB.S9S_MB_2U(SCH_1):M_D_CPU1_SA_DQ<9>
   18  M_D_CPU1_SA_DQ<8>  DQ_A8  @S9S_MB_2U_LIB.S9S_MB_2U(SCH_1):M_D_CPU1_SA_DQ<8>
  161  M_D_CPU1_SA_DQ<7>  DQ_A7  @S9S_MB_2U_LIB.S9S_MB_2U(SCH_1):M_D_CPU1_SA_DQ<7>
  159  M_D_CPU1_SA_DQ<6>  DQ_A6  @S9S_MB_2U_LIB.S9S_MB_2U(SCH_1):M_D_CPU1_SA_DQ<6>
   16  M_D_CPU1_SA_DQ<5>  DQ_A5  @S9S_MB_2U_LIB.S9S_MB_2U(SCH_1):M_D_CPU1_SA_DQ<5>
   14  M_D_CPU1_SA_DQ<4>  DQ_A4  @S9S_MB_2U_LIB.S9S_MB_2U(SCH_1):M_D_CPU1_SA_DQ<4>
  154  M_D_CPU1_SA_DQ<3>  DQ_A3  @S9S_MB_2U_LIB.S9S_MB_2U(SCH_1):M_D_CPU1_SA_DQ<3>
  194  M_D_CPU1_SA_DQ<31>  DQ_A31  @S9S_MB_2U_LIB.S9S_MB_2U(SCH_1):M_D_CPU1_SA_DQ<31>
  192  M_D_CPU1_SA_DQ<30>  DQ_A30  @S9S_MB_2U_LIB.S9S_MB_2U(SCH_1):M_D_CPU1_SA_DQ<30>
  152  M_D_CPU1_SA_DQ<2>  DQ_A2  @S9S_MB_2U_LIB.S9S_MB_2U(SCH_1):M_D_CPU1_SA_DQ<2>
   49  M_D_CPU1_SA_DQ<29>  DQ_A29  @S9S_MB_2U_LIB.S9S_MB_2U(SCH_1):M_D_CPU1_SA_DQ<29>
   47  M_D_CPU1_SA_DQ<28>  DQ_A28  @S9S_MB_2U_LIB.S9S_MB_2U(SCH_1):M_D_CPU1_SA_DQ<28>
  187  M_D_CPU1_SA_DQ<27>  DQ_A27  @S9S_MB_2U_LIB.S9S_MB_2U(SCH_1):M_D_CPU1_SA_DQ<27>
  185  M_D_CPU1_SA_DQ<26>  DQ_A26  @S9S_MB_2U_LIB.S9S_MB_2U(SCH_1):M_D_CPU1_SA_DQ<26>
   42  M_D_CPU1_SA_DQ<25>  DQ_A25  @S9S_MB_2U_LIB.S9S_MB_2U(SCH_1):M_D_CPU1_SA_DQ<25>
   40  M_D_CPU1_SA_DQ<24>  DQ_A24  @S9S_MB_2U_LIB.S9S_MB_2U(SCH_1):M_D_CPU1_SA_DQ<24>
  183  M_D_CPU1_SA_DQ<23>  DQ_A23  @S9S_MB_2U_LIB.S9S_MB_2U(SCH_1):M_D_CPU1_SA_DQ<23>
  181  M_D_CPU1_SA_DQ<22>  DQ_A22  @S9S_MB_2U_LIB.S9S_MB_2U(SCH_1):M_D_CPU1_SA_DQ<22>
   38  M_D_CPU1_SA_DQ<21>  DQ_A21  @S9S_MB_2U_LIB.S9S_MB_2U(SCH_1):M_D_CPU1_SA_DQ<21>
   36  M_D_CPU1_SA_DQ<20>  DQ_A20  @S9S_MB_2U_LIB.S9S_MB_2U(SCH_1):M_D_CPU1_SA_DQ<20>
    9  M_D_CPU1_SA_DQ<1>  DQ_A1  @S9S_MB_2U_LIB.S9S_MB_2U(SCH_1):M_D_CPU1_SA_DQ<1>
  176  M_D_CPU1_SA_DQ<19>  DQ_A19  @S9S_MB_2U_LIB.S9S_MB_2U(SCH_1):M_D_CPU1_SA_DQ<19>
  174  M_D_CPU1_SA_DQ<18>  DQ_A18  @S9S_MB_2U_LIB.S9S_MB_2U(SCH_1):M_D_CPU1_SA_DQ<18>
   31  M_D_CPU1_SA_DQ<17>  DQ_A17  @S9S_MB_2U_LIB.S9S_MB_2U(SCH_1):M_D_CPU1_SA_DQ<17>
   29  M_D_CPU1_SA_DQ<16>  DQ_A16  @S9S_MB_2U_LIB.S9S_MB_2U(SCH_1):M_D_CPU1_SA_DQ<16>
  172  M_D_CPU1_SA_DQ<15>  DQ_A15  @S9S_MB_2U_LIB.S9S_MB_2U(SCH_1):M_D_CPU1_SA_DQ<15>
  170  M_D_CPU1_SA_DQ<14>  DQ_A14  @S9S_MB_2U_LIB.S9S_MB_2U(SCH_1):M_D_CPU1_SA_DQ<14>
   27  M_D_CPU1_SA_DQ<13>  DQ_A13  @S9S_MB_2U_LIB.S9S_MB_2U(SCH_1):M_D_CPU1_SA_DQ<13>
   25  M_D_CPU1_SA_DQ<12>  DQ_A12  @S9S_MB_2U_LIB.S9S_MB_2U(SCH_1):M_D_CPU1_SA_DQ<12>
  165  M_D_CPU1_SA_DQ<11>  DQ_A11  @S9S_MB_2U_LIB.S9S_MB_2U(SCH_1):M_D_CPU1_SA_DQ<11>
  163  M_D_CPU1_SA_DQ<10>  DQ_A10  @S9S_MB_2U_LIB.S9S_MB_2U(SCH_1):M_D_CPU1_SA_DQ<10>
    7  M_D_CPU1_SA_DQ<0>  DQ_A0  @S9S_MB_2U_LIB.S9S_MB_2U(SCH_1):M_D_CPU1_SA_DQ<0>
  209  M_D_CPU1_SA_CS_N<3>  CS1_N_A  @S9S_MB_2U_LIB.S9S_MB_2U(SCH_1):M_D_CPU1_SA_CS_N<3>
   64  M_D_CPU1_SA_CS_N<2>  CS0_N_A  @S9S_MB_2U_LIB.S9S_MB_2U(SCH_1):M_D_CPU1_SA_CS_N<2>
  205  M_D_CPU1_SA_CB<7>  CB_A7  @S9S_MB_2U_LIB.S9S_MB_2U(SCH_1):M_D_CPU1_SA_CB<7>
  203  M_D_CPU1_SA_CB<6>  CB_A6  @S9S_MB_2U_LIB.S9S_MB_2U(SCH_1):M_D_CPU1_SA_CB<6>
   60  M_D_CPU1_SA_CB<5>  CB_A5  @S9S_MB_2U_LIB.S9S_MB_2U(SCH_1):M_D_CPU1_SA_CB<5>
   58  M_D_CPU1_SA_CB<4>  CB_A4  @S9S_MB_2U_LIB.S9S_MB_2U(SCH_1):M_D_CPU1_SA_CB<4>
  198  M_D_CPU1_SA_CB<3>  CB_A3  @S9S_MB_2U_LIB.S9S_MB_2U(SCH_1):M_D_CPU1_SA_CB<3>
  196  M_D_CPU1_SA_CB<2>  CB_A2  @S9S_MB_2U_LIB.S9S_MB_2U(SCH_1):M_D_CPU1_SA_CB<2>
   53  M_D_CPU1_SA_CB<1>  CB_A1  @S9S_MB_2U_LIB.S9S_MB_2U(SCH_1):M_D_CPU1_SA_CB<1>
   51  M_D_CPU1_SA_CB<0>  CB_A0  @S9S_MB_2U_LIB.S9S_MB_2U(SCH_1):M_D_CPU1_SA_CB<0>
   72  M_D_CPU1_SA_CA<6>  CA6_A  @S9S_MB_2U_LIB.S9S_MB_2U(SCH_1):M_D_CPU1_SA_CA<6>
  215  M_D_CPU1_SA_CA<5>  CA5_A  @S9S_MB_2U_LIB.S9S_MB_2U(SCH_1):M_D_CPU1_SA_CA<5>
   70  M_D_CPU1_SA_CA<4>  CA4_A  @S9S_MB_2U_LIB.S9S_MB_2U(SCH_1):M_D_CPU1_SA_CA<4>
  213  M_D_CPU1_SA_CA<3>  CA3_A  @S9S_MB_2U_LIB.S9S_MB_2U(SCH_1):M_D_CPU1_SA_CA<3>
   68  M_D_CPU1_SA_CA<2>  CA2_A  @S9S_MB_2U_LIB.S9S_MB_2U(SCH_1):M_D_CPU1_SA_CA<2>
  211  M_D_CPU1_SA_CA<1>  CA1_A  @S9S_MB_2U_LIB.S9S_MB_2U(SCH_1):M_D_CPU1_SA_CA<1>
   66  M_D_CPU1_SA_CA<0>  CA0_A  @S9S_MB_2U_LIB.S9S_MB_2U(SCH_1):M_D_CPU1_SA_CA<0>
  217  M_D_CPU1_CLK_DP<1>   CK_P  @S9S_MB_2U_LIB.S9S_MB_2U(SCH_1):M_D_CPU1_CLK_DP<1>
  218  M_D_CPU1_CLK_DN<1>   CK_N  @S9S_MB_2U_LIB.S9S_MB_2U(SCH_1):M_D_CPU1_CLK_DN<1>
   62  M_D_CPU1_ALERT_N  ALERT_N  @S9S_MB_2U_LIB.S9S_MB_2U(SCH_1):M_D_CPU1_ALERT_N
    5  I3C_SPD_DDRABCD_CPU1_LVC1_SDA   HSDA  @S9S_MB_2U_LIB.S9S_MB_2U(SCH_1):I3C_SPD_DDRABCD_CPU1_LVC1_SDA
    4  I3C_SPD_DDRABCD_CPU1_LVC1_SCL   HSCL  @S9S_MB_2U_LIB.S9S_MB_2U(SCH_1):I3C_SPD_DDRABCD_CPU1_LVC1_SCL

SCONN288_ADR50001P013C01  I178  J25    [SCONN288_ADR50001P013C01-SCONNA]
  146  P12V_S3_AUX_CPU1_NVDIMM  VIN_BULK2  @S9S_MB_2U_LIB.S9S_MB_2U(SCH_1):P12V_S3_AUX_CPU1_NVDIMM
  145  P12V_S3_AUX_CPU1_NVDIMM  VIN_BULK1  @S9S_MB_2U_LIB.S9S_MB_2U(SCH_1):P12V_S3_AUX_CPU1_NVDIMM
    1  P12V_S3_AUX_CPU1_NVDIMM  VIN_BULK0  @S9S_MB_2U_LIB.S9S_MB_2U(SCH_1):P12V_S3_AUX_CPU1_NVDIMM
  288  GND            VSS126  @S9S_MB_2U_LIB.S9S_MB_2U(SCH_1):GND
  286  GND            VSS125  @S9S_MB_2U_LIB.S9S_MB_2U(SCH_1):GND
  284  GND            VSS124  @S9S_MB_2U_LIB.S9S_MB_2U(SCH_1):GND
  281  GND            VSS123  @S9S_MB_2U_LIB.S9S_MB_2U(SCH_1):GND
  279  GND            VSS122  @S9S_MB_2U_LIB.S9S_MB_2U(SCH_1):GND
  277  GND            VSS121  @S9S_MB_2U_LIB.S9S_MB_2U(SCH_1):GND
  275  GND            VSS120  @S9S_MB_2U_LIB.S9S_MB_2U(SCH_1):GND
  273  GND            VSS119  @S9S_MB_2U_LIB.S9S_MB_2U(SCH_1):GND
  270  GND            VSS118  @S9S_MB_2U_LIB.S9S_MB_2U(SCH_1):GND
  268  GND            VSS117  @S9S_MB_2U_LIB.S9S_MB_2U(SCH_1):GND
  266  GND            VSS116  @S9S_MB_2U_LIB.S9S_MB_2U(SCH_1):GND
  264  GND            VSS115  @S9S_MB_2U_LIB.S9S_MB_2U(SCH_1):GND
  262  GND            VSS114  @S9S_MB_2U_LIB.S9S_MB_2U(SCH_1):GND
  259  GND            VSS113  @S9S_MB_2U_LIB.S9S_MB_2U(SCH_1):GND
  257  GND            VSS112  @S9S_MB_2U_LIB.S9S_MB_2U(SCH_1):GND
  255  GND            VSS111  @S9S_MB_2U_LIB.S9S_MB_2U(SCH_1):GND
  253  GND            VSS110  @S9S_MB_2U_LIB.S9S_MB_2U(SCH_1):GND
  251  GND            VSS109  @S9S_MB_2U_LIB.S9S_MB_2U(SCH_1):GND
  248  GND            VSS108  @S9S_MB_2U_LIB.S9S_MB_2U(SCH_1):GND
  246  GND            VSS107  @S9S_MB_2U_LIB.S9S_MB_2U(SCH_1):GND
  244  GND            VSS106  @S9S_MB_2U_LIB.S9S_MB_2U(SCH_1):GND
  242  GND            VSS105  @S9S_MB_2U_LIB.S9S_MB_2U(SCH_1):GND
  240  GND            VSS104  @S9S_MB_2U_LIB.S9S_MB_2U(SCH_1):GND
  237  GND            VSS103  @S9S_MB_2U_LIB.S9S_MB_2U(SCH_1):GND
  235  GND            VSS102  @S9S_MB_2U_LIB.S9S_MB_2U(SCH_1):GND
  233  GND            VSS101  @S9S_MB_2U_LIB.S9S_MB_2U(SCH_1):GND
  230  GND            VSS100  @S9S_MB_2U_LIB.S9S_MB_2U(SCH_1):GND
  228  GND            VSS99  @S9S_MB_2U_LIB.S9S_MB_2U(SCH_1):GND
  226  GND            VSS98  @S9S_MB_2U_LIB.S9S_MB_2U(SCH_1):GND
  224  GND            VSS97  @S9S_MB_2U_LIB.S9S_MB_2U(SCH_1):GND
  222  GND            VSS96  @S9S_MB_2U_LIB.S9S_MB_2U(SCH_1):GND
  219  GND            VSS95  @S9S_MB_2U_LIB.S9S_MB_2U(SCH_1):GND
  216  GND            VSS94  @S9S_MB_2U_LIB.S9S_MB_2U(SCH_1):GND
  214  GND            VSS93  @S9S_MB_2U_LIB.S9S_MB_2U(SCH_1):GND
  212  GND            VSS92  @S9S_MB_2U_LIB.S9S_MB_2U(SCH_1):GND
  210  GND            VSS91  @S9S_MB_2U_LIB.S9S_MB_2U(SCH_1):GND
  208  GND            VSS90  @S9S_MB_2U_LIB.S9S_MB_2U(SCH_1):GND
  206  GND            VSS89  @S9S_MB_2U_LIB.S9S_MB_2U(SCH_1):GND
  204  GND            VSS88  @S9S_MB_2U_LIB.S9S_MB_2U(SCH_1):GND
  202  GND            VSS87  @S9S_MB_2U_LIB.S9S_MB_2U(SCH_1):GND
  199  GND            VSS86  @S9S_MB_2U_LIB.S9S_MB_2U(SCH_1):GND
  197  GND            VSS85  @S9S_MB_2U_LIB.S9S_MB_2U(SCH_1):GND
  195  GND            VSS84  @S9S_MB_2U_LIB.S9S_MB_2U(SCH_1):GND
  193  GND            VSS83  @S9S_MB_2U_LIB.S9S_MB_2U(SCH_1):GND
  191  GND            VSS82  @S9S_MB_2U_LIB.S9S_MB_2U(SCH_1):GND
  188  GND            VSS81  @S9S_MB_2U_LIB.S9S_MB_2U(SCH_1):GND
  186  GND            VSS80  @S9S_MB_2U_LIB.S9S_MB_2U(SCH_1):GND
  184  GND            VSS79  @S9S_MB_2U_LIB.S9S_MB_2U(SCH_1):GND
  182  GND            VSS78  @S9S_MB_2U_LIB.S9S_MB_2U(SCH_1):GND
  180  GND            VSS77  @S9S_MB_2U_LIB.S9S_MB_2U(SCH_1):GND
  177  GND            VSS76  @S9S_MB_2U_LIB.S9S_MB_2U(SCH_1):GND
  175  GND            VSS75  @S9S_MB_2U_LIB.S9S_MB_2U(SCH_1):GND
  173  GND            VSS74  @S9S_MB_2U_LIB.S9S_MB_2U(SCH_1):GND
  171  GND            VSS73  @S9S_MB_2U_LIB.S9S_MB_2U(SCH_1):GND
  169  GND            VSS72  @S9S_MB_2U_LIB.S9S_MB_2U(SCH_1):GND
  166  GND            VSS71  @S9S_MB_2U_LIB.S9S_MB_2U(SCH_1):GND
  164  GND            VSS70  @S9S_MB_2U_LIB.S9S_MB_2U(SCH_1):GND
  162  GND            VSS69  @S9S_MB_2U_LIB.S9S_MB_2U(SCH_1):GND
  160  GND            VSS68  @S9S_MB_2U_LIB.S9S_MB_2U(SCH_1):GND
  158  GND            VSS67  @S9S_MB_2U_LIB.S9S_MB_2U(SCH_1):GND
  155  GND            VSS66  @S9S_MB_2U_LIB.S9S_MB_2U(SCH_1):GND
  153  GND            VSS65  @S9S_MB_2U_LIB.S9S_MB_2U(SCH_1):GND
  151  GND            VSS64  @S9S_MB_2U_LIB.S9S_MB_2U(SCH_1):GND
  143  GND            VSS63  @S9S_MB_2U_LIB.S9S_MB_2U(SCH_1):GND
  141  GND            VSS62  @S9S_MB_2U_LIB.S9S_MB_2U(SCH_1):GND
  139  GND            VSS61  @S9S_MB_2U_LIB.S9S_MB_2U(SCH_1):GND
  136  GND            VSS60  @S9S_MB_2U_LIB.S9S_MB_2U(SCH_1):GND
  134  GND            VSS59  @S9S_MB_2U_LIB.S9S_MB_2U(SCH_1):GND
  132  GND            VSS58  @S9S_MB_2U_LIB.S9S_MB_2U(SCH_1):GND
  130  GND            VSS57  @S9S_MB_2U_LIB.S9S_MB_2U(SCH_1):GND
  128  GND            VSS56  @S9S_MB_2U_LIB.S9S_MB_2U(SCH_1):GND
  125  GND            VSS55  @S9S_MB_2U_LIB.S9S_MB_2U(SCH_1):GND
  123  GND            VSS54  @S9S_MB_2U_LIB.S9S_MB_2U(SCH_1):GND
  121  GND            VSS53  @S9S_MB_2U_LIB.S9S_MB_2U(SCH_1):GND
  119  GND            VSS52  @S9S_MB_2U_LIB.S9S_MB_2U(SCH_1):GND
  117  GND            VSS51  @S9S_MB_2U_LIB.S9S_MB_2U(SCH_1):GND
  114  GND            VSS50  @S9S_MB_2U_LIB.S9S_MB_2U(SCH_1):GND
  112  GND            VSS49  @S9S_MB_2U_LIB.S9S_MB_2U(SCH_1):GND
  110  GND            VSS48  @S9S_MB_2U_LIB.S9S_MB_2U(SCH_1):GND
  108  GND            VSS47  @S9S_MB_2U_LIB.S9S_MB_2U(SCH_1):GND
  106  GND            VSS46  @S9S_MB_2U_LIB.S9S_MB_2U(SCH_1):GND
  103  GND            VSS45  @S9S_MB_2U_LIB.S9S_MB_2U(SCH_1):GND
  101  GND            VSS44  @S9S_MB_2U_LIB.S9S_MB_2U(SCH_1):GND
   99  GND            VSS43  @S9S_MB_2U_LIB.S9S_MB_2U(SCH_1):GND
   97  GND            VSS42  @S9S_MB_2U_LIB.S9S_MB_2U(SCH_1):GND
   95  GND            VSS41  @S9S_MB_2U_LIB.S9S_MB_2U(SCH_1):GND
   92  GND            VSS40  @S9S_MB_2U_LIB.S9S_MB_2U(SCH_1):GND
   90  GND            VSS39  @S9S_MB_2U_LIB.S9S_MB_2U(SCH_1):GND
   88  GND            VSS38  @S9S_MB_2U_LIB.S9S_MB_2U(SCH_1):GND
   85  GND            VSS37  @S9S_MB_2U_LIB.S9S_MB_2U(SCH_1):GND
   83  GND            VSS36  @S9S_MB_2U_LIB.S9S_MB_2U(SCH_1):GND
   81  GND            VSS35  @S9S_MB_2U_LIB.S9S_MB_2U(SCH_1):GND
   79  GND            VSS34  @S9S_MB_2U_LIB.S9S_MB_2U(SCH_1):GND
   77  GND            VSS33  @S9S_MB_2U_LIB.S9S_MB_2U(SCH_1):GND
   75  GND            VSS32  @S9S_MB_2U_LIB.S9S_MB_2U(SCH_1):GND
   73  GND            VSS31  @S9S_MB_2U_LIB.S9S_MB_2U(SCH_1):GND
   71  GND            VSS30  @S9S_MB_2U_LIB.S9S_MB_2U(SCH_1):GND
   69  GND            VSS29  @S9S_MB_2U_LIB.S9S_MB_2U(SCH_1):GND
   67  GND            VSS28  @S9S_MB_2U_LIB.S9S_MB_2U(SCH_1):GND
   65  GND            VSS27  @S9S_MB_2U_LIB.S9S_MB_2U(SCH_1):GND
   63  GND            VSS26  @S9S_MB_2U_LIB.S9S_MB_2U(SCH_1):GND
   61  GND            VSS25  @S9S_MB_2U_LIB.S9S_MB_2U(SCH_1):GND
   59  GND            VSS24  @S9S_MB_2U_LIB.S9S_MB_2U(SCH_1):GND
   57  GND            VSS23  @S9S_MB_2U_LIB.S9S_MB_2U(SCH_1):GND
   54  GND            VSS22  @S9S_MB_2U_LIB.S9S_MB_2U(SCH_1):GND
   52  GND            VSS21  @S9S_MB_2U_LIB.S9S_MB_2U(SCH_1):GND
   50  GND            VSS20  @S9S_MB_2U_LIB.S9S_MB_2U(SCH_1):GND
   48  GND            VSS19  @S9S_MB_2U_LIB.S9S_MB_2U(SCH_1):GND
   46  GND            VSS18  @S9S_MB_2U_LIB.S9S_MB_2U(SCH_1):GND
   43  GND            VSS17  @S9S_MB_2U_LIB.S9S_MB_2U(SCH_1):GND
   41  GND            VSS16  @S9S_MB_2U_LIB.S9S_MB_2U(SCH_1):GND
   39  GND            VSS15  @S9S_MB_2U_LIB.S9S_MB_2U(SCH_1):GND
   37  GND            VSS14  @S9S_MB_2U_LIB.S9S_MB_2U(SCH_1):GND
   35  GND            VSS13  @S9S_MB_2U_LIB.S9S_MB_2U(SCH_1):GND
   32  GND            VSS12  @S9S_MB_2U_LIB.S9S_MB_2U(SCH_1):GND
   30  GND            VSS11  @S9S_MB_2U_LIB.S9S_MB_2U(SCH_1):GND
   28  GND            VSS10  @S9S_MB_2U_LIB.S9S_MB_2U(SCH_1):GND
   26  GND             VSS9  @S9S_MB_2U_LIB.S9S_MB_2U(SCH_1):GND
   24  GND             VSS8  @S9S_MB_2U_LIB.S9S_MB_2U(SCH_1):GND
   21  GND             VSS7  @S9S_MB_2U_LIB.S9S_MB_2U(SCH_1):GND
   19  GND             VSS6  @S9S_MB_2U_LIB.S9S_MB_2U(SCH_1):GND
   17  GND             VSS5  @S9S_MB_2U_LIB.S9S_MB_2U(SCH_1):GND
   15  GND             VSS4  @S9S_MB_2U_LIB.S9S_MB_2U(SCH_1):GND
   13  GND             VSS3  @S9S_MB_2U_LIB.S9S_MB_2U(SCH_1):GND
   10  GND             VSS2  @S9S_MB_2U_LIB.S9S_MB_2U(SCH_1):GND
    8  GND             VSS1  @S9S_MB_2U_LIB.S9S_MB_2U(SCH_1):GND
    6  GND             VSS0  @S9S_MB_2U_LIB.S9S_MB_2U(SCH_1):GND
   G3  GND               G3  @S9S_MB_2U_LIB.S9S_MB_2U(SCH_1):GND
   G2  GND               G2  @S9S_MB_2U_LIB.S9S_MB_2U(SCH_1):GND
   G1  GND               G1  @S9S_MB_2U_LIB.S9S_MB_2U(SCH_1):GND

SCONN288_ADR50001P013C01  I179  J25    [SCONN288_ADR50001P013C01-SCONNA]
   93  M_E_CPU1_SB_DQS_DP<9>  DQS9_B_P  @S9S_MB_2U_LIB.S9S_MB_2U(SCH_1):M_E_CPU1_SB_DQS_DP<9>
  283  M_E_CPU1_SB_DQS_DP<8>  DQS8_B_P  @S9S_MB_2U_LIB.S9S_MB_2U(SCH_1):M_E_CPU1_SB_DQS_DP<8>
  272  M_E_CPU1_SB_DQS_DP<7>  DQS7_B_P  @S9S_MB_2U_LIB.S9S_MB_2U(SCH_1):M_E_CPU1_SB_DQS_DP<7>
  261  M_E_CPU1_SB_DQS_DP<6>  DQS6_B_P  @S9S_MB_2U_LIB.S9S_MB_2U(SCH_1):M_E_CPU1_SB_DQS_DP<6>
  250  M_E_CPU1_SB_DQS_DP<5>  DQS5_B_P  @S9S_MB_2U_LIB.S9S_MB_2U(SCH_1):M_E_CPU1_SB_DQS_DP<5>
  239  M_E_CPU1_SB_DQS_DP<4>  DQS4_B_P  @S9S_MB_2U_LIB.S9S_MB_2U(SCH_1):M_E_CPU1_SB_DQS_DP<4>
  137  M_E_CPU1_SB_DQS_DP<3>  DQS3_B_P  @S9S_MB_2U_LIB.S9S_MB_2U(SCH_1):M_E_CPU1_SB_DQS_DP<3>
  126  M_E_CPU1_SB_DQS_DP<2>  DQS2_B_P  @S9S_MB_2U_LIB.S9S_MB_2U(SCH_1):M_E_CPU1_SB_DQS_DP<2>
  115  M_E_CPU1_SB_DQS_DP<1>  DQS1_B_P  @S9S_MB_2U_LIB.S9S_MB_2U(SCH_1):M_E_CPU1_SB_DQS_DP<1>
  104  M_E_CPU1_SB_DQS_DP<0>  DQS0_B_P  @S9S_MB_2U_LIB.S9S_MB_2U(SCH_1):M_E_CPU1_SB_DQS_DP<0>
   94  M_E_CPU1_SB_DQS_DN<9>  DQS9_B_N  @S9S_MB_2U_LIB.S9S_MB_2U(SCH_1):M_E_CPU1_SB_DQS_DN<9>
  282  M_E_CPU1_SB_DQS_DN<8>  DQS8_B_N  @S9S_MB_2U_LIB.S9S_MB_2U(SCH_1):M_E_CPU1_SB_DQS_DN<8>
  271  M_E_CPU1_SB_DQS_DN<7>  DQS7_B_N  @S9S_MB_2U_LIB.S9S_MB_2U(SCH_1):M_E_CPU1_SB_DQS_DN<7>
  260  M_E_CPU1_SB_DQS_DN<6>  DQS6_B_N  @S9S_MB_2U_LIB.S9S_MB_2U(SCH_1):M_E_CPU1_SB_DQS_DN<6>
  249  M_E_CPU1_SB_DQS_DN<5>  DQS5_B_N  @S9S_MB_2U_LIB.S9S_MB_2U(SCH_1):M_E_CPU1_SB_DQS_DN<5>
  238  M_E_CPU1_SB_DQS_DN<4>  DQS4_B_N  @S9S_MB_2U_LIB.S9S_MB_2U(SCH_1):M_E_CPU1_SB_DQS_DN<4>
  138  M_E_CPU1_SB_DQS_DN<3>  DQS3_B_N  @S9S_MB_2U_LIB.S9S_MB_2U(SCH_1):M_E_CPU1_SB_DQS_DN<3>
  127  M_E_CPU1_SB_DQS_DN<2>  DQS2_B_N  @S9S_MB_2U_LIB.S9S_MB_2U(SCH_1):M_E_CPU1_SB_DQS_DN<2>
  116  M_E_CPU1_SB_DQS_DN<1>  DQS1_B_N  @S9S_MB_2U_LIB.S9S_MB_2U(SCH_1):M_E_CPU1_SB_DQS_DN<1>
  105  M_E_CPU1_SB_DQS_DN<0>  DQS0_B_N  @S9S_MB_2U_LIB.S9S_MB_2U(SCH_1):M_E_CPU1_SB_DQS_DN<0>
  201  M_E_CPU1_SA_DQS_DP<9>  DQS9_A_P  @S9S_MB_2U_LIB.S9S_MB_2U(SCH_1):M_E_CPU1_SA_DQS_DP<9>
  190  M_E_CPU1_SA_DQS_DP<8>  DQS8_A_P  @S9S_MB_2U_LIB.S9S_MB_2U(SCH_1):M_E_CPU1_SA_DQS_DP<8>
  179  M_E_CPU1_SA_DQS_DP<7>  DQS7_A_P  @S9S_MB_2U_LIB.S9S_MB_2U(SCH_1):M_E_CPU1_SA_DQS_DP<7>
  168  M_E_CPU1_SA_DQS_DP<6>  DQS6_A_P  @S9S_MB_2U_LIB.S9S_MB_2U(SCH_1):M_E_CPU1_SA_DQS_DP<6>
  157  M_E_CPU1_SA_DQS_DP<5>  DQS5_A_P  @S9S_MB_2U_LIB.S9S_MB_2U(SCH_1):M_E_CPU1_SA_DQS_DP<5>
   55  M_E_CPU1_SA_DQS_DP<4>  DQS4_A_P  @S9S_MB_2U_LIB.S9S_MB_2U(SCH_1):M_E_CPU1_SA_DQS_DP<4>
   44  M_E_CPU1_SA_DQS_DP<3>  DQS3_A_P  @S9S_MB_2U_LIB.S9S_MB_2U(SCH_1):M_E_CPU1_SA_DQS_DP<3>
   33  M_E_CPU1_SA_DQS_DP<2>  DQS2_A_P  @S9S_MB_2U_LIB.S9S_MB_2U(SCH_1):M_E_CPU1_SA_DQS_DP<2>
   22  M_E_CPU1_SA_DQS_DP<1>  DQS1_A_P  @S9S_MB_2U_LIB.S9S_MB_2U(SCH_1):M_E_CPU1_SA_DQS_DP<1>
   11  M_E_CPU1_SA_DQS_DP<0>  DQS0_A_P  @S9S_MB_2U_LIB.S9S_MB_2U(SCH_1):M_E_CPU1_SA_DQS_DP<0>
  200  M_E_CPU1_SA_DQS_DN<9>  DQS9_A_N  @S9S_MB_2U_LIB.S9S_MB_2U(SCH_1):M_E_CPU1_SA_DQS_DN<9>
  189  M_E_CPU1_SA_DQS_DN<8>  DQS8_A_N  @S9S_MB_2U_LIB.S9S_MB_2U(SCH_1):M_E_CPU1_SA_DQS_DN<8>
  178  M_E_CPU1_SA_DQS_DN<7>  DQS7_A_N  @S9S_MB_2U_LIB.S9S_MB_2U(SCH_1):M_E_CPU1_SA_DQS_DN<7>
  167  M_E_CPU1_SA_DQS_DN<6>  DQS6_A_N  @S9S_MB_2U_LIB.S9S_MB_2U(SCH_1):M_E_CPU1_SA_DQS_DN<6>
  156  M_E_CPU1_SA_DQS_DN<5>  DQS5_A_N  @S9S_MB_2U_LIB.S9S_MB_2U(SCH_1):M_E_CPU1_SA_DQS_DN<5>
   56  M_E_CPU1_SA_DQS_DN<4>  DQS4_A_N  @S9S_MB_2U_LIB.S9S_MB_2U(SCH_1):M_E_CPU1_SA_DQS_DN<4>
   45  M_E_CPU1_SA_DQS_DN<3>  DQS3_A_N  @S9S_MB_2U_LIB.S9S_MB_2U(SCH_1):M_E_CPU1_SA_DQS_DN<3>
   34  M_E_CPU1_SA_DQS_DN<2>  DQS2_A_N  @S9S_MB_2U_LIB.S9S_MB_2U(SCH_1):M_E_CPU1_SA_DQS_DN<2>
   23  M_E_CPU1_SA_DQS_DN<1>  DQS1_A_N  @S9S_MB_2U_LIB.S9S_MB_2U(SCH_1):M_E_CPU1_SA_DQS_DN<1>
   12  M_E_CPU1_SA_DQS_DN<0>  DQS0_A_N  @S9S_MB_2U_LIB.S9S_MB_2U(SCH_1):M_E_CPU1_SA_DQS_DN<0>

SCONN288_ADR50001P013C01  I180  J25    [SCONN288_ADR50001P013C01-SCONNA]
  232  NC              RFU6  NC
  231  NC              RFU5  NC
  220  NC              RFU4  NC
  150  NC              RFU3  NC
  149  NC              RFU2  NC
  144  NC              RFU1  NC
    2  NC              RFU0  NC
  207  RST_M_EF_CPU1_FPGA_N  RESET_N  @S9S_MB_2U_LIB.S9S_MB_2U(SCH_1):RST_M_EF_CPU1_FPGA_N
  147  PWRGD_CHE_CPU1_DIMM1  PWR_GOOD||FAIL_N  @S9S_MB_2U_LIB.S9S_MB_2U(SCH_1):PWRGD_CHE_CPU1_DIMM1
  148  PD_CHE_CPU1_DIMM1_SAA    HAS  @S9S_MB_2U_LIB.S9S_MB_2U(SCH_1):PD_CHE_CPU1_DIMM1_SAA
    3  P3V3_AUX       VIN_MGMT  @S9S_MB_2U_LIB.S9S_MB_2U(SCH_1):P3V3_AUX
   87  M_E_CPU1_SB_RSP<0>  LBS||RSP_N_B  @S9S_MB_2U_LIB.S9S_MB_2U(SCH_1):M_E_CPU1_SB_RSP<0>
  227  M_E_CPU1_SB_PAR  PAR_B  @S9S_MB_2U_LIB.S9S_MB_2U(SCH_1):M_E_CPU1_SB_PAR
  113  M_E_CPU1_SB_DQ<9>  DQ_B9  @S9S_MB_2U_LIB.S9S_MB_2U(SCH_1):M_E_CPU1_SB_DQ<9>
  111  M_E_CPU1_SB_DQ<8>  DQ_B8  @S9S_MB_2U_LIB.S9S_MB_2U(SCH_1):M_E_CPU1_SB_DQ<8>
  254  M_E_CPU1_SB_DQ<7>  DQ_B7  @S9S_MB_2U_LIB.S9S_MB_2U(SCH_1):M_E_CPU1_SB_DQ<7>
  252  M_E_CPU1_SB_DQ<6>  DQ_B6  @S9S_MB_2U_LIB.S9S_MB_2U(SCH_1):M_E_CPU1_SB_DQ<6>
  109  M_E_CPU1_SB_DQ<5>  DQ_B5  @S9S_MB_2U_LIB.S9S_MB_2U(SCH_1):M_E_CPU1_SB_DQ<5>
  107  M_E_CPU1_SB_DQ<4>  DQ_B4  @S9S_MB_2U_LIB.S9S_MB_2U(SCH_1):M_E_CPU1_SB_DQ<4>
  247  M_E_CPU1_SB_DQ<3>  DQ_B3  @S9S_MB_2U_LIB.S9S_MB_2U(SCH_1):M_E_CPU1_SB_DQ<3>
  287  M_E_CPU1_SB_DQ<31>  DQ_B31  @S9S_MB_2U_LIB.S9S_MB_2U(SCH_1):M_E_CPU1_SB_DQ<31>
  285  M_E_CPU1_SB_DQ<30>  DQ_B30  @S9S_MB_2U_LIB.S9S_MB_2U(SCH_1):M_E_CPU1_SB_DQ<30>
  245  M_E_CPU1_SB_DQ<2>  DQ_B2  @S9S_MB_2U_LIB.S9S_MB_2U(SCH_1):M_E_CPU1_SB_DQ<2>
  142  M_E_CPU1_SB_DQ<29>  DQ_B29  @S9S_MB_2U_LIB.S9S_MB_2U(SCH_1):M_E_CPU1_SB_DQ<29>
  140  M_E_CPU1_SB_DQ<28>  DQ_B28  @S9S_MB_2U_LIB.S9S_MB_2U(SCH_1):M_E_CPU1_SB_DQ<28>
  280  M_E_CPU1_SB_DQ<27>  DQ_B27  @S9S_MB_2U_LIB.S9S_MB_2U(SCH_1):M_E_CPU1_SB_DQ<27>
  278  M_E_CPU1_SB_DQ<26>  DQ_B26  @S9S_MB_2U_LIB.S9S_MB_2U(SCH_1):M_E_CPU1_SB_DQ<26>
  135  M_E_CPU1_SB_DQ<25>  DQ_B25  @S9S_MB_2U_LIB.S9S_MB_2U(SCH_1):M_E_CPU1_SB_DQ<25>
  133  M_E_CPU1_SB_DQ<24>  DQ_B24  @S9S_MB_2U_LIB.S9S_MB_2U(SCH_1):M_E_CPU1_SB_DQ<24>
  276  M_E_CPU1_SB_DQ<23>  DQ_B23  @S9S_MB_2U_LIB.S9S_MB_2U(SCH_1):M_E_CPU1_SB_DQ<23>
  274  M_E_CPU1_SB_DQ<22>  DQ_B22  @S9S_MB_2U_LIB.S9S_MB_2U(SCH_1):M_E_CPU1_SB_DQ<22>
  131  M_E_CPU1_SB_DQ<21>  DQ_B21  @S9S_MB_2U_LIB.S9S_MB_2U(SCH_1):M_E_CPU1_SB_DQ<21>
  129  M_E_CPU1_SB_DQ<20>  DQ_B20  @S9S_MB_2U_LIB.S9S_MB_2U(SCH_1):M_E_CPU1_SB_DQ<20>
  102  M_E_CPU1_SB_DQ<1>  DQ_B1  @S9S_MB_2U_LIB.S9S_MB_2U(SCH_1):M_E_CPU1_SB_DQ<1>
  269  M_E_CPU1_SB_DQ<19>  DQ_B19  @S9S_MB_2U_LIB.S9S_MB_2U(SCH_1):M_E_CPU1_SB_DQ<19>
  267  M_E_CPU1_SB_DQ<18>  DQ_B18  @S9S_MB_2U_LIB.S9S_MB_2U(SCH_1):M_E_CPU1_SB_DQ<18>
  124  M_E_CPU1_SB_DQ<17>  DQ_B17  @S9S_MB_2U_LIB.S9S_MB_2U(SCH_1):M_E_CPU1_SB_DQ<17>
  122  M_E_CPU1_SB_DQ<16>  DQ_B16  @S9S_MB_2U_LIB.S9S_MB_2U(SCH_1):M_E_CPU1_SB_DQ<16>
  265  M_E_CPU1_SB_DQ<15>  DQ_B15  @S9S_MB_2U_LIB.S9S_MB_2U(SCH_1):M_E_CPU1_SB_DQ<15>
  263  M_E_CPU1_SB_DQ<14>  DQ_B14  @S9S_MB_2U_LIB.S9S_MB_2U(SCH_1):M_E_CPU1_SB_DQ<14>
  120  M_E_CPU1_SB_DQ<13>  DQ_B13  @S9S_MB_2U_LIB.S9S_MB_2U(SCH_1):M_E_CPU1_SB_DQ<13>
  118  M_E_CPU1_SB_DQ<12>  DQ_B12  @S9S_MB_2U_LIB.S9S_MB_2U(SCH_1):M_E_CPU1_SB_DQ<12>
  258  M_E_CPU1_SB_DQ<11>  DQ_B11  @S9S_MB_2U_LIB.S9S_MB_2U(SCH_1):M_E_CPU1_SB_DQ<11>
  256  M_E_CPU1_SB_DQ<10>  DQ_B10  @S9S_MB_2U_LIB.S9S_MB_2U(SCH_1):M_E_CPU1_SB_DQ<10>
  100  M_E_CPU1_SB_DQ<0>  DQ_B0  @S9S_MB_2U_LIB.S9S_MB_2U(SCH_1):M_E_CPU1_SB_DQ<0>
  229  M_E_CPU1_SB_CS_N<1>  CS1_N_B  @S9S_MB_2U_LIB.S9S_MB_2U(SCH_1):M_E_CPU1_SB_CS_N<1>
   84  M_E_CPU1_SB_CS_N<0>  CS0_N_B  @S9S_MB_2U_LIB.S9S_MB_2U(SCH_1):M_E_CPU1_SB_CS_N<0>
  236  M_E_CPU1_SB_CB<7>  CB_B7  @S9S_MB_2U_LIB.S9S_MB_2U(SCH_1):M_E_CPU1_SB_CB<7>
  234  M_E_CPU1_SB_CB<6>  CB_B6  @S9S_MB_2U_LIB.S9S_MB_2U(SCH_1):M_E_CPU1_SB_CB<6>
   91  M_E_CPU1_SB_CB<5>  CB_B5  @S9S_MB_2U_LIB.S9S_MB_2U(SCH_1):M_E_CPU1_SB_CB<5>
   89  M_E_CPU1_SB_CB<4>  CB_B4  @S9S_MB_2U_LIB.S9S_MB_2U(SCH_1):M_E_CPU1_SB_CB<4>
  243  M_E_CPU1_SB_CB<3>  CB_B3  @S9S_MB_2U_LIB.S9S_MB_2U(SCH_1):M_E_CPU1_SB_CB<3>
  241  M_E_CPU1_SB_CB<2>  CB_B2  @S9S_MB_2U_LIB.S9S_MB_2U(SCH_1):M_E_CPU1_SB_CB<2>
   98  M_E_CPU1_SB_CB<1>  CB_B1  @S9S_MB_2U_LIB.S9S_MB_2U(SCH_1):M_E_CPU1_SB_CB<1>
   96  M_E_CPU1_SB_CB<0>  CB_B0  @S9S_MB_2U_LIB.S9S_MB_2U(SCH_1):M_E_CPU1_SB_CB<0>
   82  M_E_CPU1_SB_CA<6>  CA6_B  @S9S_MB_2U_LIB.S9S_MB_2U(SCH_1):M_E_CPU1_SB_CA<6>
  225  M_E_CPU1_SB_CA<5>  CA5_B  @S9S_MB_2U_LIB.S9S_MB_2U(SCH_1):M_E_CPU1_SB_CA<5>
   80  M_E_CPU1_SB_CA<4>  CA4_B  @S9S_MB_2U_LIB.S9S_MB_2U(SCH_1):M_E_CPU1_SB_CA<4>
  223  M_E_CPU1_SB_CA<3>  CA3_B  @S9S_MB_2U_LIB.S9S_MB_2U(SCH_1):M_E_CPU1_SB_CA<3>
   78  M_E_CPU1_SB_CA<2>  CA2_B  @S9S_MB_2U_LIB.S9S_MB_2U(SCH_1):M_E_CPU1_SB_CA<2>
  221  M_E_CPU1_SB_CA<1>  CA1_B  @S9S_MB_2U_LIB.S9S_MB_2U(SCH_1):M_E_CPU1_SB_CA<1>
   76  M_E_CPU1_SB_CA<0>  CA0_B  @S9S_MB_2U_LIB.S9S_MB_2U(SCH_1):M_E_CPU1_SB_CA<0>
   86  M_E_CPU1_SA_RSP<0>  LBD||RSP_N_A  @S9S_MB_2U_LIB.S9S_MB_2U(SCH_1):M_E_CPU1_SA_RSP<0>
   74  M_E_CPU1_SA_PAR  PAR_A  @S9S_MB_2U_LIB.S9S_MB_2U(SCH_1):M_E_CPU1_SA_PAR
   20  M_E_CPU1_SA_DQ<9>  DQ_A9  @S9S_MB_2U_LIB.S9S_MB_2U(SCH_1):M_E_CPU1_SA_DQ<9>
   18  M_E_CPU1_SA_DQ<8>  DQ_A8  @S9S_MB_2U_LIB.S9S_MB_2U(SCH_1):M_E_CPU1_SA_DQ<8>
  161  M_E_CPU1_SA_DQ<7>  DQ_A7  @S9S_MB_2U_LIB.S9S_MB_2U(SCH_1):M_E_CPU1_SA_DQ<7>
  159  M_E_CPU1_SA_DQ<6>  DQ_A6  @S9S_MB_2U_LIB.S9S_MB_2U(SCH_1):M_E_CPU1_SA_DQ<6>
   16  M_E_CPU1_SA_DQ<5>  DQ_A5  @S9S_MB_2U_LIB.S9S_MB_2U(SCH_1):M_E_CPU1_SA_DQ<5>
   14  M_E_CPU1_SA_DQ<4>  DQ_A4  @S9S_MB_2U_LIB.S9S_MB_2U(SCH_1):M_E_CPU1_SA_DQ<4>
  154  M_E_CPU1_SA_DQ<3>  DQ_A3  @S9S_MB_2U_LIB.S9S_MB_2U(SCH_1):M_E_CPU1_SA_DQ<3>
  194  M_E_CPU1_SA_DQ<31>  DQ_A31  @S9S_MB_2U_LIB.S9S_MB_2U(SCH_1):M_E_CPU1_SA_DQ<31>
  192  M_E_CPU1_SA_DQ<30>  DQ_A30  @S9S_MB_2U_LIB.S9S_MB_2U(SCH_1):M_E_CPU1_SA_DQ<30>
  152  M_E_CPU1_SA_DQ<2>  DQ_A2  @S9S_MB_2U_LIB.S9S_MB_2U(SCH_1):M_E_CPU1_SA_DQ<2>
   49  M_E_CPU1_SA_DQ<29>  DQ_A29  @S9S_MB_2U_LIB.S9S_MB_2U(SCH_1):M_E_CPU1_SA_DQ<29>
   47  M_E_CPU1_SA_DQ<28>  DQ_A28  @S9S_MB_2U_LIB.S9S_MB_2U(SCH_1):M_E_CPU1_SA_DQ<28>
  187  M_E_CPU1_SA_DQ<27>  DQ_A27  @S9S_MB_2U_LIB.S9S_MB_2U(SCH_1):M_E_CPU1_SA_DQ<27>
  185  M_E_CPU1_SA_DQ<26>  DQ_A26  @S9S_MB_2U_LIB.S9S_MB_2U(SCH_1):M_E_CPU1_SA_DQ<26>
   42  M_E_CPU1_SA_DQ<25>  DQ_A25  @S9S_MB_2U_LIB.S9S_MB_2U(SCH_1):M_E_CPU1_SA_DQ<25>
   40  M_E_CPU1_SA_DQ<24>  DQ_A24  @S9S_MB_2U_LIB.S9S_MB_2U(SCH_1):M_E_CPU1_SA_DQ<24>
  183  M_E_CPU1_SA_DQ<23>  DQ_A23  @S9S_MB_2U_LIB.S9S_MB_2U(SCH_1):M_E_CPU1_SA_DQ<23>
  181  M_E_CPU1_SA_DQ<22>  DQ_A22  @S9S_MB_2U_LIB.S9S_MB_2U(SCH_1):M_E_CPU1_SA_DQ<22>
   38  M_E_CPU1_SA_DQ<21>  DQ_A21  @S9S_MB_2U_LIB.S9S_MB_2U(SCH_1):M_E_CPU1_SA_DQ<21>
   36  M_E_CPU1_SA_DQ<20>  DQ_A20  @S9S_MB_2U_LIB.S9S_MB_2U(SCH_1):M_E_CPU1_SA_DQ<20>
    9  M_E_CPU1_SA_DQ<1>  DQ_A1  @S9S_MB_2U_LIB.S9S_MB_2U(SCH_1):M_E_CPU1_SA_DQ<1>
  176  M_E_CPU1_SA_DQ<19>  DQ_A19  @S9S_MB_2U_LIB.S9S_MB_2U(SCH_1):M_E_CPU1_SA_DQ<19>
  174  M_E_CPU1_SA_DQ<18>  DQ_A18  @S9S_MB_2U_LIB.S9S_MB_2U(SCH_1):M_E_CPU1_SA_DQ<18>
   31  M_E_CPU1_SA_DQ<17>  DQ_A17  @S9S_MB_2U_LIB.S9S_MB_2U(SCH_1):M_E_CPU1_SA_DQ<17>
   29  M_E_CPU1_SA_DQ<16>  DQ_A16  @S9S_MB_2U_LIB.S9S_MB_2U(SCH_1):M_E_CPU1_SA_DQ<16>
  172  M_E_CPU1_SA_DQ<15>  DQ_A15  @S9S_MB_2U_LIB.S9S_MB_2U(SCH_1):M_E_CPU1_SA_DQ<15>
  170  M_E_CPU1_SA_DQ<14>  DQ_A14  @S9S_MB_2U_LIB.S9S_MB_2U(SCH_1):M_E_CPU1_SA_DQ<14>
   27  M_E_CPU1_SA_DQ<13>  DQ_A13  @S9S_MB_2U_LIB.S9S_MB_2U(SCH_1):M_E_CPU1_SA_DQ<13>
   25  M_E_CPU1_SA_DQ<12>  DQ_A12  @S9S_MB_2U_LIB.S9S_MB_2U(SCH_1):M_E_CPU1_SA_DQ<12>
  165  M_E_CPU1_SA_DQ<11>  DQ_A11  @S9S_MB_2U_LIB.S9S_MB_2U(SCH_1):M_E_CPU1_SA_DQ<11>
  163  M_E_CPU1_SA_DQ<10>  DQ_A10  @S9S_MB_2U_LIB.S9S_MB_2U(SCH_1):M_E_CPU1_SA_DQ<10>
    7  M_E_CPU1_SA_DQ<0>  DQ_A0  @S9S_MB_2U_LIB.S9S_MB_2U(SCH_1):M_E_CPU1_SA_DQ<0>
  209  M_E_CPU1_SA_CS_N<1>  CS1_N_A  @S9S_MB_2U_LIB.S9S_MB_2U(SCH_1):M_E_CPU1_SA_CS_N<1>
   64  M_E_CPU1_SA_CS_N<0>  CS0_N_A  @S9S_MB_2U_LIB.S9S_MB_2U(SCH_1):M_E_CPU1_SA_CS_N<0>
  205  M_E_CPU1_SA_CB<7>  CB_A7  @S9S_MB_2U_LIB.S9S_MB_2U(SCH_1):M_E_CPU1_SA_CB<7>
  203  M_E_CPU1_SA_CB<6>  CB_A6  @S9S_MB_2U_LIB.S9S_MB_2U(SCH_1):M_E_CPU1_SA_CB<6>
   60  M_E_CPU1_SA_CB<5>  CB_A5  @S9S_MB_2U_LIB.S9S_MB_2U(SCH_1):M_E_CPU1_SA_CB<5>
   58  M_E_CPU1_SA_CB<4>  CB_A4  @S9S_MB_2U_LIB.S9S_MB_2U(SCH_1):M_E_CPU1_SA_CB<4>
  198  M_E_CPU1_SA_CB<3>  CB_A3  @S9S_MB_2U_LIB.S9S_MB_2U(SCH_1):M_E_CPU1_SA_CB<3>
  196  M_E_CPU1_SA_CB<2>  CB_A2  @S9S_MB_2U_LIB.S9S_MB_2U(SCH_1):M_E_CPU1_SA_CB<2>
   53  M_E_CPU1_SA_CB<1>  CB_A1  @S9S_MB_2U_LIB.S9S_MB_2U(SCH_1):M_E_CPU1_SA_CB<1>
   51  M_E_CPU1_SA_CB<0>  CB_A0  @S9S_MB_2U_LIB.S9S_MB_2U(SCH_1):M_E_CPU1_SA_CB<0>
   72  M_E_CPU1_SA_CA<6>  CA6_A  @S9S_MB_2U_LIB.S9S_MB_2U(SCH_1):M_E_CPU1_SA_CA<6>
  215  M_E_CPU1_SA_CA<5>  CA5_A  @S9S_MB_2U_LIB.S9S_MB_2U(SCH_1):M_E_CPU1_SA_CA<5>
   70  M_E_CPU1_SA_CA<4>  CA4_A  @S9S_MB_2U_LIB.S9S_MB_2U(SCH_1):M_E_CPU1_SA_CA<4>
  213  M_E_CPU1_SA_CA<3>  CA3_A  @S9S_MB_2U_LIB.S9S_MB_2U(SCH_1):M_E_CPU1_SA_CA<3>
   68  M_E_CPU1_SA_CA<2>  CA2_A  @S9S_MB_2U_LIB.S9S_MB_2U(SCH_1):M_E_CPU1_SA_CA<2>
  211  M_E_CPU1_SA_CA<1>  CA1_A  @S9S_MB_2U_LIB.S9S_MB_2U(SCH_1):M_E_CPU1_SA_CA<1>
   66  M_E_CPU1_SA_CA<0>  CA0_A  @S9S_MB_2U_LIB.S9S_MB_2U(SCH_1):M_E_CPU1_SA_CA<0>
  217  M_E_CPU1_CLK_DP<0>   CK_P  @S9S_MB_2U_LIB.S9S_MB_2U(SCH_1):M_E_CPU1_CLK_DP<0>
  218  M_E_CPU1_CLK_DN<0>   CK_N  @S9S_MB_2U_LIB.S9S_MB_2U(SCH_1):M_E_CPU1_CLK_DN<0>
   62  M_E_CPU1_ALERT_N  ALERT_N  @S9S_MB_2U_LIB.S9S_MB_2U(SCH_1):M_E_CPU1_ALERT_N
    5  I3C_SPD_DDREFGH_CPU1_LVC1_SDA   HSDA  @S9S_MB_2U_LIB.S9S_MB_2U(SCH_1):I3C_SPD_DDREFGH_CPU1_LVC1_SDA
    4  I3C_SPD_DDREFGH_CPU1_LVC1_SCL   HSCL  @S9S_MB_2U_LIB.S9S_MB_2U(SCH_1):I3C_SPD_DDREFGH_CPU1_LVC1_SCL

SCONN288_ADR50001P003C01  I179  J26    [SCONN288_ADR50001P003C01-SCONNA]
  146  P12V_S3_AUX_CPU1_NVDIMM  VIN_BULK2  @S9S_MB_2U_LIB.S9S_MB_2U(SCH_1):P12V_S3_AUX_CPU1_NVDIMM
  145  P12V_S3_AUX_CPU1_NVDIMM  VIN_BULK1  @S9S_MB_2U_LIB.S9S_MB_2U(SCH_1):P12V_S3_AUX_CPU1_NVDIMM
    1  P12V_S3_AUX_CPU1_NVDIMM  VIN_BULK0  @S9S_MB_2U_LIB.S9S_MB_2U(SCH_1):P12V_S3_AUX_CPU1_NVDIMM
  288  GND            VSS126  @S9S_MB_2U_LIB.S9S_MB_2U(SCH_1):GND
  286  GND            VSS125  @S9S_MB_2U_LIB.S9S_MB_2U(SCH_1):GND
  284  GND            VSS124  @S9S_MB_2U_LIB.S9S_MB_2U(SCH_1):GND
  281  GND            VSS123  @S9S_MB_2U_LIB.S9S_MB_2U(SCH_1):GND
  279  GND            VSS122  @S9S_MB_2U_LIB.S9S_MB_2U(SCH_1):GND
  277  GND            VSS121  @S9S_MB_2U_LIB.S9S_MB_2U(SCH_1):GND
  275  GND            VSS120  @S9S_MB_2U_LIB.S9S_MB_2U(SCH_1):GND
  273  GND            VSS119  @S9S_MB_2U_LIB.S9S_MB_2U(SCH_1):GND
  270  GND            VSS118  @S9S_MB_2U_LIB.S9S_MB_2U(SCH_1):GND
  268  GND            VSS117  @S9S_MB_2U_LIB.S9S_MB_2U(SCH_1):GND
  266  GND            VSS116  @S9S_MB_2U_LIB.S9S_MB_2U(SCH_1):GND
  264  GND            VSS115  @S9S_MB_2U_LIB.S9S_MB_2U(SCH_1):GND
  262  GND            VSS114  @S9S_MB_2U_LIB.S9S_MB_2U(SCH_1):GND
  259  GND            VSS113  @S9S_MB_2U_LIB.S9S_MB_2U(SCH_1):GND
  257  GND            VSS112  @S9S_MB_2U_LIB.S9S_MB_2U(SCH_1):GND
  255  GND            VSS111  @S9S_MB_2U_LIB.S9S_MB_2U(SCH_1):GND
  253  GND            VSS110  @S9S_MB_2U_LIB.S9S_MB_2U(SCH_1):GND
  251  GND            VSS109  @S9S_MB_2U_LIB.S9S_MB_2U(SCH_1):GND
  248  GND            VSS108  @S9S_MB_2U_LIB.S9S_MB_2U(SCH_1):GND
  246  GND            VSS107  @S9S_MB_2U_LIB.S9S_MB_2U(SCH_1):GND
  244  GND            VSS106  @S9S_MB_2U_LIB.S9S_MB_2U(SCH_1):GND
  242  GND            VSS105  @S9S_MB_2U_LIB.S9S_MB_2U(SCH_1):GND
  240  GND            VSS104  @S9S_MB_2U_LIB.S9S_MB_2U(SCH_1):GND
  237  GND            VSS103  @S9S_MB_2U_LIB.S9S_MB_2U(SCH_1):GND
  235  GND            VSS102  @S9S_MB_2U_LIB.S9S_MB_2U(SCH_1):GND
  233  GND            VSS101  @S9S_MB_2U_LIB.S9S_MB_2U(SCH_1):GND
  230  GND            VSS100  @S9S_MB_2U_LIB.S9S_MB_2U(SCH_1):GND
  228  GND            VSS99  @S9S_MB_2U_LIB.S9S_MB_2U(SCH_1):GND
  226  GND            VSS98  @S9S_MB_2U_LIB.S9S_MB_2U(SCH_1):GND
  224  GND            VSS97  @S9S_MB_2U_LIB.S9S_MB_2U(SCH_1):GND
  222  GND            VSS96  @S9S_MB_2U_LIB.S9S_MB_2U(SCH_1):GND
  219  GND            VSS95  @S9S_MB_2U_LIB.S9S_MB_2U(SCH_1):GND
  216  GND            VSS94  @S9S_MB_2U_LIB.S9S_MB_2U(SCH_1):GND
  214  GND            VSS93  @S9S_MB_2U_LIB.S9S_MB_2U(SCH_1):GND
  212  GND            VSS92  @S9S_MB_2U_LIB.S9S_MB_2U(SCH_1):GND
  210  GND            VSS91  @S9S_MB_2U_LIB.S9S_MB_2U(SCH_1):GND
  208  GND            VSS90  @S9S_MB_2U_LIB.S9S_MB_2U(SCH_1):GND
  206  GND            VSS89  @S9S_MB_2U_LIB.S9S_MB_2U(SCH_1):GND
  204  GND            VSS88  @S9S_MB_2U_LIB.S9S_MB_2U(SCH_1):GND
  202  GND            VSS87  @S9S_MB_2U_LIB.S9S_MB_2U(SCH_1):GND
  199  GND            VSS86  @S9S_MB_2U_LIB.S9S_MB_2U(SCH_1):GND
  197  GND            VSS85  @S9S_MB_2U_LIB.S9S_MB_2U(SCH_1):GND
  195  GND            VSS84  @S9S_MB_2U_LIB.S9S_MB_2U(SCH_1):GND
  193  GND            VSS83  @S9S_MB_2U_LIB.S9S_MB_2U(SCH_1):GND
  191  GND            VSS82  @S9S_MB_2U_LIB.S9S_MB_2U(SCH_1):GND
  188  GND            VSS81  @S9S_MB_2U_LIB.S9S_MB_2U(SCH_1):GND
  186  GND            VSS80  @S9S_MB_2U_LIB.S9S_MB_2U(SCH_1):GND
  184  GND            VSS79  @S9S_MB_2U_LIB.S9S_MB_2U(SCH_1):GND
  182  GND            VSS78  @S9S_MB_2U_LIB.S9S_MB_2U(SCH_1):GND
  180  GND            VSS77  @S9S_MB_2U_LIB.S9S_MB_2U(SCH_1):GND
  177  GND            VSS76  @S9S_MB_2U_LIB.S9S_MB_2U(SCH_1):GND
  175  GND            VSS75  @S9S_MB_2U_LIB.S9S_MB_2U(SCH_1):GND
  173  GND            VSS74  @S9S_MB_2U_LIB.S9S_MB_2U(SCH_1):GND
  171  GND            VSS73  @S9S_MB_2U_LIB.S9S_MB_2U(SCH_1):GND
  169  GND            VSS72  @S9S_MB_2U_LIB.S9S_MB_2U(SCH_1):GND
  166  GND            VSS71  @S9S_MB_2U_LIB.S9S_MB_2U(SCH_1):GND
  164  GND            VSS70  @S9S_MB_2U_LIB.S9S_MB_2U(SCH_1):GND
  162  GND            VSS69  @S9S_MB_2U_LIB.S9S_MB_2U(SCH_1):GND
  160  GND            VSS68  @S9S_MB_2U_LIB.S9S_MB_2U(SCH_1):GND
  158  GND            VSS67  @S9S_MB_2U_LIB.S9S_MB_2U(SCH_1):GND
  155  GND            VSS66  @S9S_MB_2U_LIB.S9S_MB_2U(SCH_1):GND
  153  GND            VSS65  @S9S_MB_2U_LIB.S9S_MB_2U(SCH_1):GND
  151  GND            VSS64  @S9S_MB_2U_LIB.S9S_MB_2U(SCH_1):GND
  143  GND            VSS63  @S9S_MB_2U_LIB.S9S_MB_2U(SCH_1):GND
  141  GND            VSS62  @S9S_MB_2U_LIB.S9S_MB_2U(SCH_1):GND
  139  GND            VSS61  @S9S_MB_2U_LIB.S9S_MB_2U(SCH_1):GND
  136  GND            VSS60  @S9S_MB_2U_LIB.S9S_MB_2U(SCH_1):GND
  134  GND            VSS59  @S9S_MB_2U_LIB.S9S_MB_2U(SCH_1):GND
  132  GND            VSS58  @S9S_MB_2U_LIB.S9S_MB_2U(SCH_1):GND
  130  GND            VSS57  @S9S_MB_2U_LIB.S9S_MB_2U(SCH_1):GND
  128  GND            VSS56  @S9S_MB_2U_LIB.S9S_MB_2U(SCH_1):GND
  125  GND            VSS55  @S9S_MB_2U_LIB.S9S_MB_2U(SCH_1):GND
  123  GND            VSS54  @S9S_MB_2U_LIB.S9S_MB_2U(SCH_1):GND
  121  GND            VSS53  @S9S_MB_2U_LIB.S9S_MB_2U(SCH_1):GND
  119  GND            VSS52  @S9S_MB_2U_LIB.S9S_MB_2U(SCH_1):GND
  117  GND            VSS51  @S9S_MB_2U_LIB.S9S_MB_2U(SCH_1):GND
  114  GND            VSS50  @S9S_MB_2U_LIB.S9S_MB_2U(SCH_1):GND
  112  GND            VSS49  @S9S_MB_2U_LIB.S9S_MB_2U(SCH_1):GND
  110  GND            VSS48  @S9S_MB_2U_LIB.S9S_MB_2U(SCH_1):GND
  108  GND            VSS47  @S9S_MB_2U_LIB.S9S_MB_2U(SCH_1):GND
  106  GND            VSS46  @S9S_MB_2U_LIB.S9S_MB_2U(SCH_1):GND
  103  GND            VSS45  @S9S_MB_2U_LIB.S9S_MB_2U(SCH_1):GND
  101  GND            VSS44  @S9S_MB_2U_LIB.S9S_MB_2U(SCH_1):GND
   99  GND            VSS43  @S9S_MB_2U_LIB.S9S_MB_2U(SCH_1):GND
   97  GND            VSS42  @S9S_MB_2U_LIB.S9S_MB_2U(SCH_1):GND
   95  GND            VSS41  @S9S_MB_2U_LIB.S9S_MB_2U(SCH_1):GND
   92  GND            VSS40  @S9S_MB_2U_LIB.S9S_MB_2U(SCH_1):GND
   90  GND            VSS39  @S9S_MB_2U_LIB.S9S_MB_2U(SCH_1):GND
   88  GND            VSS38  @S9S_MB_2U_LIB.S9S_MB_2U(SCH_1):GND
   85  GND            VSS37  @S9S_MB_2U_LIB.S9S_MB_2U(SCH_1):GND
   83  GND            VSS36  @S9S_MB_2U_LIB.S9S_MB_2U(SCH_1):GND
   81  GND            VSS35  @S9S_MB_2U_LIB.S9S_MB_2U(SCH_1):GND
   79  GND            VSS34  @S9S_MB_2U_LIB.S9S_MB_2U(SCH_1):GND
   77  GND            VSS33  @S9S_MB_2U_LIB.S9S_MB_2U(SCH_1):GND
   75  GND            VSS32  @S9S_MB_2U_LIB.S9S_MB_2U(SCH_1):GND
   73  GND            VSS31  @S9S_MB_2U_LIB.S9S_MB_2U(SCH_1):GND
   71  GND            VSS30  @S9S_MB_2U_LIB.S9S_MB_2U(SCH_1):GND
   69  GND            VSS29  @S9S_MB_2U_LIB.S9S_MB_2U(SCH_1):GND
   67  GND            VSS28  @S9S_MB_2U_LIB.S9S_MB_2U(SCH_1):GND
   65  GND            VSS27  @S9S_MB_2U_LIB.S9S_MB_2U(SCH_1):GND
   63  GND            VSS26  @S9S_MB_2U_LIB.S9S_MB_2U(SCH_1):GND
   61  GND            VSS25  @S9S_MB_2U_LIB.S9S_MB_2U(SCH_1):GND
   59  GND            VSS24  @S9S_MB_2U_LIB.S9S_MB_2U(SCH_1):GND
   57  GND            VSS23  @S9S_MB_2U_LIB.S9S_MB_2U(SCH_1):GND
   54  GND            VSS22  @S9S_MB_2U_LIB.S9S_MB_2U(SCH_1):GND
   52  GND            VSS21  @S9S_MB_2U_LIB.S9S_MB_2U(SCH_1):GND
   50  GND            VSS20  @S9S_MB_2U_LIB.S9S_MB_2U(SCH_1):GND
   48  GND            VSS19  @S9S_MB_2U_LIB.S9S_MB_2U(SCH_1):GND
   46  GND            VSS18  @S9S_MB_2U_LIB.S9S_MB_2U(SCH_1):GND
   43  GND            VSS17  @S9S_MB_2U_LIB.S9S_MB_2U(SCH_1):GND
   41  GND            VSS16  @S9S_MB_2U_LIB.S9S_MB_2U(SCH_1):GND
   39  GND            VSS15  @S9S_MB_2U_LIB.S9S_MB_2U(SCH_1):GND
   37  GND            VSS14  @S9S_MB_2U_LIB.S9S_MB_2U(SCH_1):GND
   35  GND            VSS13  @S9S_MB_2U_LIB.S9S_MB_2U(SCH_1):GND
   32  GND            VSS12  @S9S_MB_2U_LIB.S9S_MB_2U(SCH_1):GND
   30  GND            VSS11  @S9S_MB_2U_LIB.S9S_MB_2U(SCH_1):GND
   28  GND            VSS10  @S9S_MB_2U_LIB.S9S_MB_2U(SCH_1):GND
   26  GND             VSS9  @S9S_MB_2U_LIB.S9S_MB_2U(SCH_1):GND
   24  GND             VSS8  @S9S_MB_2U_LIB.S9S_MB_2U(SCH_1):GND
   21  GND             VSS7  @S9S_MB_2U_LIB.S9S_MB_2U(SCH_1):GND
   19  GND             VSS6  @S9S_MB_2U_LIB.S9S_MB_2U(SCH_1):GND
   17  GND             VSS5  @S9S_MB_2U_LIB.S9S_MB_2U(SCH_1):GND
   15  GND             VSS4  @S9S_MB_2U_LIB.S9S_MB_2U(SCH_1):GND
   13  GND             VSS3  @S9S_MB_2U_LIB.S9S_MB_2U(SCH_1):GND
   10  GND             VSS2  @S9S_MB_2U_LIB.S9S_MB_2U(SCH_1):GND
    8  GND             VSS1  @S9S_MB_2U_LIB.S9S_MB_2U(SCH_1):GND
    6  GND             VSS0  @S9S_MB_2U_LIB.S9S_MB_2U(SCH_1):GND
   G3  GND               G3  @S9S_MB_2U_LIB.S9S_MB_2U(SCH_1):GND
   G2  GND               G2  @S9S_MB_2U_LIB.S9S_MB_2U(SCH_1):GND
   G1  GND               G1  @S9S_MB_2U_LIB.S9S_MB_2U(SCH_1):GND

SCONN288_ADR50001P003C01  I178  J26    [SCONN288_ADR50001P003C01-SCONNA]
   93  M_E_CPU1_SB_DQS_DP<9>  DQS9_B_P  @S9S_MB_2U_LIB.S9S_MB_2U(SCH_1):M_E_CPU1_SB_DQS_DP<9>
  283  M_E_CPU1_SB_DQS_DP<8>  DQS8_B_P  @S9S_MB_2U_LIB.S9S_MB_2U(SCH_1):M_E_CPU1_SB_DQS_DP<8>
  272  M_E_CPU1_SB_DQS_DP<7>  DQS7_B_P  @S9S_MB_2U_LIB.S9S_MB_2U(SCH_1):M_E_CPU1_SB_DQS_DP<7>
  261  M_E_CPU1_SB_DQS_DP<6>  DQS6_B_P  @S9S_MB_2U_LIB.S9S_MB_2U(SCH_1):M_E_CPU1_SB_DQS_DP<6>
  250  M_E_CPU1_SB_DQS_DP<5>  DQS5_B_P  @S9S_MB_2U_LIB.S9S_MB_2U(SCH_1):M_E_CPU1_SB_DQS_DP<5>
  239  M_E_CPU1_SB_DQS_DP<4>  DQS4_B_P  @S9S_MB_2U_LIB.S9S_MB_2U(SCH_1):M_E_CPU1_SB_DQS_DP<4>
  137  M_E_CPU1_SB_DQS_DP<3>  DQS3_B_P  @S9S_MB_2U_LIB.S9S_MB_2U(SCH_1):M_E_CPU1_SB_DQS_DP<3>
  126  M_E_CPU1_SB_DQS_DP<2>  DQS2_B_P  @S9S_MB_2U_LIB.S9S_MB_2U(SCH_1):M_E_CPU1_SB_DQS_DP<2>
  115  M_E_CPU1_SB_DQS_DP<1>  DQS1_B_P  @S9S_MB_2U_LIB.S9S_MB_2U(SCH_1):M_E_CPU1_SB_DQS_DP<1>
  104  M_E_CPU1_SB_DQS_DP<0>  DQS0_B_P  @S9S_MB_2U_LIB.S9S_MB_2U(SCH_1):M_E_CPU1_SB_DQS_DP<0>
   94  M_E_CPU1_SB_DQS_DN<9>  DQS9_B_N  @S9S_MB_2U_LIB.S9S_MB_2U(SCH_1):M_E_CPU1_SB_DQS_DN<9>
  282  M_E_CPU1_SB_DQS_DN<8>  DQS8_B_N  @S9S_MB_2U_LIB.S9S_MB_2U(SCH_1):M_E_CPU1_SB_DQS_DN<8>
  271  M_E_CPU1_SB_DQS_DN<7>  DQS7_B_N  @S9S_MB_2U_LIB.S9S_MB_2U(SCH_1):M_E_CPU1_SB_DQS_DN<7>
  260  M_E_CPU1_SB_DQS_DN<6>  DQS6_B_N  @S9S_MB_2U_LIB.S9S_MB_2U(SCH_1):M_E_CPU1_SB_DQS_DN<6>
  249  M_E_CPU1_SB_DQS_DN<5>  DQS5_B_N  @S9S_MB_2U_LIB.S9S_MB_2U(SCH_1):M_E_CPU1_SB_DQS_DN<5>
  238  M_E_CPU1_SB_DQS_DN<4>  DQS4_B_N  @S9S_MB_2U_LIB.S9S_MB_2U(SCH_1):M_E_CPU1_SB_DQS_DN<4>
  138  M_E_CPU1_SB_DQS_DN<3>  DQS3_B_N  @S9S_MB_2U_LIB.S9S_MB_2U(SCH_1):M_E_CPU1_SB_DQS_DN<3>
  127  M_E_CPU1_SB_DQS_DN<2>  DQS2_B_N  @S9S_MB_2U_LIB.S9S_MB_2U(SCH_1):M_E_CPU1_SB_DQS_DN<2>
  116  M_E_CPU1_SB_DQS_DN<1>  DQS1_B_N  @S9S_MB_2U_LIB.S9S_MB_2U(SCH_1):M_E_CPU1_SB_DQS_DN<1>
  105  M_E_CPU1_SB_DQS_DN<0>  DQS0_B_N  @S9S_MB_2U_LIB.S9S_MB_2U(SCH_1):M_E_CPU1_SB_DQS_DN<0>
  201  M_E_CPU1_SA_DQS_DP<9>  DQS9_A_P  @S9S_MB_2U_LIB.S9S_MB_2U(SCH_1):M_E_CPU1_SA_DQS_DP<9>
  190  M_E_CPU1_SA_DQS_DP<8>  DQS8_A_P  @S9S_MB_2U_LIB.S9S_MB_2U(SCH_1):M_E_CPU1_SA_DQS_DP<8>
  179  M_E_CPU1_SA_DQS_DP<7>  DQS7_A_P  @S9S_MB_2U_LIB.S9S_MB_2U(SCH_1):M_E_CPU1_SA_DQS_DP<7>
  168  M_E_CPU1_SA_DQS_DP<6>  DQS6_A_P  @S9S_MB_2U_LIB.S9S_MB_2U(SCH_1):M_E_CPU1_SA_DQS_DP<6>
  157  M_E_CPU1_SA_DQS_DP<5>  DQS5_A_P  @S9S_MB_2U_LIB.S9S_MB_2U(SCH_1):M_E_CPU1_SA_DQS_DP<5>
   55  M_E_CPU1_SA_DQS_DP<4>  DQS4_A_P  @S9S_MB_2U_LIB.S9S_MB_2U(SCH_1):M_E_CPU1_SA_DQS_DP<4>
   44  M_E_CPU1_SA_DQS_DP<3>  DQS3_A_P  @S9S_MB_2U_LIB.S9S_MB_2U(SCH_1):M_E_CPU1_SA_DQS_DP<3>
   33  M_E_CPU1_SA_DQS_DP<2>  DQS2_A_P  @S9S_MB_2U_LIB.S9S_MB_2U(SCH_1):M_E_CPU1_SA_DQS_DP<2>
   22  M_E_CPU1_SA_DQS_DP<1>  DQS1_A_P  @S9S_MB_2U_LIB.S9S_MB_2U(SCH_1):M_E_CPU1_SA_DQS_DP<1>
   11  M_E_CPU1_SA_DQS_DP<0>  DQS0_A_P  @S9S_MB_2U_LIB.S9S_MB_2U(SCH_1):M_E_CPU1_SA_DQS_DP<0>
  200  M_E_CPU1_SA_DQS_DN<9>  DQS9_A_N  @S9S_MB_2U_LIB.S9S_MB_2U(SCH_1):M_E_CPU1_SA_DQS_DN<9>
  189  M_E_CPU1_SA_DQS_DN<8>  DQS8_A_N  @S9S_MB_2U_LIB.S9S_MB_2U(SCH_1):M_E_CPU1_SA_DQS_DN<8>
  178  M_E_CPU1_SA_DQS_DN<7>  DQS7_A_N  @S9S_MB_2U_LIB.S9S_MB_2U(SCH_1):M_E_CPU1_SA_DQS_DN<7>
  167  M_E_CPU1_SA_DQS_DN<6>  DQS6_A_N  @S9S_MB_2U_LIB.S9S_MB_2U(SCH_1):M_E_CPU1_SA_DQS_DN<6>
  156  M_E_CPU1_SA_DQS_DN<5>  DQS5_A_N  @S9S_MB_2U_LIB.S9S_MB_2U(SCH_1):M_E_CPU1_SA_DQS_DN<5>
   56  M_E_CPU1_SA_DQS_DN<4>  DQS4_A_N  @S9S_MB_2U_LIB.S9S_MB_2U(SCH_1):M_E_CPU1_SA_DQS_DN<4>
   45  M_E_CPU1_SA_DQS_DN<3>  DQS3_A_N  @S9S_MB_2U_LIB.S9S_MB_2U(SCH_1):M_E_CPU1_SA_DQS_DN<3>
   34  M_E_CPU1_SA_DQS_DN<2>  DQS2_A_N  @S9S_MB_2U_LIB.S9S_MB_2U(SCH_1):M_E_CPU1_SA_DQS_DN<2>
   23  M_E_CPU1_SA_DQS_DN<1>  DQS1_A_N  @S9S_MB_2U_LIB.S9S_MB_2U(SCH_1):M_E_CPU1_SA_DQS_DN<1>
   12  M_E_CPU1_SA_DQS_DN<0>  DQS0_A_N  @S9S_MB_2U_LIB.S9S_MB_2U(SCH_1):M_E_CPU1_SA_DQS_DN<0>

SCONN288_ADR50001P003C01  I180  J26    [SCONN288_ADR50001P003C01-SCONNA]
  232  NC              RFU6  NC
  231  NC              RFU5  NC
  220  NC              RFU4  NC
  150  NC              RFU3  NC
  149  NC              RFU2  NC
  144  NC              RFU1  NC
    2  NC              RFU0  NC
  207  RST_M_EF_CPU1_FPGA_N  RESET_N  @S9S_MB_2U_LIB.S9S_MB_2U(SCH_1):RST_M_EF_CPU1_FPGA_N
  147  PWRGD_CHE_CPU1_DIMM2  PWR_GOOD||FAIL_N  @S9S_MB_2U_LIB.S9S_MB_2U(SCH_1):PWRGD_CHE_CPU1_DIMM2
  148  PD_CHE_CPU1_DIMM2_SAA    HAS  @S9S_MB_2U_LIB.S9S_MB_2U(SCH_1):PD_CHE_CPU1_DIMM2_SAA
    3  P3V3_AUX       VIN_MGMT  @S9S_MB_2U_LIB.S9S_MB_2U(SCH_1):P3V3_AUX
   87  M_E_CPU1_SB_RSP<1>  LBS||RSP_N_B  @S9S_MB_2U_LIB.S9S_MB_2U(SCH_1):M_E_CPU1_SB_RSP<1>
  227  M_E_CPU1_SB_PAR  PAR_B  @S9S_MB_2U_LIB.S9S_MB_2U(SCH_1):M_E_CPU1_SB_PAR
  113  M_E_CPU1_SB_DQ<9>  DQ_B9  @S9S_MB_2U_LIB.S9S_MB_2U(SCH_1):M_E_CPU1_SB_DQ<9>
  111  M_E_CPU1_SB_DQ<8>  DQ_B8  @S9S_MB_2U_LIB.S9S_MB_2U(SCH_1):M_E_CPU1_SB_DQ<8>
  254  M_E_CPU1_SB_DQ<7>  DQ_B7  @S9S_MB_2U_LIB.S9S_MB_2U(SCH_1):M_E_CPU1_SB_DQ<7>
  252  M_E_CPU1_SB_DQ<6>  DQ_B6  @S9S_MB_2U_LIB.S9S_MB_2U(SCH_1):M_E_CPU1_SB_DQ<6>
  109  M_E_CPU1_SB_DQ<5>  DQ_B5  @S9S_MB_2U_LIB.S9S_MB_2U(SCH_1):M_E_CPU1_SB_DQ<5>
  107  M_E_CPU1_SB_DQ<4>  DQ_B4  @S9S_MB_2U_LIB.S9S_MB_2U(SCH_1):M_E_CPU1_SB_DQ<4>
  247  M_E_CPU1_SB_DQ<3>  DQ_B3  @S9S_MB_2U_LIB.S9S_MB_2U(SCH_1):M_E_CPU1_SB_DQ<3>
  287  M_E_CPU1_SB_DQ<31>  DQ_B31  @S9S_MB_2U_LIB.S9S_MB_2U(SCH_1):M_E_CPU1_SB_DQ<31>
  285  M_E_CPU1_SB_DQ<30>  DQ_B30  @S9S_MB_2U_LIB.S9S_MB_2U(SCH_1):M_E_CPU1_SB_DQ<30>
  245  M_E_CPU1_SB_DQ<2>  DQ_B2  @S9S_MB_2U_LIB.S9S_MB_2U(SCH_1):M_E_CPU1_SB_DQ<2>
  142  M_E_CPU1_SB_DQ<29>  DQ_B29  @S9S_MB_2U_LIB.S9S_MB_2U(SCH_1):M_E_CPU1_SB_DQ<29>
  140  M_E_CPU1_SB_DQ<28>  DQ_B28  @S9S_MB_2U_LIB.S9S_MB_2U(SCH_1):M_E_CPU1_SB_DQ<28>
  280  M_E_CPU1_SB_DQ<27>  DQ_B27  @S9S_MB_2U_LIB.S9S_MB_2U(SCH_1):M_E_CPU1_SB_DQ<27>
  278  M_E_CPU1_SB_DQ<26>  DQ_B26  @S9S_MB_2U_LIB.S9S_MB_2U(SCH_1):M_E_CPU1_SB_DQ<26>
  135  M_E_CPU1_SB_DQ<25>  DQ_B25  @S9S_MB_2U_LIB.S9S_MB_2U(SCH_1):M_E_CPU1_SB_DQ<25>
  133  M_E_CPU1_SB_DQ<24>  DQ_B24  @S9S_MB_2U_LIB.S9S_MB_2U(SCH_1):M_E_CPU1_SB_DQ<24>
  276  M_E_CPU1_SB_DQ<23>  DQ_B23  @S9S_MB_2U_LIB.S9S_MB_2U(SCH_1):M_E_CPU1_SB_DQ<23>
  274  M_E_CPU1_SB_DQ<22>  DQ_B22  @S9S_MB_2U_LIB.S9S_MB_2U(SCH_1):M_E_CPU1_SB_DQ<22>
  131  M_E_CPU1_SB_DQ<21>  DQ_B21  @S9S_MB_2U_LIB.S9S_MB_2U(SCH_1):M_E_CPU1_SB_DQ<21>
  129  M_E_CPU1_SB_DQ<20>  DQ_B20  @S9S_MB_2U_LIB.S9S_MB_2U(SCH_1):M_E_CPU1_SB_DQ<20>
  102  M_E_CPU1_SB_DQ<1>  DQ_B1  @S9S_MB_2U_LIB.S9S_MB_2U(SCH_1):M_E_CPU1_SB_DQ<1>
  269  M_E_CPU1_SB_DQ<19>  DQ_B19  @S9S_MB_2U_LIB.S9S_MB_2U(SCH_1):M_E_CPU1_SB_DQ<19>
  267  M_E_CPU1_SB_DQ<18>  DQ_B18  @S9S_MB_2U_LIB.S9S_MB_2U(SCH_1):M_E_CPU1_SB_DQ<18>
  124  M_E_CPU1_SB_DQ<17>  DQ_B17  @S9S_MB_2U_LIB.S9S_MB_2U(SCH_1):M_E_CPU1_SB_DQ<17>
  122  M_E_CPU1_SB_DQ<16>  DQ_B16  @S9S_MB_2U_LIB.S9S_MB_2U(SCH_1):M_E_CPU1_SB_DQ<16>
  265  M_E_CPU1_SB_DQ<15>  DQ_B15  @S9S_MB_2U_LIB.S9S_MB_2U(SCH_1):M_E_CPU1_SB_DQ<15>
  263  M_E_CPU1_SB_DQ<14>  DQ_B14  @S9S_MB_2U_LIB.S9S_MB_2U(SCH_1):M_E_CPU1_SB_DQ<14>
  120  M_E_CPU1_SB_DQ<13>  DQ_B13  @S9S_MB_2U_LIB.S9S_MB_2U(SCH_1):M_E_CPU1_SB_DQ<13>
  118  M_E_CPU1_SB_DQ<12>  DQ_B12  @S9S_MB_2U_LIB.S9S_MB_2U(SCH_1):M_E_CPU1_SB_DQ<12>
  258  M_E_CPU1_SB_DQ<11>  DQ_B11  @S9S_MB_2U_LIB.S9S_MB_2U(SCH_1):M_E_CPU1_SB_DQ<11>
  256  M_E_CPU1_SB_DQ<10>  DQ_B10  @S9S_MB_2U_LIB.S9S_MB_2U(SCH_1):M_E_CPU1_SB_DQ<10>
  100  M_E_CPU1_SB_DQ<0>  DQ_B0  @S9S_MB_2U_LIB.S9S_MB_2U(SCH_1):M_E_CPU1_SB_DQ<0>
  229  M_E_CPU1_SB_CS_N<3>  CS1_N_B  @S9S_MB_2U_LIB.S9S_MB_2U(SCH_1):M_E_CPU1_SB_CS_N<3>
   84  M_E_CPU1_SB_CS_N<2>  CS0_N_B  @S9S_MB_2U_LIB.S9S_MB_2U(SCH_1):M_E_CPU1_SB_CS_N<2>
  236  M_E_CPU1_SB_CB<7>  CB_B7  @S9S_MB_2U_LIB.S9S_MB_2U(SCH_1):M_E_CPU1_SB_CB<7>
  234  M_E_CPU1_SB_CB<6>  CB_B6  @S9S_MB_2U_LIB.S9S_MB_2U(SCH_1):M_E_CPU1_SB_CB<6>
   91  M_E_CPU1_SB_CB<5>  CB_B5  @S9S_MB_2U_LIB.S9S_MB_2U(SCH_1):M_E_CPU1_SB_CB<5>
   89  M_E_CPU1_SB_CB<4>  CB_B4  @S9S_MB_2U_LIB.S9S_MB_2U(SCH_1):M_E_CPU1_SB_CB<4>
  243  M_E_CPU1_SB_CB<3>  CB_B3  @S9S_MB_2U_LIB.S9S_MB_2U(SCH_1):M_E_CPU1_SB_CB<3>
  241  M_E_CPU1_SB_CB<2>  CB_B2  @S9S_MB_2U_LIB.S9S_MB_2U(SCH_1):M_E_CPU1_SB_CB<2>
   98  M_E_CPU1_SB_CB<1>  CB_B1  @S9S_MB_2U_LIB.S9S_MB_2U(SCH_1):M_E_CPU1_SB_CB<1>
   96  M_E_CPU1_SB_CB<0>  CB_B0  @S9S_MB_2U_LIB.S9S_MB_2U(SCH_1):M_E_CPU1_SB_CB<0>
   82  M_E_CPU1_SB_CA<6>  CA6_B  @S9S_MB_2U_LIB.S9S_MB_2U(SCH_1):M_E_CPU1_SB_CA<6>
  225  M_E_CPU1_SB_CA<5>  CA5_B  @S9S_MB_2U_LIB.S9S_MB_2U(SCH_1):M_E_CPU1_SB_CA<5>
   80  M_E_CPU1_SB_CA<4>  CA4_B  @S9S_MB_2U_LIB.S9S_MB_2U(SCH_1):M_E_CPU1_SB_CA<4>
  223  M_E_CPU1_SB_CA<3>  CA3_B  @S9S_MB_2U_LIB.S9S_MB_2U(SCH_1):M_E_CPU1_SB_CA<3>
   78  M_E_CPU1_SB_CA<2>  CA2_B  @S9S_MB_2U_LIB.S9S_MB_2U(SCH_1):M_E_CPU1_SB_CA<2>
  221  M_E_CPU1_SB_CA<1>  CA1_B  @S9S_MB_2U_LIB.S9S_MB_2U(SCH_1):M_E_CPU1_SB_CA<1>
   76  M_E_CPU1_SB_CA<0>  CA0_B  @S9S_MB_2U_LIB.S9S_MB_2U(SCH_1):M_E_CPU1_SB_CA<0>
   86  M_E_CPU1_SA_RSP<1>  LBD||RSP_N_A  @S9S_MB_2U_LIB.S9S_MB_2U(SCH_1):M_E_CPU1_SA_RSP<1>
   74  M_E_CPU1_SA_PAR  PAR_A  @S9S_MB_2U_LIB.S9S_MB_2U(SCH_1):M_E_CPU1_SA_PAR
   20  M_E_CPU1_SA_DQ<9>  DQ_A9  @S9S_MB_2U_LIB.S9S_MB_2U(SCH_1):M_E_CPU1_SA_DQ<9>
   18  M_E_CPU1_SA_DQ<8>  DQ_A8  @S9S_MB_2U_LIB.S9S_MB_2U(SCH_1):M_E_CPU1_SA_DQ<8>
  161  M_E_CPU1_SA_DQ<7>  DQ_A7  @S9S_MB_2U_LIB.S9S_MB_2U(SCH_1):M_E_CPU1_SA_DQ<7>
  159  M_E_CPU1_SA_DQ<6>  DQ_A6  @S9S_MB_2U_LIB.S9S_MB_2U(SCH_1):M_E_CPU1_SA_DQ<6>
   16  M_E_CPU1_SA_DQ<5>  DQ_A5  @S9S_MB_2U_LIB.S9S_MB_2U(SCH_1):M_E_CPU1_SA_DQ<5>
   14  M_E_CPU1_SA_DQ<4>  DQ_A4  @S9S_MB_2U_LIB.S9S_MB_2U(SCH_1):M_E_CPU1_SA_DQ<4>
  154  M_E_CPU1_SA_DQ<3>  DQ_A3  @S9S_MB_2U_LIB.S9S_MB_2U(SCH_1):M_E_CPU1_SA_DQ<3>
  194  M_E_CPU1_SA_DQ<31>  DQ_A31  @S9S_MB_2U_LIB.S9S_MB_2U(SCH_1):M_E_CPU1_SA_DQ<31>
  192  M_E_CPU1_SA_DQ<30>  DQ_A30  @S9S_MB_2U_LIB.S9S_MB_2U(SCH_1):M_E_CPU1_SA_DQ<30>
  152  M_E_CPU1_SA_DQ<2>  DQ_A2  @S9S_MB_2U_LIB.S9S_MB_2U(SCH_1):M_E_CPU1_SA_DQ<2>
   49  M_E_CPU1_SA_DQ<29>  DQ_A29  @S9S_MB_2U_LIB.S9S_MB_2U(SCH_1):M_E_CPU1_SA_DQ<29>
   47  M_E_CPU1_SA_DQ<28>  DQ_A28  @S9S_MB_2U_LIB.S9S_MB_2U(SCH_1):M_E_CPU1_SA_DQ<28>
  187  M_E_CPU1_SA_DQ<27>  DQ_A27  @S9S_MB_2U_LIB.S9S_MB_2U(SCH_1):M_E_CPU1_SA_DQ<27>
  185  M_E_CPU1_SA_DQ<26>  DQ_A26  @S9S_MB_2U_LIB.S9S_MB_2U(SCH_1):M_E_CPU1_SA_DQ<26>
   42  M_E_CPU1_SA_DQ<25>  DQ_A25  @S9S_MB_2U_LIB.S9S_MB_2U(SCH_1):M_E_CPU1_SA_DQ<25>
   40  M_E_CPU1_SA_DQ<24>  DQ_A24  @S9S_MB_2U_LIB.S9S_MB_2U(SCH_1):M_E_CPU1_SA_DQ<24>
  183  M_E_CPU1_SA_DQ<23>  DQ_A23  @S9S_MB_2U_LIB.S9S_MB_2U(SCH_1):M_E_CPU1_SA_DQ<23>
  181  M_E_CPU1_SA_DQ<22>  DQ_A22  @S9S_MB_2U_LIB.S9S_MB_2U(SCH_1):M_E_CPU1_SA_DQ<22>
   38  M_E_CPU1_SA_DQ<21>  DQ_A21  @S9S_MB_2U_LIB.S9S_MB_2U(SCH_1):M_E_CPU1_SA_DQ<21>
   36  M_E_CPU1_SA_DQ<20>  DQ_A20  @S9S_MB_2U_LIB.S9S_MB_2U(SCH_1):M_E_CPU1_SA_DQ<20>
    9  M_E_CPU1_SA_DQ<1>  DQ_A1  @S9S_MB_2U_LIB.S9S_MB_2U(SCH_1):M_E_CPU1_SA_DQ<1>
  176  M_E_CPU1_SA_DQ<19>  DQ_A19  @S9S_MB_2U_LIB.S9S_MB_2U(SCH_1):M_E_CPU1_SA_DQ<19>
  174  M_E_CPU1_SA_DQ<18>  DQ_A18  @S9S_MB_2U_LIB.S9S_MB_2U(SCH_1):M_E_CPU1_SA_DQ<18>
   31  M_E_CPU1_SA_DQ<17>  DQ_A17  @S9S_MB_2U_LIB.S9S_MB_2U(SCH_1):M_E_CPU1_SA_DQ<17>
   29  M_E_CPU1_SA_DQ<16>  DQ_A16  @S9S_MB_2U_LIB.S9S_MB_2U(SCH_1):M_E_CPU1_SA_DQ<16>
  172  M_E_CPU1_SA_DQ<15>  DQ_A15  @S9S_MB_2U_LIB.S9S_MB_2U(SCH_1):M_E_CPU1_SA_DQ<15>
  170  M_E_CPU1_SA_DQ<14>  DQ_A14  @S9S_MB_2U_LIB.S9S_MB_2U(SCH_1):M_E_CPU1_SA_DQ<14>
   27  M_E_CPU1_SA_DQ<13>  DQ_A13  @S9S_MB_2U_LIB.S9S_MB_2U(SCH_1):M_E_CPU1_SA_DQ<13>
   25  M_E_CPU1_SA_DQ<12>  DQ_A12  @S9S_MB_2U_LIB.S9S_MB_2U(SCH_1):M_E_CPU1_SA_DQ<12>
  165  M_E_CPU1_SA_DQ<11>  DQ_A11  @S9S_MB_2U_LIB.S9S_MB_2U(SCH_1):M_E_CPU1_SA_DQ<11>
  163  M_E_CPU1_SA_DQ<10>  DQ_A10  @S9S_MB_2U_LIB.S9S_MB_2U(SCH_1):M_E_CPU1_SA_DQ<10>
    7  M_E_CPU1_SA_DQ<0>  DQ_A0  @S9S_MB_2U_LIB.S9S_MB_2U(SCH_1):M_E_CPU1_SA_DQ<0>
  209  M_E_CPU1_SA_CS_N<3>  CS1_N_A  @S9S_MB_2U_LIB.S9S_MB_2U(SCH_1):M_E_CPU1_SA_CS_N<3>
   64  M_E_CPU1_SA_CS_N<2>  CS0_N_A  @S9S_MB_2U_LIB.S9S_MB_2U(SCH_1):M_E_CPU1_SA_CS_N<2>
  205  M_E_CPU1_SA_CB<7>  CB_A7  @S9S_MB_2U_LIB.S9S_MB_2U(SCH_1):M_E_CPU1_SA_CB<7>
  203  M_E_CPU1_SA_CB<6>  CB_A6  @S9S_MB_2U_LIB.S9S_MB_2U(SCH_1):M_E_CPU1_SA_CB<6>
   60  M_E_CPU1_SA_CB<5>  CB_A5  @S9S_MB_2U_LIB.S9S_MB_2U(SCH_1):M_E_CPU1_SA_CB<5>
   58  M_E_CPU1_SA_CB<4>  CB_A4  @S9S_MB_2U_LIB.S9S_MB_2U(SCH_1):M_E_CPU1_SA_CB<4>
  198  M_E_CPU1_SA_CB<3>  CB_A3  @S9S_MB_2U_LIB.S9S_MB_2U(SCH_1):M_E_CPU1_SA_CB<3>
  196  M_E_CPU1_SA_CB<2>  CB_A2  @S9S_MB_2U_LIB.S9S_MB_2U(SCH_1):M_E_CPU1_SA_CB<2>
   53  M_E_CPU1_SA_CB<1>  CB_A1  @S9S_MB_2U_LIB.S9S_MB_2U(SCH_1):M_E_CPU1_SA_CB<1>
   51  M_E_CPU1_SA_CB<0>  CB_A0  @S9S_MB_2U_LIB.S9S_MB_2U(SCH_1):M_E_CPU1_SA_CB<0>
   72  M_E_CPU1_SA_CA<6>  CA6_A  @S9S_MB_2U_LIB.S9S_MB_2U(SCH_1):M_E_CPU1_SA_CA<6>
  215  M_E_CPU1_SA_CA<5>  CA5_A  @S9S_MB_2U_LIB.S9S_MB_2U(SCH_1):M_E_CPU1_SA_CA<5>
   70  M_E_CPU1_SA_CA<4>  CA4_A  @S9S_MB_2U_LIB.S9S_MB_2U(SCH_1):M_E_CPU1_SA_CA<4>
  213  M_E_CPU1_SA_CA<3>  CA3_A  @S9S_MB_2U_LIB.S9S_MB_2U(SCH_1):M_E_CPU1_SA_CA<3>
   68  M_E_CPU1_SA_CA<2>  CA2_A  @S9S_MB_2U_LIB.S9S_MB_2U(SCH_1):M_E_CPU1_SA_CA<2>
  211  M_E_CPU1_SA_CA<1>  CA1_A  @S9S_MB_2U_LIB.S9S_MB_2U(SCH_1):M_E_CPU1_SA_CA<1>
   66  M_E_CPU1_SA_CA<0>  CA0_A  @S9S_MB_2U_LIB.S9S_MB_2U(SCH_1):M_E_CPU1_SA_CA<0>
  217  M_E_CPU1_CLK_DP<1>   CK_P  @S9S_MB_2U_LIB.S9S_MB_2U(SCH_1):M_E_CPU1_CLK_DP<1>
  218  M_E_CPU1_CLK_DN<1>   CK_N  @S9S_MB_2U_LIB.S9S_MB_2U(SCH_1):M_E_CPU1_CLK_DN<1>
   62  M_E_CPU1_ALERT_N  ALERT_N  @S9S_MB_2U_LIB.S9S_MB_2U(SCH_1):M_E_CPU1_ALERT_N
    5  I3C_SPD_DDREFGH_CPU1_LVC1_SDA   HSDA  @S9S_MB_2U_LIB.S9S_MB_2U(SCH_1):I3C_SPD_DDREFGH_CPU1_LVC1_SDA
    4  I3C_SPD_DDREFGH_CPU1_LVC1_SCL   HSCL  @S9S_MB_2U_LIB.S9S_MB_2U(SCH_1):I3C_SPD_DDREFGH_CPU1_LVC1_SCL

SCONN288_ADR50001P013C01  I178  J27    [SCONN288_ADR50001P013C01-SCONNA]
  146  P12V_S3_AUX_CPU1_NVDIMM  VIN_BULK2  @S9S_MB_2U_LIB.S9S_MB_2U(SCH_1):P12V_S3_AUX_CPU1_NVDIMM
  145  P12V_S3_AUX_CPU1_NVDIMM  VIN_BULK1  @S9S_MB_2U_LIB.S9S_MB_2U(SCH_1):P12V_S3_AUX_CPU1_NVDIMM
    1  P12V_S3_AUX_CPU1_NVDIMM  VIN_BULK0  @S9S_MB_2U_LIB.S9S_MB_2U(SCH_1):P12V_S3_AUX_CPU1_NVDIMM
  288  GND            VSS126  @S9S_MB_2U_LIB.S9S_MB_2U(SCH_1):GND
  286  GND            VSS125  @S9S_MB_2U_LIB.S9S_MB_2U(SCH_1):GND
  284  GND            VSS124  @S9S_MB_2U_LIB.S9S_MB_2U(SCH_1):GND
  281  GND            VSS123  @S9S_MB_2U_LIB.S9S_MB_2U(SCH_1):GND
  279  GND            VSS122  @S9S_MB_2U_LIB.S9S_MB_2U(SCH_1):GND
  277  GND            VSS121  @S9S_MB_2U_LIB.S9S_MB_2U(SCH_1):GND
  275  GND            VSS120  @S9S_MB_2U_LIB.S9S_MB_2U(SCH_1):GND
  273  GND            VSS119  @S9S_MB_2U_LIB.S9S_MB_2U(SCH_1):GND
  270  GND            VSS118  @S9S_MB_2U_LIB.S9S_MB_2U(SCH_1):GND
  268  GND            VSS117  @S9S_MB_2U_LIB.S9S_MB_2U(SCH_1):GND
  266  GND            VSS116  @S9S_MB_2U_LIB.S9S_MB_2U(SCH_1):GND
  264  GND            VSS115  @S9S_MB_2U_LIB.S9S_MB_2U(SCH_1):GND
  262  GND            VSS114  @S9S_MB_2U_LIB.S9S_MB_2U(SCH_1):GND
  259  GND            VSS113  @S9S_MB_2U_LIB.S9S_MB_2U(SCH_1):GND
  257  GND            VSS112  @S9S_MB_2U_LIB.S9S_MB_2U(SCH_1):GND
  255  GND            VSS111  @S9S_MB_2U_LIB.S9S_MB_2U(SCH_1):GND
  253  GND            VSS110  @S9S_MB_2U_LIB.S9S_MB_2U(SCH_1):GND
  251  GND            VSS109  @S9S_MB_2U_LIB.S9S_MB_2U(SCH_1):GND
  248  GND            VSS108  @S9S_MB_2U_LIB.S9S_MB_2U(SCH_1):GND
  246  GND            VSS107  @S9S_MB_2U_LIB.S9S_MB_2U(SCH_1):GND
  244  GND            VSS106  @S9S_MB_2U_LIB.S9S_MB_2U(SCH_1):GND
  242  GND            VSS105  @S9S_MB_2U_LIB.S9S_MB_2U(SCH_1):GND
  240  GND            VSS104  @S9S_MB_2U_LIB.S9S_MB_2U(SCH_1):GND
  237  GND            VSS103  @S9S_MB_2U_LIB.S9S_MB_2U(SCH_1):GND
  235  GND            VSS102  @S9S_MB_2U_LIB.S9S_MB_2U(SCH_1):GND
  233  GND            VSS101  @S9S_MB_2U_LIB.S9S_MB_2U(SCH_1):GND
  230  GND            VSS100  @S9S_MB_2U_LIB.S9S_MB_2U(SCH_1):GND
  228  GND            VSS99  @S9S_MB_2U_LIB.S9S_MB_2U(SCH_1):GND
  226  GND            VSS98  @S9S_MB_2U_LIB.S9S_MB_2U(SCH_1):GND
  224  GND            VSS97  @S9S_MB_2U_LIB.S9S_MB_2U(SCH_1):GND
  222  GND            VSS96  @S9S_MB_2U_LIB.S9S_MB_2U(SCH_1):GND
  219  GND            VSS95  @S9S_MB_2U_LIB.S9S_MB_2U(SCH_1):GND
  216  GND            VSS94  @S9S_MB_2U_LIB.S9S_MB_2U(SCH_1):GND
  214  GND            VSS93  @S9S_MB_2U_LIB.S9S_MB_2U(SCH_1):GND
  212  GND            VSS92  @S9S_MB_2U_LIB.S9S_MB_2U(SCH_1):GND
  210  GND            VSS91  @S9S_MB_2U_LIB.S9S_MB_2U(SCH_1):GND
  208  GND            VSS90  @S9S_MB_2U_LIB.S9S_MB_2U(SCH_1):GND
  206  GND            VSS89  @S9S_MB_2U_LIB.S9S_MB_2U(SCH_1):GND
  204  GND            VSS88  @S9S_MB_2U_LIB.S9S_MB_2U(SCH_1):GND
  202  GND            VSS87  @S9S_MB_2U_LIB.S9S_MB_2U(SCH_1):GND
  199  GND            VSS86  @S9S_MB_2U_LIB.S9S_MB_2U(SCH_1):GND
  197  GND            VSS85  @S9S_MB_2U_LIB.S9S_MB_2U(SCH_1):GND
  195  GND            VSS84  @S9S_MB_2U_LIB.S9S_MB_2U(SCH_1):GND
  193  GND            VSS83  @S9S_MB_2U_LIB.S9S_MB_2U(SCH_1):GND
  191  GND            VSS82  @S9S_MB_2U_LIB.S9S_MB_2U(SCH_1):GND
  188  GND            VSS81  @S9S_MB_2U_LIB.S9S_MB_2U(SCH_1):GND
  186  GND            VSS80  @S9S_MB_2U_LIB.S9S_MB_2U(SCH_1):GND
  184  GND            VSS79  @S9S_MB_2U_LIB.S9S_MB_2U(SCH_1):GND
  182  GND            VSS78  @S9S_MB_2U_LIB.S9S_MB_2U(SCH_1):GND
  180  GND            VSS77  @S9S_MB_2U_LIB.S9S_MB_2U(SCH_1):GND
  177  GND            VSS76  @S9S_MB_2U_LIB.S9S_MB_2U(SCH_1):GND
  175  GND            VSS75  @S9S_MB_2U_LIB.S9S_MB_2U(SCH_1):GND
  173  GND            VSS74  @S9S_MB_2U_LIB.S9S_MB_2U(SCH_1):GND
  171  GND            VSS73  @S9S_MB_2U_LIB.S9S_MB_2U(SCH_1):GND
  169  GND            VSS72  @S9S_MB_2U_LIB.S9S_MB_2U(SCH_1):GND
  166  GND            VSS71  @S9S_MB_2U_LIB.S9S_MB_2U(SCH_1):GND
  164  GND            VSS70  @S9S_MB_2U_LIB.S9S_MB_2U(SCH_1):GND
  162  GND            VSS69  @S9S_MB_2U_LIB.S9S_MB_2U(SCH_1):GND
  160  GND            VSS68  @S9S_MB_2U_LIB.S9S_MB_2U(SCH_1):GND
  158  GND            VSS67  @S9S_MB_2U_LIB.S9S_MB_2U(SCH_1):GND
  155  GND            VSS66  @S9S_MB_2U_LIB.S9S_MB_2U(SCH_1):GND
  153  GND            VSS65  @S9S_MB_2U_LIB.S9S_MB_2U(SCH_1):GND
  151  GND            VSS64  @S9S_MB_2U_LIB.S9S_MB_2U(SCH_1):GND
  143  GND            VSS63  @S9S_MB_2U_LIB.S9S_MB_2U(SCH_1):GND
  141  GND            VSS62  @S9S_MB_2U_LIB.S9S_MB_2U(SCH_1):GND
  139  GND            VSS61  @S9S_MB_2U_LIB.S9S_MB_2U(SCH_1):GND
  136  GND            VSS60  @S9S_MB_2U_LIB.S9S_MB_2U(SCH_1):GND
  134  GND            VSS59  @S9S_MB_2U_LIB.S9S_MB_2U(SCH_1):GND
  132  GND            VSS58  @S9S_MB_2U_LIB.S9S_MB_2U(SCH_1):GND
  130  GND            VSS57  @S9S_MB_2U_LIB.S9S_MB_2U(SCH_1):GND
  128  GND            VSS56  @S9S_MB_2U_LIB.S9S_MB_2U(SCH_1):GND
  125  GND            VSS55  @S9S_MB_2U_LIB.S9S_MB_2U(SCH_1):GND
  123  GND            VSS54  @S9S_MB_2U_LIB.S9S_MB_2U(SCH_1):GND
  121  GND            VSS53  @S9S_MB_2U_LIB.S9S_MB_2U(SCH_1):GND
  119  GND            VSS52  @S9S_MB_2U_LIB.S9S_MB_2U(SCH_1):GND
  117  GND            VSS51  @S9S_MB_2U_LIB.S9S_MB_2U(SCH_1):GND
  114  GND            VSS50  @S9S_MB_2U_LIB.S9S_MB_2U(SCH_1):GND
  112  GND            VSS49  @S9S_MB_2U_LIB.S9S_MB_2U(SCH_1):GND
  110  GND            VSS48  @S9S_MB_2U_LIB.S9S_MB_2U(SCH_1):GND
  108  GND            VSS47  @S9S_MB_2U_LIB.S9S_MB_2U(SCH_1):GND
  106  GND            VSS46  @S9S_MB_2U_LIB.S9S_MB_2U(SCH_1):GND
  103  GND            VSS45  @S9S_MB_2U_LIB.S9S_MB_2U(SCH_1):GND
  101  GND            VSS44  @S9S_MB_2U_LIB.S9S_MB_2U(SCH_1):GND
   99  GND            VSS43  @S9S_MB_2U_LIB.S9S_MB_2U(SCH_1):GND
   97  GND            VSS42  @S9S_MB_2U_LIB.S9S_MB_2U(SCH_1):GND
   95  GND            VSS41  @S9S_MB_2U_LIB.S9S_MB_2U(SCH_1):GND
   92  GND            VSS40  @S9S_MB_2U_LIB.S9S_MB_2U(SCH_1):GND
   90  GND            VSS39  @S9S_MB_2U_LIB.S9S_MB_2U(SCH_1):GND
   88  GND            VSS38  @S9S_MB_2U_LIB.S9S_MB_2U(SCH_1):GND
   85  GND            VSS37  @S9S_MB_2U_LIB.S9S_MB_2U(SCH_1):GND
   83  GND            VSS36  @S9S_MB_2U_LIB.S9S_MB_2U(SCH_1):GND
   81  GND            VSS35  @S9S_MB_2U_LIB.S9S_MB_2U(SCH_1):GND
   79  GND            VSS34  @S9S_MB_2U_LIB.S9S_MB_2U(SCH_1):GND
   77  GND            VSS33  @S9S_MB_2U_LIB.S9S_MB_2U(SCH_1):GND
   75  GND            VSS32  @S9S_MB_2U_LIB.S9S_MB_2U(SCH_1):GND
   73  GND            VSS31  @S9S_MB_2U_LIB.S9S_MB_2U(SCH_1):GND
   71  GND            VSS30  @S9S_MB_2U_LIB.S9S_MB_2U(SCH_1):GND
   69  GND            VSS29  @S9S_MB_2U_LIB.S9S_MB_2U(SCH_1):GND
   67  GND            VSS28  @S9S_MB_2U_LIB.S9S_MB_2U(SCH_1):GND
   65  GND            VSS27  @S9S_MB_2U_LIB.S9S_MB_2U(SCH_1):GND
   63  GND            VSS26  @S9S_MB_2U_LIB.S9S_MB_2U(SCH_1):GND
   61  GND            VSS25  @S9S_MB_2U_LIB.S9S_MB_2U(SCH_1):GND
   59  GND            VSS24  @S9S_MB_2U_LIB.S9S_MB_2U(SCH_1):GND
   57  GND            VSS23  @S9S_MB_2U_LIB.S9S_MB_2U(SCH_1):GND
   54  GND            VSS22  @S9S_MB_2U_LIB.S9S_MB_2U(SCH_1):GND
   52  GND            VSS21  @S9S_MB_2U_LIB.S9S_MB_2U(SCH_1):GND
   50  GND            VSS20  @S9S_MB_2U_LIB.S9S_MB_2U(SCH_1):GND
   48  GND            VSS19  @S9S_MB_2U_LIB.S9S_MB_2U(SCH_1):GND
   46  GND            VSS18  @S9S_MB_2U_LIB.S9S_MB_2U(SCH_1):GND
   43  GND            VSS17  @S9S_MB_2U_LIB.S9S_MB_2U(SCH_1):GND
   41  GND            VSS16  @S9S_MB_2U_LIB.S9S_MB_2U(SCH_1):GND
   39  GND            VSS15  @S9S_MB_2U_LIB.S9S_MB_2U(SCH_1):GND
   37  GND            VSS14  @S9S_MB_2U_LIB.S9S_MB_2U(SCH_1):GND
   35  GND            VSS13  @S9S_MB_2U_LIB.S9S_MB_2U(SCH_1):GND
   32  GND            VSS12  @S9S_MB_2U_LIB.S9S_MB_2U(SCH_1):GND
   30  GND            VSS11  @S9S_MB_2U_LIB.S9S_MB_2U(SCH_1):GND
   28  GND            VSS10  @S9S_MB_2U_LIB.S9S_MB_2U(SCH_1):GND
   26  GND             VSS9  @S9S_MB_2U_LIB.S9S_MB_2U(SCH_1):GND
   24  GND             VSS8  @S9S_MB_2U_LIB.S9S_MB_2U(SCH_1):GND
   21  GND             VSS7  @S9S_MB_2U_LIB.S9S_MB_2U(SCH_1):GND
   19  GND             VSS6  @S9S_MB_2U_LIB.S9S_MB_2U(SCH_1):GND
   17  GND             VSS5  @S9S_MB_2U_LIB.S9S_MB_2U(SCH_1):GND
   15  GND             VSS4  @S9S_MB_2U_LIB.S9S_MB_2U(SCH_1):GND
   13  GND             VSS3  @S9S_MB_2U_LIB.S9S_MB_2U(SCH_1):GND
   10  GND             VSS2  @S9S_MB_2U_LIB.S9S_MB_2U(SCH_1):GND
    8  GND             VSS1  @S9S_MB_2U_LIB.S9S_MB_2U(SCH_1):GND
    6  GND             VSS0  @S9S_MB_2U_LIB.S9S_MB_2U(SCH_1):GND
   G3  GND               G3  @S9S_MB_2U_LIB.S9S_MB_2U(SCH_1):GND
   G2  GND               G2  @S9S_MB_2U_LIB.S9S_MB_2U(SCH_1):GND
   G1  GND               G1  @S9S_MB_2U_LIB.S9S_MB_2U(SCH_1):GND

SCONN288_ADR50001P013C01  I177  J27    [SCONN288_ADR50001P013C01-SCONNA]
   93  M_F_CPU1_SB_DQS_DP<9>  DQS9_B_P  @S9S_MB_2U_LIB.S9S_MB_2U(SCH_1):M_F_CPU1_SB_DQS_DP<9>
  283  M_F_CPU1_SB_DQS_DP<8>  DQS8_B_P  @S9S_MB_2U_LIB.S9S_MB_2U(SCH_1):M_F_CPU1_SB_DQS_DP<8>
  272  M_F_CPU1_SB_DQS_DP<7>  DQS7_B_P  @S9S_MB_2U_LIB.S9S_MB_2U(SCH_1):M_F_CPU1_SB_DQS_DP<7>
  261  M_F_CPU1_SB_DQS_DP<6>  DQS6_B_P  @S9S_MB_2U_LIB.S9S_MB_2U(SCH_1):M_F_CPU1_SB_DQS_DP<6>
  250  M_F_CPU1_SB_DQS_DP<5>  DQS5_B_P  @S9S_MB_2U_LIB.S9S_MB_2U(SCH_1):M_F_CPU1_SB_DQS_DP<5>
  239  M_F_CPU1_SB_DQS_DP<4>  DQS4_B_P  @S9S_MB_2U_LIB.S9S_MB_2U(SCH_1):M_F_CPU1_SB_DQS_DP<4>
  137  M_F_CPU1_SB_DQS_DP<3>  DQS3_B_P  @S9S_MB_2U_LIB.S9S_MB_2U(SCH_1):M_F_CPU1_SB_DQS_DP<3>
  126  M_F_CPU1_SB_DQS_DP<2>  DQS2_B_P  @S9S_MB_2U_LIB.S9S_MB_2U(SCH_1):M_F_CPU1_SB_DQS_DP<2>
  115  M_F_CPU1_SB_DQS_DP<1>  DQS1_B_P  @S9S_MB_2U_LIB.S9S_MB_2U(SCH_1):M_F_CPU1_SB_DQS_DP<1>
  104  M_F_CPU1_SB_DQS_DP<0>  DQS0_B_P  @S9S_MB_2U_LIB.S9S_MB_2U(SCH_1):M_F_CPU1_SB_DQS_DP<0>
   94  M_F_CPU1_SB_DQS_DN<9>  DQS9_B_N  @S9S_MB_2U_LIB.S9S_MB_2U(SCH_1):M_F_CPU1_SB_DQS_DN<9>
  282  M_F_CPU1_SB_DQS_DN<8>  DQS8_B_N  @S9S_MB_2U_LIB.S9S_MB_2U(SCH_1):M_F_CPU1_SB_DQS_DN<8>
  271  M_F_CPU1_SB_DQS_DN<7>  DQS7_B_N  @S9S_MB_2U_LIB.S9S_MB_2U(SCH_1):M_F_CPU1_SB_DQS_DN<7>
  260  M_F_CPU1_SB_DQS_DN<6>  DQS6_B_N  @S9S_MB_2U_LIB.S9S_MB_2U(SCH_1):M_F_CPU1_SB_DQS_DN<6>
  249  M_F_CPU1_SB_DQS_DN<5>  DQS5_B_N  @S9S_MB_2U_LIB.S9S_MB_2U(SCH_1):M_F_CPU1_SB_DQS_DN<5>
  238  M_F_CPU1_SB_DQS_DN<4>  DQS4_B_N  @S9S_MB_2U_LIB.S9S_MB_2U(SCH_1):M_F_CPU1_SB_DQS_DN<4>
  138  M_F_CPU1_SB_DQS_DN<3>  DQS3_B_N  @S9S_MB_2U_LIB.S9S_MB_2U(SCH_1):M_F_CPU1_SB_DQS_DN<3>
  127  M_F_CPU1_SB_DQS_DN<2>  DQS2_B_N  @S9S_MB_2U_LIB.S9S_MB_2U(SCH_1):M_F_CPU1_SB_DQS_DN<2>
  116  M_F_CPU1_SB_DQS_DN<1>  DQS1_B_N  @S9S_MB_2U_LIB.S9S_MB_2U(SCH_1):M_F_CPU1_SB_DQS_DN<1>
  105  M_F_CPU1_SB_DQS_DN<0>  DQS0_B_N  @S9S_MB_2U_LIB.S9S_MB_2U(SCH_1):M_F_CPU1_SB_DQS_DN<0>
  201  M_F_CPU1_SA_DQS_DP<9>  DQS9_A_P  @S9S_MB_2U_LIB.S9S_MB_2U(SCH_1):M_F_CPU1_SA_DQS_DP<9>
  190  M_F_CPU1_SA_DQS_DP<8>  DQS8_A_P  @S9S_MB_2U_LIB.S9S_MB_2U(SCH_1):M_F_CPU1_SA_DQS_DP<8>
  179  M_F_CPU1_SA_DQS_DP<7>  DQS7_A_P  @S9S_MB_2U_LIB.S9S_MB_2U(SCH_1):M_F_CPU1_SA_DQS_DP<7>
  168  M_F_CPU1_SA_DQS_DP<6>  DQS6_A_P  @S9S_MB_2U_LIB.S9S_MB_2U(SCH_1):M_F_CPU1_SA_DQS_DP<6>
  157  M_F_CPU1_SA_DQS_DP<5>  DQS5_A_P  @S9S_MB_2U_LIB.S9S_MB_2U(SCH_1):M_F_CPU1_SA_DQS_DP<5>
   55  M_F_CPU1_SA_DQS_DP<4>  DQS4_A_P  @S9S_MB_2U_LIB.S9S_MB_2U(SCH_1):M_F_CPU1_SA_DQS_DP<4>
   44  M_F_CPU1_SA_DQS_DP<3>  DQS3_A_P  @S9S_MB_2U_LIB.S9S_MB_2U(SCH_1):M_F_CPU1_SA_DQS_DP<3>
   33  M_F_CPU1_SA_DQS_DP<2>  DQS2_A_P  @S9S_MB_2U_LIB.S9S_MB_2U(SCH_1):M_F_CPU1_SA_DQS_DP<2>
   22  M_F_CPU1_SA_DQS_DP<1>  DQS1_A_P  @S9S_MB_2U_LIB.S9S_MB_2U(SCH_1):M_F_CPU1_SA_DQS_DP<1>
   11  M_F_CPU1_SA_DQS_DP<0>  DQS0_A_P  @S9S_MB_2U_LIB.S9S_MB_2U(SCH_1):M_F_CPU1_SA_DQS_DP<0>
  200  M_F_CPU1_SA_DQS_DN<9>  DQS9_A_N  @S9S_MB_2U_LIB.S9S_MB_2U(SCH_1):M_F_CPU1_SA_DQS_DN<9>
  189  M_F_CPU1_SA_DQS_DN<8>  DQS8_A_N  @S9S_MB_2U_LIB.S9S_MB_2U(SCH_1):M_F_CPU1_SA_DQS_DN<8>
  178  M_F_CPU1_SA_DQS_DN<7>  DQS7_A_N  @S9S_MB_2U_LIB.S9S_MB_2U(SCH_1):M_F_CPU1_SA_DQS_DN<7>
  167  M_F_CPU1_SA_DQS_DN<6>  DQS6_A_N  @S9S_MB_2U_LIB.S9S_MB_2U(SCH_1):M_F_CPU1_SA_DQS_DN<6>
  156  M_F_CPU1_SA_DQS_DN<5>  DQS5_A_N  @S9S_MB_2U_LIB.S9S_MB_2U(SCH_1):M_F_CPU1_SA_DQS_DN<5>
   56  M_F_CPU1_SA_DQS_DN<4>  DQS4_A_N  @S9S_MB_2U_LIB.S9S_MB_2U(SCH_1):M_F_CPU1_SA_DQS_DN<4>
   45  M_F_CPU1_SA_DQS_DN<3>  DQS3_A_N  @S9S_MB_2U_LIB.S9S_MB_2U(SCH_1):M_F_CPU1_SA_DQS_DN<3>
   34  M_F_CPU1_SA_DQS_DN<2>  DQS2_A_N  @S9S_MB_2U_LIB.S9S_MB_2U(SCH_1):M_F_CPU1_SA_DQS_DN<2>
   23  M_F_CPU1_SA_DQS_DN<1>  DQS1_A_N  @S9S_MB_2U_LIB.S9S_MB_2U(SCH_1):M_F_CPU1_SA_DQS_DN<1>
   12  M_F_CPU1_SA_DQS_DN<0>  DQS0_A_N  @S9S_MB_2U_LIB.S9S_MB_2U(SCH_1):M_F_CPU1_SA_DQS_DN<0>

SCONN288_ADR50001P013C01  I179  J27    [SCONN288_ADR50001P013C01-SCONNA]
  232  NC              RFU6  NC
  231  NC              RFU5  NC
  220  NC              RFU4  NC
  150  NC              RFU3  NC
  149  NC              RFU2  NC
  144  NC              RFU1  NC
    2  NC              RFU0  NC
  207  RST_M_EF_CPU1_FPGA_N  RESET_N  @S9S_MB_2U_LIB.S9S_MB_2U(SCH_1):RST_M_EF_CPU1_FPGA_N
  147  PWRGD_CHF_CPU1_DIMM1  PWR_GOOD||FAIL_N  @S9S_MB_2U_LIB.S9S_MB_2U(SCH_1):PWRGD_CHF_CPU1_DIMM1
  148  PD_CHF_CPU1_DIMM1_SAA    HAS  @S9S_MB_2U_LIB.S9S_MB_2U(SCH_1):PD_CHF_CPU1_DIMM1_SAA
    3  P3V3_AUX       VIN_MGMT  @S9S_MB_2U_LIB.S9S_MB_2U(SCH_1):P3V3_AUX
   87  M_F_CPU1_SB_RSP<0>  LBS||RSP_N_B  @S9S_MB_2U_LIB.S9S_MB_2U(SCH_1):M_F_CPU1_SB_RSP<0>
  227  M_F_CPU1_SB_PAR  PAR_B  @S9S_MB_2U_LIB.S9S_MB_2U(SCH_1):M_F_CPU1_SB_PAR
  113  M_F_CPU1_SB_DQ<9>  DQ_B9  @S9S_MB_2U_LIB.S9S_MB_2U(SCH_1):M_F_CPU1_SB_DQ<9>
  111  M_F_CPU1_SB_DQ<8>  DQ_B8  @S9S_MB_2U_LIB.S9S_MB_2U(SCH_1):M_F_CPU1_SB_DQ<8>
  254  M_F_CPU1_SB_DQ<7>  DQ_B7  @S9S_MB_2U_LIB.S9S_MB_2U(SCH_1):M_F_CPU1_SB_DQ<7>
  252  M_F_CPU1_SB_DQ<6>  DQ_B6  @S9S_MB_2U_LIB.S9S_MB_2U(SCH_1):M_F_CPU1_SB_DQ<6>
  109  M_F_CPU1_SB_DQ<5>  DQ_B5  @S9S_MB_2U_LIB.S9S_MB_2U(SCH_1):M_F_CPU1_SB_DQ<5>
  107  M_F_CPU1_SB_DQ<4>  DQ_B4  @S9S_MB_2U_LIB.S9S_MB_2U(SCH_1):M_F_CPU1_SB_DQ<4>
  247  M_F_CPU1_SB_DQ<3>  DQ_B3  @S9S_MB_2U_LIB.S9S_MB_2U(SCH_1):M_F_CPU1_SB_DQ<3>
  287  M_F_CPU1_SB_DQ<31>  DQ_B31  @S9S_MB_2U_LIB.S9S_MB_2U(SCH_1):M_F_CPU1_SB_DQ<31>
  285  M_F_CPU1_SB_DQ<30>  DQ_B30  @S9S_MB_2U_LIB.S9S_MB_2U(SCH_1):M_F_CPU1_SB_DQ<30>
  245  M_F_CPU1_SB_DQ<2>  DQ_B2  @S9S_MB_2U_LIB.S9S_MB_2U(SCH_1):M_F_CPU1_SB_DQ<2>
  142  M_F_CPU1_SB_DQ<29>  DQ_B29  @S9S_MB_2U_LIB.S9S_MB_2U(SCH_1):M_F_CPU1_SB_DQ<29>
  140  M_F_CPU1_SB_DQ<28>  DQ_B28  @S9S_MB_2U_LIB.S9S_MB_2U(SCH_1):M_F_CPU1_SB_DQ<28>
  280  M_F_CPU1_SB_DQ<27>  DQ_B27  @S9S_MB_2U_LIB.S9S_MB_2U(SCH_1):M_F_CPU1_SB_DQ<27>
  278  M_F_CPU1_SB_DQ<26>  DQ_B26  @S9S_MB_2U_LIB.S9S_MB_2U(SCH_1):M_F_CPU1_SB_DQ<26>
  135  M_F_CPU1_SB_DQ<25>  DQ_B25  @S9S_MB_2U_LIB.S9S_MB_2U(SCH_1):M_F_CPU1_SB_DQ<25>
  133  M_F_CPU1_SB_DQ<24>  DQ_B24  @S9S_MB_2U_LIB.S9S_MB_2U(SCH_1):M_F_CPU1_SB_DQ<24>
  276  M_F_CPU1_SB_DQ<23>  DQ_B23  @S9S_MB_2U_LIB.S9S_MB_2U(SCH_1):M_F_CPU1_SB_DQ<23>
  274  M_F_CPU1_SB_DQ<22>  DQ_B22  @S9S_MB_2U_LIB.S9S_MB_2U(SCH_1):M_F_CPU1_SB_DQ<22>
  131  M_F_CPU1_SB_DQ<21>  DQ_B21  @S9S_MB_2U_LIB.S9S_MB_2U(SCH_1):M_F_CPU1_SB_DQ<21>
  129  M_F_CPU1_SB_DQ<20>  DQ_B20  @S9S_MB_2U_LIB.S9S_MB_2U(SCH_1):M_F_CPU1_SB_DQ<20>
  102  M_F_CPU1_SB_DQ<1>  DQ_B1  @S9S_MB_2U_LIB.S9S_MB_2U(SCH_1):M_F_CPU1_SB_DQ<1>
  269  M_F_CPU1_SB_DQ<19>  DQ_B19  @S9S_MB_2U_LIB.S9S_MB_2U(SCH_1):M_F_CPU1_SB_DQ<19>
  267  M_F_CPU1_SB_DQ<18>  DQ_B18  @S9S_MB_2U_LIB.S9S_MB_2U(SCH_1):M_F_CPU1_SB_DQ<18>
  124  M_F_CPU1_SB_DQ<17>  DQ_B17  @S9S_MB_2U_LIB.S9S_MB_2U(SCH_1):M_F_CPU1_SB_DQ<17>
  122  M_F_CPU1_SB_DQ<16>  DQ_B16  @S9S_MB_2U_LIB.S9S_MB_2U(SCH_1):M_F_CPU1_SB_DQ<16>
  265  M_F_CPU1_SB_DQ<15>  DQ_B15  @S9S_MB_2U_LIB.S9S_MB_2U(SCH_1):M_F_CPU1_SB_DQ<15>
  263  M_F_CPU1_SB_DQ<14>  DQ_B14  @S9S_MB_2U_LIB.S9S_MB_2U(SCH_1):M_F_CPU1_SB_DQ<14>
  120  M_F_CPU1_SB_DQ<13>  DQ_B13  @S9S_MB_2U_LIB.S9S_MB_2U(SCH_1):M_F_CPU1_SB_DQ<13>
  118  M_F_CPU1_SB_DQ<12>  DQ_B12  @S9S_MB_2U_LIB.S9S_MB_2U(SCH_1):M_F_CPU1_SB_DQ<12>
  258  M_F_CPU1_SB_DQ<11>  DQ_B11  @S9S_MB_2U_LIB.S9S_MB_2U(SCH_1):M_F_CPU1_SB_DQ<11>
  256  M_F_CPU1_SB_DQ<10>  DQ_B10  @S9S_MB_2U_LIB.S9S_MB_2U(SCH_1):M_F_CPU1_SB_DQ<10>
  100  M_F_CPU1_SB_DQ<0>  DQ_B0  @S9S_MB_2U_LIB.S9S_MB_2U(SCH_1):M_F_CPU1_SB_DQ<0>
  229  M_F_CPU1_SB_CS_N<1>  CS1_N_B  @S9S_MB_2U_LIB.S9S_MB_2U(SCH_1):M_F_CPU1_SB_CS_N<1>
   84  M_F_CPU1_SB_CS_N<0>  CS0_N_B  @S9S_MB_2U_LIB.S9S_MB_2U(SCH_1):M_F_CPU1_SB_CS_N<0>
  236  M_F_CPU1_SB_CB<7>  CB_B7  @S9S_MB_2U_LIB.S9S_MB_2U(SCH_1):M_F_CPU1_SB_CB<7>
  234  M_F_CPU1_SB_CB<6>  CB_B6  @S9S_MB_2U_LIB.S9S_MB_2U(SCH_1):M_F_CPU1_SB_CB<6>
   91  M_F_CPU1_SB_CB<5>  CB_B5  @S9S_MB_2U_LIB.S9S_MB_2U(SCH_1):M_F_CPU1_SB_CB<5>
   89  M_F_CPU1_SB_CB<4>  CB_B4  @S9S_MB_2U_LIB.S9S_MB_2U(SCH_1):M_F_CPU1_SB_CB<4>
  243  M_F_CPU1_SB_CB<3>  CB_B3  @S9S_MB_2U_LIB.S9S_MB_2U(SCH_1):M_F_CPU1_SB_CB<3>
  241  M_F_CPU1_SB_CB<2>  CB_B2  @S9S_MB_2U_LIB.S9S_MB_2U(SCH_1):M_F_CPU1_SB_CB<2>
   98  M_F_CPU1_SB_CB<1>  CB_B1  @S9S_MB_2U_LIB.S9S_MB_2U(SCH_1):M_F_CPU1_SB_CB<1>
   96  M_F_CPU1_SB_CB<0>  CB_B0  @S9S_MB_2U_LIB.S9S_MB_2U(SCH_1):M_F_CPU1_SB_CB<0>
   82  M_F_CPU1_SB_CA<6>  CA6_B  @S9S_MB_2U_LIB.S9S_MB_2U(SCH_1):M_F_CPU1_SB_CA<6>
  225  M_F_CPU1_SB_CA<5>  CA5_B  @S9S_MB_2U_LIB.S9S_MB_2U(SCH_1):M_F_CPU1_SB_CA<5>
   80  M_F_CPU1_SB_CA<4>  CA4_B  @S9S_MB_2U_LIB.S9S_MB_2U(SCH_1):M_F_CPU1_SB_CA<4>
  223  M_F_CPU1_SB_CA<3>  CA3_B  @S9S_MB_2U_LIB.S9S_MB_2U(SCH_1):M_F_CPU1_SB_CA<3>
   78  M_F_CPU1_SB_CA<2>  CA2_B  @S9S_MB_2U_LIB.S9S_MB_2U(SCH_1):M_F_CPU1_SB_CA<2>
  221  M_F_CPU1_SB_CA<1>  CA1_B  @S9S_MB_2U_LIB.S9S_MB_2U(SCH_1):M_F_CPU1_SB_CA<1>
   76  M_F_CPU1_SB_CA<0>  CA0_B  @S9S_MB_2U_LIB.S9S_MB_2U(SCH_1):M_F_CPU1_SB_CA<0>
   86  M_F_CPU1_SA_RSP<0>  LBD||RSP_N_A  @S9S_MB_2U_LIB.S9S_MB_2U(SCH_1):M_F_CPU1_SA_RSP<0>
   74  M_F_CPU1_SA_PAR  PAR_A  @S9S_MB_2U_LIB.S9S_MB_2U(SCH_1):M_F_CPU1_SA_PAR
   20  M_F_CPU1_SA_DQ<9>  DQ_A9  @S9S_MB_2U_LIB.S9S_MB_2U(SCH_1):M_F_CPU1_SA_DQ<9>
   18  M_F_CPU1_SA_DQ<8>  DQ_A8  @S9S_MB_2U_LIB.S9S_MB_2U(SCH_1):M_F_CPU1_SA_DQ<8>
  161  M_F_CPU1_SA_DQ<7>  DQ_A7  @S9S_MB_2U_LIB.S9S_MB_2U(SCH_1):M_F_CPU1_SA_DQ<7>
  159  M_F_CPU1_SA_DQ<6>  DQ_A6  @S9S_MB_2U_LIB.S9S_MB_2U(SCH_1):M_F_CPU1_SA_DQ<6>
   16  M_F_CPU1_SA_DQ<5>  DQ_A5  @S9S_MB_2U_LIB.S9S_MB_2U(SCH_1):M_F_CPU1_SA_DQ<5>
   14  M_F_CPU1_SA_DQ<4>  DQ_A4  @S9S_MB_2U_LIB.S9S_MB_2U(SCH_1):M_F_CPU1_SA_DQ<4>
  154  M_F_CPU1_SA_DQ<3>  DQ_A3  @S9S_MB_2U_LIB.S9S_MB_2U(SCH_1):M_F_CPU1_SA_DQ<3>
  194  M_F_CPU1_SA_DQ<31>  DQ_A31  @S9S_MB_2U_LIB.S9S_MB_2U(SCH_1):M_F_CPU1_SA_DQ<31>
  192  M_F_CPU1_SA_DQ<30>  DQ_A30  @S9S_MB_2U_LIB.S9S_MB_2U(SCH_1):M_F_CPU1_SA_DQ<30>
  152  M_F_CPU1_SA_DQ<2>  DQ_A2  @S9S_MB_2U_LIB.S9S_MB_2U(SCH_1):M_F_CPU1_SA_DQ<2>
   49  M_F_CPU1_SA_DQ<29>  DQ_A29  @S9S_MB_2U_LIB.S9S_MB_2U(SCH_1):M_F_CPU1_SA_DQ<29>
   47  M_F_CPU1_SA_DQ<28>  DQ_A28  @S9S_MB_2U_LIB.S9S_MB_2U(SCH_1):M_F_CPU1_SA_DQ<28>
  187  M_F_CPU1_SA_DQ<27>  DQ_A27  @S9S_MB_2U_LIB.S9S_MB_2U(SCH_1):M_F_CPU1_SA_DQ<27>
  185  M_F_CPU1_SA_DQ<26>  DQ_A26  @S9S_MB_2U_LIB.S9S_MB_2U(SCH_1):M_F_CPU1_SA_DQ<26>
   42  M_F_CPU1_SA_DQ<25>  DQ_A25  @S9S_MB_2U_LIB.S9S_MB_2U(SCH_1):M_F_CPU1_SA_DQ<25>
   40  M_F_CPU1_SA_DQ<24>  DQ_A24  @S9S_MB_2U_LIB.S9S_MB_2U(SCH_1):M_F_CPU1_SA_DQ<24>
  183  M_F_CPU1_SA_DQ<23>  DQ_A23  @S9S_MB_2U_LIB.S9S_MB_2U(SCH_1):M_F_CPU1_SA_DQ<23>
  181  M_F_CPU1_SA_DQ<22>  DQ_A22  @S9S_MB_2U_LIB.S9S_MB_2U(SCH_1):M_F_CPU1_SA_DQ<22>
   38  M_F_CPU1_SA_DQ<21>  DQ_A21  @S9S_MB_2U_LIB.S9S_MB_2U(SCH_1):M_F_CPU1_SA_DQ<21>
   36  M_F_CPU1_SA_DQ<20>  DQ_A20  @S9S_MB_2U_LIB.S9S_MB_2U(SCH_1):M_F_CPU1_SA_DQ<20>
    9  M_F_CPU1_SA_DQ<1>  DQ_A1  @S9S_MB_2U_LIB.S9S_MB_2U(SCH_1):M_F_CPU1_SA_DQ<1>
  176  M_F_CPU1_SA_DQ<19>  DQ_A19  @S9S_MB_2U_LIB.S9S_MB_2U(SCH_1):M_F_CPU1_SA_DQ<19>
  174  M_F_CPU1_SA_DQ<18>  DQ_A18  @S9S_MB_2U_LIB.S9S_MB_2U(SCH_1):M_F_CPU1_SA_DQ<18>
   31  M_F_CPU1_SA_DQ<17>  DQ_A17  @S9S_MB_2U_LIB.S9S_MB_2U(SCH_1):M_F_CPU1_SA_DQ<17>
   29  M_F_CPU1_SA_DQ<16>  DQ_A16  @S9S_MB_2U_LIB.S9S_MB_2U(SCH_1):M_F_CPU1_SA_DQ<16>
  172  M_F_CPU1_SA_DQ<15>  DQ_A15  @S9S_MB_2U_LIB.S9S_MB_2U(SCH_1):M_F_CPU1_SA_DQ<15>
  170  M_F_CPU1_SA_DQ<14>  DQ_A14  @S9S_MB_2U_LIB.S9S_MB_2U(SCH_1):M_F_CPU1_SA_DQ<14>
   27  M_F_CPU1_SA_DQ<13>  DQ_A13  @S9S_MB_2U_LIB.S9S_MB_2U(SCH_1):M_F_CPU1_SA_DQ<13>
   25  M_F_CPU1_SA_DQ<12>  DQ_A12  @S9S_MB_2U_LIB.S9S_MB_2U(SCH_1):M_F_CPU1_SA_DQ<12>
  165  M_F_CPU1_SA_DQ<11>  DQ_A11  @S9S_MB_2U_LIB.S9S_MB_2U(SCH_1):M_F_CPU1_SA_DQ<11>
  163  M_F_CPU1_SA_DQ<10>  DQ_A10  @S9S_MB_2U_LIB.S9S_MB_2U(SCH_1):M_F_CPU1_SA_DQ<10>
    7  M_F_CPU1_SA_DQ<0>  DQ_A0  @S9S_MB_2U_LIB.S9S_MB_2U(SCH_1):M_F_CPU1_SA_DQ<0>
  209  M_F_CPU1_SA_CS_N<1>  CS1_N_A  @S9S_MB_2U_LIB.S9S_MB_2U(SCH_1):M_F_CPU1_SA_CS_N<1>
   64  M_F_CPU1_SA_CS_N<0>  CS0_N_A  @S9S_MB_2U_LIB.S9S_MB_2U(SCH_1):M_F_CPU1_SA_CS_N<0>
  205  M_F_CPU1_SA_CB<7>  CB_A7  @S9S_MB_2U_LIB.S9S_MB_2U(SCH_1):M_F_CPU1_SA_CB<7>
  203  M_F_CPU1_SA_CB<6>  CB_A6  @S9S_MB_2U_LIB.S9S_MB_2U(SCH_1):M_F_CPU1_SA_CB<6>
   60  M_F_CPU1_SA_CB<5>  CB_A5  @S9S_MB_2U_LIB.S9S_MB_2U(SCH_1):M_F_CPU1_SA_CB<5>
   58  M_F_CPU1_SA_CB<4>  CB_A4  @S9S_MB_2U_LIB.S9S_MB_2U(SCH_1):M_F_CPU1_SA_CB<4>
  198  M_F_CPU1_SA_CB<3>  CB_A3  @S9S_MB_2U_LIB.S9S_MB_2U(SCH_1):M_F_CPU1_SA_CB<3>
  196  M_F_CPU1_SA_CB<2>  CB_A2  @S9S_MB_2U_LIB.S9S_MB_2U(SCH_1):M_F_CPU1_SA_CB<2>
   53  M_F_CPU1_SA_CB<1>  CB_A1  @S9S_MB_2U_LIB.S9S_MB_2U(SCH_1):M_F_CPU1_SA_CB<1>
   51  M_F_CPU1_SA_CB<0>  CB_A0  @S9S_MB_2U_LIB.S9S_MB_2U(SCH_1):M_F_CPU1_SA_CB<0>
   72  M_F_CPU1_SA_CA<6>  CA6_A  @S9S_MB_2U_LIB.S9S_MB_2U(SCH_1):M_F_CPU1_SA_CA<6>
  215  M_F_CPU1_SA_CA<5>  CA5_A  @S9S_MB_2U_LIB.S9S_MB_2U(SCH_1):M_F_CPU1_SA_CA<5>
   70  M_F_CPU1_SA_CA<4>  CA4_A  @S9S_MB_2U_LIB.S9S_MB_2U(SCH_1):M_F_CPU1_SA_CA<4>
  213  M_F_CPU1_SA_CA<3>  CA3_A  @S9S_MB_2U_LIB.S9S_MB_2U(SCH_1):M_F_CPU1_SA_CA<3>
   68  M_F_CPU1_SA_CA<2>  CA2_A  @S9S_MB_2U_LIB.S9S_MB_2U(SCH_1):M_F_CPU1_SA_CA<2>
  211  M_F_CPU1_SA_CA<1>  CA1_A  @S9S_MB_2U_LIB.S9S_MB_2U(SCH_1):M_F_CPU1_SA_CA<1>
   66  M_F_CPU1_SA_CA<0>  CA0_A  @S9S_MB_2U_LIB.S9S_MB_2U(SCH_1):M_F_CPU1_SA_CA<0>
  217  M_F_CPU1_CLK_DP<0>   CK_P  @S9S_MB_2U_LIB.S9S_MB_2U(SCH_1):M_F_CPU1_CLK_DP<0>
  218  M_F_CPU1_CLK_DN<0>   CK_N  @S9S_MB_2U_LIB.S9S_MB_2U(SCH_1):M_F_CPU1_CLK_DN<0>
   62  M_F_CPU1_ALERT_N  ALERT_N  @S9S_MB_2U_LIB.S9S_MB_2U(SCH_1):M_F_CPU1_ALERT_N
    5  I3C_SPD_DDREFGH_CPU1_LVC1_SDA   HSDA  @S9S_MB_2U_LIB.S9S_MB_2U(SCH_1):I3C_SPD_DDREFGH_CPU1_LVC1_SDA
    4  I3C_SPD_DDREFGH_CPU1_LVC1_SCL   HSCL  @S9S_MB_2U_LIB.S9S_MB_2U(SCH_1):I3C_SPD_DDREFGH_CPU1_LVC1_SCL

SCONN288_ADR50001P003C01  I176  J28    [SCONN288_ADR50001P003C01-SCONNA]
  146  P12V_S3_AUX_CPU1_NVDIMM  VIN_BULK2  @S9S_MB_2U_LIB.S9S_MB_2U(SCH_1):P12V_S3_AUX_CPU1_NVDIMM
  145  P12V_S3_AUX_CPU1_NVDIMM  VIN_BULK1  @S9S_MB_2U_LIB.S9S_MB_2U(SCH_1):P12V_S3_AUX_CPU1_NVDIMM
    1  P12V_S3_AUX_CPU1_NVDIMM  VIN_BULK0  @S9S_MB_2U_LIB.S9S_MB_2U(SCH_1):P12V_S3_AUX_CPU1_NVDIMM
  288  GND            VSS126  @S9S_MB_2U_LIB.S9S_MB_2U(SCH_1):GND
  286  GND            VSS125  @S9S_MB_2U_LIB.S9S_MB_2U(SCH_1):GND
  284  GND            VSS124  @S9S_MB_2U_LIB.S9S_MB_2U(SCH_1):GND
  281  GND            VSS123  @S9S_MB_2U_LIB.S9S_MB_2U(SCH_1):GND
  279  GND            VSS122  @S9S_MB_2U_LIB.S9S_MB_2U(SCH_1):GND
  277  GND            VSS121  @S9S_MB_2U_LIB.S9S_MB_2U(SCH_1):GND
  275  GND            VSS120  @S9S_MB_2U_LIB.S9S_MB_2U(SCH_1):GND
  273  GND            VSS119  @S9S_MB_2U_LIB.S9S_MB_2U(SCH_1):GND
  270  GND            VSS118  @S9S_MB_2U_LIB.S9S_MB_2U(SCH_1):GND
  268  GND            VSS117  @S9S_MB_2U_LIB.S9S_MB_2U(SCH_1):GND
  266  GND            VSS116  @S9S_MB_2U_LIB.S9S_MB_2U(SCH_1):GND
  264  GND            VSS115  @S9S_MB_2U_LIB.S9S_MB_2U(SCH_1):GND
  262  GND            VSS114  @S9S_MB_2U_LIB.S9S_MB_2U(SCH_1):GND
  259  GND            VSS113  @S9S_MB_2U_LIB.S9S_MB_2U(SCH_1):GND
  257  GND            VSS112  @S9S_MB_2U_LIB.S9S_MB_2U(SCH_1):GND
  255  GND            VSS111  @S9S_MB_2U_LIB.S9S_MB_2U(SCH_1):GND
  253  GND            VSS110  @S9S_MB_2U_LIB.S9S_MB_2U(SCH_1):GND
  251  GND            VSS109  @S9S_MB_2U_LIB.S9S_MB_2U(SCH_1):GND
  248  GND            VSS108  @S9S_MB_2U_LIB.S9S_MB_2U(SCH_1):GND
  246  GND            VSS107  @S9S_MB_2U_LIB.S9S_MB_2U(SCH_1):GND
  244  GND            VSS106  @S9S_MB_2U_LIB.S9S_MB_2U(SCH_1):GND
  242  GND            VSS105  @S9S_MB_2U_LIB.S9S_MB_2U(SCH_1):GND
  240  GND            VSS104  @S9S_MB_2U_LIB.S9S_MB_2U(SCH_1):GND
  237  GND            VSS103  @S9S_MB_2U_LIB.S9S_MB_2U(SCH_1):GND
  235  GND            VSS102  @S9S_MB_2U_LIB.S9S_MB_2U(SCH_1):GND
  233  GND            VSS101  @S9S_MB_2U_LIB.S9S_MB_2U(SCH_1):GND
  230  GND            VSS100  @S9S_MB_2U_LIB.S9S_MB_2U(SCH_1):GND
  228  GND            VSS99  @S9S_MB_2U_LIB.S9S_MB_2U(SCH_1):GND
  226  GND            VSS98  @S9S_MB_2U_LIB.S9S_MB_2U(SCH_1):GND
  224  GND            VSS97  @S9S_MB_2U_LIB.S9S_MB_2U(SCH_1):GND
  222  GND            VSS96  @S9S_MB_2U_LIB.S9S_MB_2U(SCH_1):GND
  219  GND            VSS95  @S9S_MB_2U_LIB.S9S_MB_2U(SCH_1):GND
  216  GND            VSS94  @S9S_MB_2U_LIB.S9S_MB_2U(SCH_1):GND
  214  GND            VSS93  @S9S_MB_2U_LIB.S9S_MB_2U(SCH_1):GND
  212  GND            VSS92  @S9S_MB_2U_LIB.S9S_MB_2U(SCH_1):GND
  210  GND            VSS91  @S9S_MB_2U_LIB.S9S_MB_2U(SCH_1):GND
  208  GND            VSS90  @S9S_MB_2U_LIB.S9S_MB_2U(SCH_1):GND
  206  GND            VSS89  @S9S_MB_2U_LIB.S9S_MB_2U(SCH_1):GND
  204  GND            VSS88  @S9S_MB_2U_LIB.S9S_MB_2U(SCH_1):GND
  202  GND            VSS87  @S9S_MB_2U_LIB.S9S_MB_2U(SCH_1):GND
  199  GND            VSS86  @S9S_MB_2U_LIB.S9S_MB_2U(SCH_1):GND
  197  GND            VSS85  @S9S_MB_2U_LIB.S9S_MB_2U(SCH_1):GND
  195  GND            VSS84  @S9S_MB_2U_LIB.S9S_MB_2U(SCH_1):GND
  193  GND            VSS83  @S9S_MB_2U_LIB.S9S_MB_2U(SCH_1):GND
  191  GND            VSS82  @S9S_MB_2U_LIB.S9S_MB_2U(SCH_1):GND
  188  GND            VSS81  @S9S_MB_2U_LIB.S9S_MB_2U(SCH_1):GND
  186  GND            VSS80  @S9S_MB_2U_LIB.S9S_MB_2U(SCH_1):GND
  184  GND            VSS79  @S9S_MB_2U_LIB.S9S_MB_2U(SCH_1):GND
  182  GND            VSS78  @S9S_MB_2U_LIB.S9S_MB_2U(SCH_1):GND
  180  GND            VSS77  @S9S_MB_2U_LIB.S9S_MB_2U(SCH_1):GND
  177  GND            VSS76  @S9S_MB_2U_LIB.S9S_MB_2U(SCH_1):GND
  175  GND            VSS75  @S9S_MB_2U_LIB.S9S_MB_2U(SCH_1):GND
  173  GND            VSS74  @S9S_MB_2U_LIB.S9S_MB_2U(SCH_1):GND
  171  GND            VSS73  @S9S_MB_2U_LIB.S9S_MB_2U(SCH_1):GND
  169  GND            VSS72  @S9S_MB_2U_LIB.S9S_MB_2U(SCH_1):GND
  166  GND            VSS71  @S9S_MB_2U_LIB.S9S_MB_2U(SCH_1):GND
  164  GND            VSS70  @S9S_MB_2U_LIB.S9S_MB_2U(SCH_1):GND
  162  GND            VSS69  @S9S_MB_2U_LIB.S9S_MB_2U(SCH_1):GND
  160  GND            VSS68  @S9S_MB_2U_LIB.S9S_MB_2U(SCH_1):GND
  158  GND            VSS67  @S9S_MB_2U_LIB.S9S_MB_2U(SCH_1):GND
  155  GND            VSS66  @S9S_MB_2U_LIB.S9S_MB_2U(SCH_1):GND
  153  GND            VSS65  @S9S_MB_2U_LIB.S9S_MB_2U(SCH_1):GND
  151  GND            VSS64  @S9S_MB_2U_LIB.S9S_MB_2U(SCH_1):GND
  143  GND            VSS63  @S9S_MB_2U_LIB.S9S_MB_2U(SCH_1):GND
  141  GND            VSS62  @S9S_MB_2U_LIB.S9S_MB_2U(SCH_1):GND
  139  GND            VSS61  @S9S_MB_2U_LIB.S9S_MB_2U(SCH_1):GND
  136  GND            VSS60  @S9S_MB_2U_LIB.S9S_MB_2U(SCH_1):GND
  134  GND            VSS59  @S9S_MB_2U_LIB.S9S_MB_2U(SCH_1):GND
  132  GND            VSS58  @S9S_MB_2U_LIB.S9S_MB_2U(SCH_1):GND
  130  GND            VSS57  @S9S_MB_2U_LIB.S9S_MB_2U(SCH_1):GND
  128  GND            VSS56  @S9S_MB_2U_LIB.S9S_MB_2U(SCH_1):GND
  125  GND            VSS55  @S9S_MB_2U_LIB.S9S_MB_2U(SCH_1):GND
  123  GND            VSS54  @S9S_MB_2U_LIB.S9S_MB_2U(SCH_1):GND
  121  GND            VSS53  @S9S_MB_2U_LIB.S9S_MB_2U(SCH_1):GND
  119  GND            VSS52  @S9S_MB_2U_LIB.S9S_MB_2U(SCH_1):GND
  117  GND            VSS51  @S9S_MB_2U_LIB.S9S_MB_2U(SCH_1):GND
  114  GND            VSS50  @S9S_MB_2U_LIB.S9S_MB_2U(SCH_1):GND
  112  GND            VSS49  @S9S_MB_2U_LIB.S9S_MB_2U(SCH_1):GND
  110  GND            VSS48  @S9S_MB_2U_LIB.S9S_MB_2U(SCH_1):GND
  108  GND            VSS47  @S9S_MB_2U_LIB.S9S_MB_2U(SCH_1):GND
  106  GND            VSS46  @S9S_MB_2U_LIB.S9S_MB_2U(SCH_1):GND
  103  GND            VSS45  @S9S_MB_2U_LIB.S9S_MB_2U(SCH_1):GND
  101  GND            VSS44  @S9S_MB_2U_LIB.S9S_MB_2U(SCH_1):GND
   99  GND            VSS43  @S9S_MB_2U_LIB.S9S_MB_2U(SCH_1):GND
   97  GND            VSS42  @S9S_MB_2U_LIB.S9S_MB_2U(SCH_1):GND
   95  GND            VSS41  @S9S_MB_2U_LIB.S9S_MB_2U(SCH_1):GND
   92  GND            VSS40  @S9S_MB_2U_LIB.S9S_MB_2U(SCH_1):GND
   90  GND            VSS39  @S9S_MB_2U_LIB.S9S_MB_2U(SCH_1):GND
   88  GND            VSS38  @S9S_MB_2U_LIB.S9S_MB_2U(SCH_1):GND
   85  GND            VSS37  @S9S_MB_2U_LIB.S9S_MB_2U(SCH_1):GND
   83  GND            VSS36  @S9S_MB_2U_LIB.S9S_MB_2U(SCH_1):GND
   81  GND            VSS35  @S9S_MB_2U_LIB.S9S_MB_2U(SCH_1):GND
   79  GND            VSS34  @S9S_MB_2U_LIB.S9S_MB_2U(SCH_1):GND
   77  GND            VSS33  @S9S_MB_2U_LIB.S9S_MB_2U(SCH_1):GND
   75  GND            VSS32  @S9S_MB_2U_LIB.S9S_MB_2U(SCH_1):GND
   73  GND            VSS31  @S9S_MB_2U_LIB.S9S_MB_2U(SCH_1):GND
   71  GND            VSS30  @S9S_MB_2U_LIB.S9S_MB_2U(SCH_1):GND
   69  GND            VSS29  @S9S_MB_2U_LIB.S9S_MB_2U(SCH_1):GND
   67  GND            VSS28  @S9S_MB_2U_LIB.S9S_MB_2U(SCH_1):GND
   65  GND            VSS27  @S9S_MB_2U_LIB.S9S_MB_2U(SCH_1):GND
   63  GND            VSS26  @S9S_MB_2U_LIB.S9S_MB_2U(SCH_1):GND
   61  GND            VSS25  @S9S_MB_2U_LIB.S9S_MB_2U(SCH_1):GND
   59  GND            VSS24  @S9S_MB_2U_LIB.S9S_MB_2U(SCH_1):GND
   57  GND            VSS23  @S9S_MB_2U_LIB.S9S_MB_2U(SCH_1):GND
   54  GND            VSS22  @S9S_MB_2U_LIB.S9S_MB_2U(SCH_1):GND
   52  GND            VSS21  @S9S_MB_2U_LIB.S9S_MB_2U(SCH_1):GND
   50  GND            VSS20  @S9S_MB_2U_LIB.S9S_MB_2U(SCH_1):GND
   48  GND            VSS19  @S9S_MB_2U_LIB.S9S_MB_2U(SCH_1):GND
   46  GND            VSS18  @S9S_MB_2U_LIB.S9S_MB_2U(SCH_1):GND
   43  GND            VSS17  @S9S_MB_2U_LIB.S9S_MB_2U(SCH_1):GND
   41  GND            VSS16  @S9S_MB_2U_LIB.S9S_MB_2U(SCH_1):GND
   39  GND            VSS15  @S9S_MB_2U_LIB.S9S_MB_2U(SCH_1):GND
   37  GND            VSS14  @S9S_MB_2U_LIB.S9S_MB_2U(SCH_1):GND
   35  GND            VSS13  @S9S_MB_2U_LIB.S9S_MB_2U(SCH_1):GND
   32  GND            VSS12  @S9S_MB_2U_LIB.S9S_MB_2U(SCH_1):GND
   30  GND            VSS11  @S9S_MB_2U_LIB.S9S_MB_2U(SCH_1):GND
   28  GND            VSS10  @S9S_MB_2U_LIB.S9S_MB_2U(SCH_1):GND
   26  GND             VSS9  @S9S_MB_2U_LIB.S9S_MB_2U(SCH_1):GND
   24  GND             VSS8  @S9S_MB_2U_LIB.S9S_MB_2U(SCH_1):GND
   21  GND             VSS7  @S9S_MB_2U_LIB.S9S_MB_2U(SCH_1):GND
   19  GND             VSS6  @S9S_MB_2U_LIB.S9S_MB_2U(SCH_1):GND
   17  GND             VSS5  @S9S_MB_2U_LIB.S9S_MB_2U(SCH_1):GND
   15  GND             VSS4  @S9S_MB_2U_LIB.S9S_MB_2U(SCH_1):GND
   13  GND             VSS3  @S9S_MB_2U_LIB.S9S_MB_2U(SCH_1):GND
   10  GND             VSS2  @S9S_MB_2U_LIB.S9S_MB_2U(SCH_1):GND
    8  GND             VSS1  @S9S_MB_2U_LIB.S9S_MB_2U(SCH_1):GND
    6  GND             VSS0  @S9S_MB_2U_LIB.S9S_MB_2U(SCH_1):GND
   G3  GND               G3  @S9S_MB_2U_LIB.S9S_MB_2U(SCH_1):GND
   G2  GND               G2  @S9S_MB_2U_LIB.S9S_MB_2U(SCH_1):GND
   G1  GND               G1  @S9S_MB_2U_LIB.S9S_MB_2U(SCH_1):GND

SCONN288_ADR50001P003C01  I124  J28    [SCONN288_ADR50001P003C01-SCONNA]
   93  M_F_CPU1_SB_DQS_DP<9>  DQS9_B_P  @S9S_MB_2U_LIB.S9S_MB_2U(SCH_1):M_F_CPU1_SB_DQS_DP<9>
  283  M_F_CPU1_SB_DQS_DP<8>  DQS8_B_P  @S9S_MB_2U_LIB.S9S_MB_2U(SCH_1):M_F_CPU1_SB_DQS_DP<8>
  272  M_F_CPU1_SB_DQS_DP<7>  DQS7_B_P  @S9S_MB_2U_LIB.S9S_MB_2U(SCH_1):M_F_CPU1_SB_DQS_DP<7>
  261  M_F_CPU1_SB_DQS_DP<6>  DQS6_B_P  @S9S_MB_2U_LIB.S9S_MB_2U(SCH_1):M_F_CPU1_SB_DQS_DP<6>
  250  M_F_CPU1_SB_DQS_DP<5>  DQS5_B_P  @S9S_MB_2U_LIB.S9S_MB_2U(SCH_1):M_F_CPU1_SB_DQS_DP<5>
  239  M_F_CPU1_SB_DQS_DP<4>  DQS4_B_P  @S9S_MB_2U_LIB.S9S_MB_2U(SCH_1):M_F_CPU1_SB_DQS_DP<4>
  137  M_F_CPU1_SB_DQS_DP<3>  DQS3_B_P  @S9S_MB_2U_LIB.S9S_MB_2U(SCH_1):M_F_CPU1_SB_DQS_DP<3>
  126  M_F_CPU1_SB_DQS_DP<2>  DQS2_B_P  @S9S_MB_2U_LIB.S9S_MB_2U(SCH_1):M_F_CPU1_SB_DQS_DP<2>
  115  M_F_CPU1_SB_DQS_DP<1>  DQS1_B_P  @S9S_MB_2U_LIB.S9S_MB_2U(SCH_1):M_F_CPU1_SB_DQS_DP<1>
  104  M_F_CPU1_SB_DQS_DP<0>  DQS0_B_P  @S9S_MB_2U_LIB.S9S_MB_2U(SCH_1):M_F_CPU1_SB_DQS_DP<0>
   94  M_F_CPU1_SB_DQS_DN<9>  DQS9_B_N  @S9S_MB_2U_LIB.S9S_MB_2U(SCH_1):M_F_CPU1_SB_DQS_DN<9>
  282  M_F_CPU1_SB_DQS_DN<8>  DQS8_B_N  @S9S_MB_2U_LIB.S9S_MB_2U(SCH_1):M_F_CPU1_SB_DQS_DN<8>
  271  M_F_CPU1_SB_DQS_DN<7>  DQS7_B_N  @S9S_MB_2U_LIB.S9S_MB_2U(SCH_1):M_F_CPU1_SB_DQS_DN<7>
  260  M_F_CPU1_SB_DQS_DN<6>  DQS6_B_N  @S9S_MB_2U_LIB.S9S_MB_2U(SCH_1):M_F_CPU1_SB_DQS_DN<6>
  249  M_F_CPU1_SB_DQS_DN<5>  DQS5_B_N  @S9S_MB_2U_LIB.S9S_MB_2U(SCH_1):M_F_CPU1_SB_DQS_DN<5>
  238  M_F_CPU1_SB_DQS_DN<4>  DQS4_B_N  @S9S_MB_2U_LIB.S9S_MB_2U(SCH_1):M_F_CPU1_SB_DQS_DN<4>
  138  M_F_CPU1_SB_DQS_DN<3>  DQS3_B_N  @S9S_MB_2U_LIB.S9S_MB_2U(SCH_1):M_F_CPU1_SB_DQS_DN<3>
  127  M_F_CPU1_SB_DQS_DN<2>  DQS2_B_N  @S9S_MB_2U_LIB.S9S_MB_2U(SCH_1):M_F_CPU1_SB_DQS_DN<2>
  116  M_F_CPU1_SB_DQS_DN<1>  DQS1_B_N  @S9S_MB_2U_LIB.S9S_MB_2U(SCH_1):M_F_CPU1_SB_DQS_DN<1>
  105  M_F_CPU1_SB_DQS_DN<0>  DQS0_B_N  @S9S_MB_2U_LIB.S9S_MB_2U(SCH_1):M_F_CPU1_SB_DQS_DN<0>
  201  M_F_CPU1_SA_DQS_DP<9>  DQS9_A_P  @S9S_MB_2U_LIB.S9S_MB_2U(SCH_1):M_F_CPU1_SA_DQS_DP<9>
  190  M_F_CPU1_SA_DQS_DP<8>  DQS8_A_P  @S9S_MB_2U_LIB.S9S_MB_2U(SCH_1):M_F_CPU1_SA_DQS_DP<8>
  179  M_F_CPU1_SA_DQS_DP<7>  DQS7_A_P  @S9S_MB_2U_LIB.S9S_MB_2U(SCH_1):M_F_CPU1_SA_DQS_DP<7>
  168  M_F_CPU1_SA_DQS_DP<6>  DQS6_A_P  @S9S_MB_2U_LIB.S9S_MB_2U(SCH_1):M_F_CPU1_SA_DQS_DP<6>
  157  M_F_CPU1_SA_DQS_DP<5>  DQS5_A_P  @S9S_MB_2U_LIB.S9S_MB_2U(SCH_1):M_F_CPU1_SA_DQS_DP<5>
   55  M_F_CPU1_SA_DQS_DP<4>  DQS4_A_P  @S9S_MB_2U_LIB.S9S_MB_2U(SCH_1):M_F_CPU1_SA_DQS_DP<4>
   44  M_F_CPU1_SA_DQS_DP<3>  DQS3_A_P  @S9S_MB_2U_LIB.S9S_MB_2U(SCH_1):M_F_CPU1_SA_DQS_DP<3>
   33  M_F_CPU1_SA_DQS_DP<2>  DQS2_A_P  @S9S_MB_2U_LIB.S9S_MB_2U(SCH_1):M_F_CPU1_SA_DQS_DP<2>
   22  M_F_CPU1_SA_DQS_DP<1>  DQS1_A_P  @S9S_MB_2U_LIB.S9S_MB_2U(SCH_1):M_F_CPU1_SA_DQS_DP<1>
   11  M_F_CPU1_SA_DQS_DP<0>  DQS0_A_P  @S9S_MB_2U_LIB.S9S_MB_2U(SCH_1):M_F_CPU1_SA_DQS_DP<0>
  200  M_F_CPU1_SA_DQS_DN<9>  DQS9_A_N  @S9S_MB_2U_LIB.S9S_MB_2U(SCH_1):M_F_CPU1_SA_DQS_DN<9>
  189  M_F_CPU1_SA_DQS_DN<8>  DQS8_A_N  @S9S_MB_2U_LIB.S9S_MB_2U(SCH_1):M_F_CPU1_SA_DQS_DN<8>
  178  M_F_CPU1_SA_DQS_DN<7>  DQS7_A_N  @S9S_MB_2U_LIB.S9S_MB_2U(SCH_1):M_F_CPU1_SA_DQS_DN<7>
  167  M_F_CPU1_SA_DQS_DN<6>  DQS6_A_N  @S9S_MB_2U_LIB.S9S_MB_2U(SCH_1):M_F_CPU1_SA_DQS_DN<6>
  156  M_F_CPU1_SA_DQS_DN<5>  DQS5_A_N  @S9S_MB_2U_LIB.S9S_MB_2U(SCH_1):M_F_CPU1_SA_DQS_DN<5>
   56  M_F_CPU1_SA_DQS_DN<4>  DQS4_A_N  @S9S_MB_2U_LIB.S9S_MB_2U(SCH_1):M_F_CPU1_SA_DQS_DN<4>
   45  M_F_CPU1_SA_DQS_DN<3>  DQS3_A_N  @S9S_MB_2U_LIB.S9S_MB_2U(SCH_1):M_F_CPU1_SA_DQS_DN<3>
   34  M_F_CPU1_SA_DQS_DN<2>  DQS2_A_N  @S9S_MB_2U_LIB.S9S_MB_2U(SCH_1):M_F_CPU1_SA_DQS_DN<2>
   23  M_F_CPU1_SA_DQS_DN<1>  DQS1_A_N  @S9S_MB_2U_LIB.S9S_MB_2U(SCH_1):M_F_CPU1_SA_DQS_DN<1>
   12  M_F_CPU1_SA_DQS_DN<0>  DQS0_A_N  @S9S_MB_2U_LIB.S9S_MB_2U(SCH_1):M_F_CPU1_SA_DQS_DN<0>

SCONN288_ADR50001P003C01  I47  J28    [SCONN288_ADR50001P003C01-SCONNA]
  232  NC              RFU6  NC
  231  NC              RFU5  NC
  220  NC              RFU4  NC
  150  NC              RFU3  NC
  149  NC              RFU2  NC
  144  NC              RFU1  NC
    2  NC              RFU0  NC
  207  RST_M_EF_CPU1_FPGA_N  RESET_N  @S9S_MB_2U_LIB.S9S_MB_2U(SCH_1):RST_M_EF_CPU1_FPGA_N
  147  PWRGD_CHF_CPU1_DIMM2  PWR_GOOD||FAIL_N  @S9S_MB_2U_LIB.S9S_MB_2U(SCH_1):PWRGD_CHF_CPU1_DIMM2
  148  PD_CHF_CPU1_DIMM2_SAA    HAS  @S9S_MB_2U_LIB.S9S_MB_2U(SCH_1):PD_CHF_CPU1_DIMM2_SAA
    3  P3V3_AUX       VIN_MGMT  @S9S_MB_2U_LIB.S9S_MB_2U(SCH_1):P3V3_AUX
   87  M_F_CPU1_SB_RSP<1>  LBS||RSP_N_B  @S9S_MB_2U_LIB.S9S_MB_2U(SCH_1):M_F_CPU1_SB_RSP<1>
  227  M_F_CPU1_SB_PAR  PAR_B  @S9S_MB_2U_LIB.S9S_MB_2U(SCH_1):M_F_CPU1_SB_PAR
  113  M_F_CPU1_SB_DQ<9>  DQ_B9  @S9S_MB_2U_LIB.S9S_MB_2U(SCH_1):M_F_CPU1_SB_DQ<9>
  111  M_F_CPU1_SB_DQ<8>  DQ_B8  @S9S_MB_2U_LIB.S9S_MB_2U(SCH_1):M_F_CPU1_SB_DQ<8>
  254  M_F_CPU1_SB_DQ<7>  DQ_B7  @S9S_MB_2U_LIB.S9S_MB_2U(SCH_1):M_F_CPU1_SB_DQ<7>
  252  M_F_CPU1_SB_DQ<6>  DQ_B6  @S9S_MB_2U_LIB.S9S_MB_2U(SCH_1):M_F_CPU1_SB_DQ<6>
  109  M_F_CPU1_SB_DQ<5>  DQ_B5  @S9S_MB_2U_LIB.S9S_MB_2U(SCH_1):M_F_CPU1_SB_DQ<5>
  107  M_F_CPU1_SB_DQ<4>  DQ_B4  @S9S_MB_2U_LIB.S9S_MB_2U(SCH_1):M_F_CPU1_SB_DQ<4>
  247  M_F_CPU1_SB_DQ<3>  DQ_B3  @S9S_MB_2U_LIB.S9S_MB_2U(SCH_1):M_F_CPU1_SB_DQ<3>
  287  M_F_CPU1_SB_DQ<31>  DQ_B31  @S9S_MB_2U_LIB.S9S_MB_2U(SCH_1):M_F_CPU1_SB_DQ<31>
  285  M_F_CPU1_SB_DQ<30>  DQ_B30  @S9S_MB_2U_LIB.S9S_MB_2U(SCH_1):M_F_CPU1_SB_DQ<30>
  245  M_F_CPU1_SB_DQ<2>  DQ_B2  @S9S_MB_2U_LIB.S9S_MB_2U(SCH_1):M_F_CPU1_SB_DQ<2>
  142  M_F_CPU1_SB_DQ<29>  DQ_B29  @S9S_MB_2U_LIB.S9S_MB_2U(SCH_1):M_F_CPU1_SB_DQ<29>
  140  M_F_CPU1_SB_DQ<28>  DQ_B28  @S9S_MB_2U_LIB.S9S_MB_2U(SCH_1):M_F_CPU1_SB_DQ<28>
  280  M_F_CPU1_SB_DQ<27>  DQ_B27  @S9S_MB_2U_LIB.S9S_MB_2U(SCH_1):M_F_CPU1_SB_DQ<27>
  278  M_F_CPU1_SB_DQ<26>  DQ_B26  @S9S_MB_2U_LIB.S9S_MB_2U(SCH_1):M_F_CPU1_SB_DQ<26>
  135  M_F_CPU1_SB_DQ<25>  DQ_B25  @S9S_MB_2U_LIB.S9S_MB_2U(SCH_1):M_F_CPU1_SB_DQ<25>
  133  M_F_CPU1_SB_DQ<24>  DQ_B24  @S9S_MB_2U_LIB.S9S_MB_2U(SCH_1):M_F_CPU1_SB_DQ<24>
  276  M_F_CPU1_SB_DQ<23>  DQ_B23  @S9S_MB_2U_LIB.S9S_MB_2U(SCH_1):M_F_CPU1_SB_DQ<23>
  274  M_F_CPU1_SB_DQ<22>  DQ_B22  @S9S_MB_2U_LIB.S9S_MB_2U(SCH_1):M_F_CPU1_SB_DQ<22>
  131  M_F_CPU1_SB_DQ<21>  DQ_B21  @S9S_MB_2U_LIB.S9S_MB_2U(SCH_1):M_F_CPU1_SB_DQ<21>
  129  M_F_CPU1_SB_DQ<20>  DQ_B20  @S9S_MB_2U_LIB.S9S_MB_2U(SCH_1):M_F_CPU1_SB_DQ<20>
  102  M_F_CPU1_SB_DQ<1>  DQ_B1  @S9S_MB_2U_LIB.S9S_MB_2U(SCH_1):M_F_CPU1_SB_DQ<1>
  269  M_F_CPU1_SB_DQ<19>  DQ_B19  @S9S_MB_2U_LIB.S9S_MB_2U(SCH_1):M_F_CPU1_SB_DQ<19>
  267  M_F_CPU1_SB_DQ<18>  DQ_B18  @S9S_MB_2U_LIB.S9S_MB_2U(SCH_1):M_F_CPU1_SB_DQ<18>
  124  M_F_CPU1_SB_DQ<17>  DQ_B17  @S9S_MB_2U_LIB.S9S_MB_2U(SCH_1):M_F_CPU1_SB_DQ<17>
  122  M_F_CPU1_SB_DQ<16>  DQ_B16  @S9S_MB_2U_LIB.S9S_MB_2U(SCH_1):M_F_CPU1_SB_DQ<16>
  265  M_F_CPU1_SB_DQ<15>  DQ_B15  @S9S_MB_2U_LIB.S9S_MB_2U(SCH_1):M_F_CPU1_SB_DQ<15>
  263  M_F_CPU1_SB_DQ<14>  DQ_B14  @S9S_MB_2U_LIB.S9S_MB_2U(SCH_1):M_F_CPU1_SB_DQ<14>
  120  M_F_CPU1_SB_DQ<13>  DQ_B13  @S9S_MB_2U_LIB.S9S_MB_2U(SCH_1):M_F_CPU1_SB_DQ<13>
  118  M_F_CPU1_SB_DQ<12>  DQ_B12  @S9S_MB_2U_LIB.S9S_MB_2U(SCH_1):M_F_CPU1_SB_DQ<12>
  258  M_F_CPU1_SB_DQ<11>  DQ_B11  @S9S_MB_2U_LIB.S9S_MB_2U(SCH_1):M_F_CPU1_SB_DQ<11>
  256  M_F_CPU1_SB_DQ<10>  DQ_B10  @S9S_MB_2U_LIB.S9S_MB_2U(SCH_1):M_F_CPU1_SB_DQ<10>
  100  M_F_CPU1_SB_DQ<0>  DQ_B0  @S9S_MB_2U_LIB.S9S_MB_2U(SCH_1):M_F_CPU1_SB_DQ<0>
  229  M_F_CPU1_SB_CS_N<3>  CS1_N_B  @S9S_MB_2U_LIB.S9S_MB_2U(SCH_1):M_F_CPU1_SB_CS_N<3>
   84  M_F_CPU1_SB_CS_N<2>  CS0_N_B  @S9S_MB_2U_LIB.S9S_MB_2U(SCH_1):M_F_CPU1_SB_CS_N<2>
  236  M_F_CPU1_SB_CB<7>  CB_B7  @S9S_MB_2U_LIB.S9S_MB_2U(SCH_1):M_F_CPU1_SB_CB<7>
  234  M_F_CPU1_SB_CB<6>  CB_B6  @S9S_MB_2U_LIB.S9S_MB_2U(SCH_1):M_F_CPU1_SB_CB<6>
   91  M_F_CPU1_SB_CB<5>  CB_B5  @S9S_MB_2U_LIB.S9S_MB_2U(SCH_1):M_F_CPU1_SB_CB<5>
   89  M_F_CPU1_SB_CB<4>  CB_B4  @S9S_MB_2U_LIB.S9S_MB_2U(SCH_1):M_F_CPU1_SB_CB<4>
  243  M_F_CPU1_SB_CB<3>  CB_B3  @S9S_MB_2U_LIB.S9S_MB_2U(SCH_1):M_F_CPU1_SB_CB<3>
  241  M_F_CPU1_SB_CB<2>  CB_B2  @S9S_MB_2U_LIB.S9S_MB_2U(SCH_1):M_F_CPU1_SB_CB<2>
   98  M_F_CPU1_SB_CB<1>  CB_B1  @S9S_MB_2U_LIB.S9S_MB_2U(SCH_1):M_F_CPU1_SB_CB<1>
   96  M_F_CPU1_SB_CB<0>  CB_B0  @S9S_MB_2U_LIB.S9S_MB_2U(SCH_1):M_F_CPU1_SB_CB<0>
   82  M_F_CPU1_SB_CA<6>  CA6_B  @S9S_MB_2U_LIB.S9S_MB_2U(SCH_1):M_F_CPU1_SB_CA<6>
  225  M_F_CPU1_SB_CA<5>  CA5_B  @S9S_MB_2U_LIB.S9S_MB_2U(SCH_1):M_F_CPU1_SB_CA<5>
   80  M_F_CPU1_SB_CA<4>  CA4_B  @S9S_MB_2U_LIB.S9S_MB_2U(SCH_1):M_F_CPU1_SB_CA<4>
  223  M_F_CPU1_SB_CA<3>  CA3_B  @S9S_MB_2U_LIB.S9S_MB_2U(SCH_1):M_F_CPU1_SB_CA<3>
   78  M_F_CPU1_SB_CA<2>  CA2_B  @S9S_MB_2U_LIB.S9S_MB_2U(SCH_1):M_F_CPU1_SB_CA<2>
  221  M_F_CPU1_SB_CA<1>  CA1_B  @S9S_MB_2U_LIB.S9S_MB_2U(SCH_1):M_F_CPU1_SB_CA<1>
   76  M_F_CPU1_SB_CA<0>  CA0_B  @S9S_MB_2U_LIB.S9S_MB_2U(SCH_1):M_F_CPU1_SB_CA<0>
   86  M_F_CPU1_SA_RSP<1>  LBD||RSP_N_A  @S9S_MB_2U_LIB.S9S_MB_2U(SCH_1):M_F_CPU1_SA_RSP<1>
   74  M_F_CPU1_SA_PAR  PAR_A  @S9S_MB_2U_LIB.S9S_MB_2U(SCH_1):M_F_CPU1_SA_PAR
   20  M_F_CPU1_SA_DQ<9>  DQ_A9  @S9S_MB_2U_LIB.S9S_MB_2U(SCH_1):M_F_CPU1_SA_DQ<9>
   18  M_F_CPU1_SA_DQ<8>  DQ_A8  @S9S_MB_2U_LIB.S9S_MB_2U(SCH_1):M_F_CPU1_SA_DQ<8>
  161  M_F_CPU1_SA_DQ<7>  DQ_A7  @S9S_MB_2U_LIB.S9S_MB_2U(SCH_1):M_F_CPU1_SA_DQ<7>
  159  M_F_CPU1_SA_DQ<6>  DQ_A6  @S9S_MB_2U_LIB.S9S_MB_2U(SCH_1):M_F_CPU1_SA_DQ<6>
   16  M_F_CPU1_SA_DQ<5>  DQ_A5  @S9S_MB_2U_LIB.S9S_MB_2U(SCH_1):M_F_CPU1_SA_DQ<5>
   14  M_F_CPU1_SA_DQ<4>  DQ_A4  @S9S_MB_2U_LIB.S9S_MB_2U(SCH_1):M_F_CPU1_SA_DQ<4>
  154  M_F_CPU1_SA_DQ<3>  DQ_A3  @S9S_MB_2U_LIB.S9S_MB_2U(SCH_1):M_F_CPU1_SA_DQ<3>
  194  M_F_CPU1_SA_DQ<31>  DQ_A31  @S9S_MB_2U_LIB.S9S_MB_2U(SCH_1):M_F_CPU1_SA_DQ<31>
  192  M_F_CPU1_SA_DQ<30>  DQ_A30  @S9S_MB_2U_LIB.S9S_MB_2U(SCH_1):M_F_CPU1_SA_DQ<30>
  152  M_F_CPU1_SA_DQ<2>  DQ_A2  @S9S_MB_2U_LIB.S9S_MB_2U(SCH_1):M_F_CPU1_SA_DQ<2>
   49  M_F_CPU1_SA_DQ<29>  DQ_A29  @S9S_MB_2U_LIB.S9S_MB_2U(SCH_1):M_F_CPU1_SA_DQ<29>
   47  M_F_CPU1_SA_DQ<28>  DQ_A28  @S9S_MB_2U_LIB.S9S_MB_2U(SCH_1):M_F_CPU1_SA_DQ<28>
  187  M_F_CPU1_SA_DQ<27>  DQ_A27  @S9S_MB_2U_LIB.S9S_MB_2U(SCH_1):M_F_CPU1_SA_DQ<27>
  185  M_F_CPU1_SA_DQ<26>  DQ_A26  @S9S_MB_2U_LIB.S9S_MB_2U(SCH_1):M_F_CPU1_SA_DQ<26>
   42  M_F_CPU1_SA_DQ<25>  DQ_A25  @S9S_MB_2U_LIB.S9S_MB_2U(SCH_1):M_F_CPU1_SA_DQ<25>
   40  M_F_CPU1_SA_DQ<24>  DQ_A24  @S9S_MB_2U_LIB.S9S_MB_2U(SCH_1):M_F_CPU1_SA_DQ<24>
  183  M_F_CPU1_SA_DQ<23>  DQ_A23  @S9S_MB_2U_LIB.S9S_MB_2U(SCH_1):M_F_CPU1_SA_DQ<23>
  181  M_F_CPU1_SA_DQ<22>  DQ_A22  @S9S_MB_2U_LIB.S9S_MB_2U(SCH_1):M_F_CPU1_SA_DQ<22>
   38  M_F_CPU1_SA_DQ<21>  DQ_A21  @S9S_MB_2U_LIB.S9S_MB_2U(SCH_1):M_F_CPU1_SA_DQ<21>
   36  M_F_CPU1_SA_DQ<20>  DQ_A20  @S9S_MB_2U_LIB.S9S_MB_2U(SCH_1):M_F_CPU1_SA_DQ<20>
    9  M_F_CPU1_SA_DQ<1>  DQ_A1  @S9S_MB_2U_LIB.S9S_MB_2U(SCH_1):M_F_CPU1_SA_DQ<1>
  176  M_F_CPU1_SA_DQ<19>  DQ_A19  @S9S_MB_2U_LIB.S9S_MB_2U(SCH_1):M_F_CPU1_SA_DQ<19>
  174  M_F_CPU1_SA_DQ<18>  DQ_A18  @S9S_MB_2U_LIB.S9S_MB_2U(SCH_1):M_F_CPU1_SA_DQ<18>
   31  M_F_CPU1_SA_DQ<17>  DQ_A17  @S9S_MB_2U_LIB.S9S_MB_2U(SCH_1):M_F_CPU1_SA_DQ<17>
   29  M_F_CPU1_SA_DQ<16>  DQ_A16  @S9S_MB_2U_LIB.S9S_MB_2U(SCH_1):M_F_CPU1_SA_DQ<16>
  172  M_F_CPU1_SA_DQ<15>  DQ_A15  @S9S_MB_2U_LIB.S9S_MB_2U(SCH_1):M_F_CPU1_SA_DQ<15>
  170  M_F_CPU1_SA_DQ<14>  DQ_A14  @S9S_MB_2U_LIB.S9S_MB_2U(SCH_1):M_F_CPU1_SA_DQ<14>
   27  M_F_CPU1_SA_DQ<13>  DQ_A13  @S9S_MB_2U_LIB.S9S_MB_2U(SCH_1):M_F_CPU1_SA_DQ<13>
   25  M_F_CPU1_SA_DQ<12>  DQ_A12  @S9S_MB_2U_LIB.S9S_MB_2U(SCH_1):M_F_CPU1_SA_DQ<12>
  165  M_F_CPU1_SA_DQ<11>  DQ_A11  @S9S_MB_2U_LIB.S9S_MB_2U(SCH_1):M_F_CPU1_SA_DQ<11>
  163  M_F_CPU1_SA_DQ<10>  DQ_A10  @S9S_MB_2U_LIB.S9S_MB_2U(SCH_1):M_F_CPU1_SA_DQ<10>
    7  M_F_CPU1_SA_DQ<0>  DQ_A0  @S9S_MB_2U_LIB.S9S_MB_2U(SCH_1):M_F_CPU1_SA_DQ<0>
  209  M_F_CPU1_SA_CS_N<3>  CS1_N_A  @S9S_MB_2U_LIB.S9S_MB_2U(SCH_1):M_F_CPU1_SA_CS_N<3>
   64  M_F_CPU1_SA_CS_N<2>  CS0_N_A  @S9S_MB_2U_LIB.S9S_MB_2U(SCH_1):M_F_CPU1_SA_CS_N<2>
  205  M_F_CPU1_SA_CB<7>  CB_A7  @S9S_MB_2U_LIB.S9S_MB_2U(SCH_1):M_F_CPU1_SA_CB<7>
  203  M_F_CPU1_SA_CB<6>  CB_A6  @S9S_MB_2U_LIB.S9S_MB_2U(SCH_1):M_F_CPU1_SA_CB<6>
   60  M_F_CPU1_SA_CB<5>  CB_A5  @S9S_MB_2U_LIB.S9S_MB_2U(SCH_1):M_F_CPU1_SA_CB<5>
   58  M_F_CPU1_SA_CB<4>  CB_A4  @S9S_MB_2U_LIB.S9S_MB_2U(SCH_1):M_F_CPU1_SA_CB<4>
  198  M_F_CPU1_SA_CB<3>  CB_A3  @S9S_MB_2U_LIB.S9S_MB_2U(SCH_1):M_F_CPU1_SA_CB<3>
  196  M_F_CPU1_SA_CB<2>  CB_A2  @S9S_MB_2U_LIB.S9S_MB_2U(SCH_1):M_F_CPU1_SA_CB<2>
   53  M_F_CPU1_SA_CB<1>  CB_A1  @S9S_MB_2U_LIB.S9S_MB_2U(SCH_1):M_F_CPU1_SA_CB<1>
   51  M_F_CPU1_SA_CB<0>  CB_A0  @S9S_MB_2U_LIB.S9S_MB_2U(SCH_1):M_F_CPU1_SA_CB<0>
   72  M_F_CPU1_SA_CA<6>  CA6_A  @S9S_MB_2U_LIB.S9S_MB_2U(SCH_1):M_F_CPU1_SA_CA<6>
  215  M_F_CPU1_SA_CA<5>  CA5_A  @S9S_MB_2U_LIB.S9S_MB_2U(SCH_1):M_F_CPU1_SA_CA<5>
   70  M_F_CPU1_SA_CA<4>  CA4_A  @S9S_MB_2U_LIB.S9S_MB_2U(SCH_1):M_F_CPU1_SA_CA<4>
  213  M_F_CPU1_SA_CA<3>  CA3_A  @S9S_MB_2U_LIB.S9S_MB_2U(SCH_1):M_F_CPU1_SA_CA<3>
   68  M_F_CPU1_SA_CA<2>  CA2_A  @S9S_MB_2U_LIB.S9S_MB_2U(SCH_1):M_F_CPU1_SA_CA<2>
  211  M_F_CPU1_SA_CA<1>  CA1_A  @S9S_MB_2U_LIB.S9S_MB_2U(SCH_1):M_F_CPU1_SA_CA<1>
   66  M_F_CPU1_SA_CA<0>  CA0_A  @S9S_MB_2U_LIB.S9S_MB_2U(SCH_1):M_F_CPU1_SA_CA<0>
  217  M_F_CPU1_CLK_DP<1>   CK_P  @S9S_MB_2U_LIB.S9S_MB_2U(SCH_1):M_F_CPU1_CLK_DP<1>
  218  M_F_CPU1_CLK_DN<1>   CK_N  @S9S_MB_2U_LIB.S9S_MB_2U(SCH_1):M_F_CPU1_CLK_DN<1>
   62  M_F_CPU1_ALERT_N  ALERT_N  @S9S_MB_2U_LIB.S9S_MB_2U(SCH_1):M_F_CPU1_ALERT_N
    5  I3C_SPD_DDREFGH_CPU1_LVC1_SDA   HSDA  @S9S_MB_2U_LIB.S9S_MB_2U(SCH_1):I3C_SPD_DDREFGH_CPU1_LVC1_SDA
    4  I3C_SPD_DDREFGH_CPU1_LVC1_SCL   HSCL  @S9S_MB_2U_LIB.S9S_MB_2U(SCH_1):I3C_SPD_DDREFGH_CPU1_LVC1_SCL

SCONN288_ADR50001P013C01  I178  J29    [SCONN288_ADR50001P013C01-SCONNA]
  146  P12V_S3_AUX_CPU1_NVDIMM  VIN_BULK2  @S9S_MB_2U_LIB.S9S_MB_2U(SCH_1):P12V_S3_AUX_CPU1_NVDIMM
  145  P12V_S3_AUX_CPU1_NVDIMM  VIN_BULK1  @S9S_MB_2U_LIB.S9S_MB_2U(SCH_1):P12V_S3_AUX_CPU1_NVDIMM
    1  P12V_S3_AUX_CPU1_NVDIMM  VIN_BULK0  @S9S_MB_2U_LIB.S9S_MB_2U(SCH_1):P12V_S3_AUX_CPU1_NVDIMM
  288  GND            VSS126  @S9S_MB_2U_LIB.S9S_MB_2U(SCH_1):GND
  286  GND            VSS125  @S9S_MB_2U_LIB.S9S_MB_2U(SCH_1):GND
  284  GND            VSS124  @S9S_MB_2U_LIB.S9S_MB_2U(SCH_1):GND
  281  GND            VSS123  @S9S_MB_2U_LIB.S9S_MB_2U(SCH_1):GND
  279  GND            VSS122  @S9S_MB_2U_LIB.S9S_MB_2U(SCH_1):GND
  277  GND            VSS121  @S9S_MB_2U_LIB.S9S_MB_2U(SCH_1):GND
  275  GND            VSS120  @S9S_MB_2U_LIB.S9S_MB_2U(SCH_1):GND
  273  GND            VSS119  @S9S_MB_2U_LIB.S9S_MB_2U(SCH_1):GND
  270  GND            VSS118  @S9S_MB_2U_LIB.S9S_MB_2U(SCH_1):GND
  268  GND            VSS117  @S9S_MB_2U_LIB.S9S_MB_2U(SCH_1):GND
  266  GND            VSS116  @S9S_MB_2U_LIB.S9S_MB_2U(SCH_1):GND
  264  GND            VSS115  @S9S_MB_2U_LIB.S9S_MB_2U(SCH_1):GND
  262  GND            VSS114  @S9S_MB_2U_LIB.S9S_MB_2U(SCH_1):GND
  259  GND            VSS113  @S9S_MB_2U_LIB.S9S_MB_2U(SCH_1):GND
  257  GND            VSS112  @S9S_MB_2U_LIB.S9S_MB_2U(SCH_1):GND
  255  GND            VSS111  @S9S_MB_2U_LIB.S9S_MB_2U(SCH_1):GND
  253  GND            VSS110  @S9S_MB_2U_LIB.S9S_MB_2U(SCH_1):GND
  251  GND            VSS109  @S9S_MB_2U_LIB.S9S_MB_2U(SCH_1):GND
  248  GND            VSS108  @S9S_MB_2U_LIB.S9S_MB_2U(SCH_1):GND
  246  GND            VSS107  @S9S_MB_2U_LIB.S9S_MB_2U(SCH_1):GND
  244  GND            VSS106  @S9S_MB_2U_LIB.S9S_MB_2U(SCH_1):GND
  242  GND            VSS105  @S9S_MB_2U_LIB.S9S_MB_2U(SCH_1):GND
  240  GND            VSS104  @S9S_MB_2U_LIB.S9S_MB_2U(SCH_1):GND
  237  GND            VSS103  @S9S_MB_2U_LIB.S9S_MB_2U(SCH_1):GND
  235  GND            VSS102  @S9S_MB_2U_LIB.S9S_MB_2U(SCH_1):GND
  233  GND            VSS101  @S9S_MB_2U_LIB.S9S_MB_2U(SCH_1):GND
  230  GND            VSS100  @S9S_MB_2U_LIB.S9S_MB_2U(SCH_1):GND
  228  GND            VSS99  @S9S_MB_2U_LIB.S9S_MB_2U(SCH_1):GND
  226  GND            VSS98  @S9S_MB_2U_LIB.S9S_MB_2U(SCH_1):GND
  224  GND            VSS97  @S9S_MB_2U_LIB.S9S_MB_2U(SCH_1):GND
  222  GND            VSS96  @S9S_MB_2U_LIB.S9S_MB_2U(SCH_1):GND
  219  GND            VSS95  @S9S_MB_2U_LIB.S9S_MB_2U(SCH_1):GND
  216  GND            VSS94  @S9S_MB_2U_LIB.S9S_MB_2U(SCH_1):GND
  214  GND            VSS93  @S9S_MB_2U_LIB.S9S_MB_2U(SCH_1):GND
  212  GND            VSS92  @S9S_MB_2U_LIB.S9S_MB_2U(SCH_1):GND
  210  GND            VSS91  @S9S_MB_2U_LIB.S9S_MB_2U(SCH_1):GND
  208  GND            VSS90  @S9S_MB_2U_LIB.S9S_MB_2U(SCH_1):GND
  206  GND            VSS89  @S9S_MB_2U_LIB.S9S_MB_2U(SCH_1):GND
  204  GND            VSS88  @S9S_MB_2U_LIB.S9S_MB_2U(SCH_1):GND
  202  GND            VSS87  @S9S_MB_2U_LIB.S9S_MB_2U(SCH_1):GND
  199  GND            VSS86  @S9S_MB_2U_LIB.S9S_MB_2U(SCH_1):GND
  197  GND            VSS85  @S9S_MB_2U_LIB.S9S_MB_2U(SCH_1):GND
  195  GND            VSS84  @S9S_MB_2U_LIB.S9S_MB_2U(SCH_1):GND
  193  GND            VSS83  @S9S_MB_2U_LIB.S9S_MB_2U(SCH_1):GND
  191  GND            VSS82  @S9S_MB_2U_LIB.S9S_MB_2U(SCH_1):GND
  188  GND            VSS81  @S9S_MB_2U_LIB.S9S_MB_2U(SCH_1):GND
  186  GND            VSS80  @S9S_MB_2U_LIB.S9S_MB_2U(SCH_1):GND
  184  GND            VSS79  @S9S_MB_2U_LIB.S9S_MB_2U(SCH_1):GND
  182  GND            VSS78  @S9S_MB_2U_LIB.S9S_MB_2U(SCH_1):GND
  180  GND            VSS77  @S9S_MB_2U_LIB.S9S_MB_2U(SCH_1):GND
  177  GND            VSS76  @S9S_MB_2U_LIB.S9S_MB_2U(SCH_1):GND
  175  GND            VSS75  @S9S_MB_2U_LIB.S9S_MB_2U(SCH_1):GND
  173  GND            VSS74  @S9S_MB_2U_LIB.S9S_MB_2U(SCH_1):GND
  171  GND            VSS73  @S9S_MB_2U_LIB.S9S_MB_2U(SCH_1):GND
  169  GND            VSS72  @S9S_MB_2U_LIB.S9S_MB_2U(SCH_1):GND
  166  GND            VSS71  @S9S_MB_2U_LIB.S9S_MB_2U(SCH_1):GND
  164  GND            VSS70  @S9S_MB_2U_LIB.S9S_MB_2U(SCH_1):GND
  162  GND            VSS69  @S9S_MB_2U_LIB.S9S_MB_2U(SCH_1):GND
  160  GND            VSS68  @S9S_MB_2U_LIB.S9S_MB_2U(SCH_1):GND
  158  GND            VSS67  @S9S_MB_2U_LIB.S9S_MB_2U(SCH_1):GND
  155  GND            VSS66  @S9S_MB_2U_LIB.S9S_MB_2U(SCH_1):GND
  153  GND            VSS65  @S9S_MB_2U_LIB.S9S_MB_2U(SCH_1):GND
  151  GND            VSS64  @S9S_MB_2U_LIB.S9S_MB_2U(SCH_1):GND
  143  GND            VSS63  @S9S_MB_2U_LIB.S9S_MB_2U(SCH_1):GND
  141  GND            VSS62  @S9S_MB_2U_LIB.S9S_MB_2U(SCH_1):GND
  139  GND            VSS61  @S9S_MB_2U_LIB.S9S_MB_2U(SCH_1):GND
  136  GND            VSS60  @S9S_MB_2U_LIB.S9S_MB_2U(SCH_1):GND
  134  GND            VSS59  @S9S_MB_2U_LIB.S9S_MB_2U(SCH_1):GND
  132  GND            VSS58  @S9S_MB_2U_LIB.S9S_MB_2U(SCH_1):GND
  130  GND            VSS57  @S9S_MB_2U_LIB.S9S_MB_2U(SCH_1):GND
  128  GND            VSS56  @S9S_MB_2U_LIB.S9S_MB_2U(SCH_1):GND
  125  GND            VSS55  @S9S_MB_2U_LIB.S9S_MB_2U(SCH_1):GND
  123  GND            VSS54  @S9S_MB_2U_LIB.S9S_MB_2U(SCH_1):GND
  121  GND            VSS53  @S9S_MB_2U_LIB.S9S_MB_2U(SCH_1):GND
  119  GND            VSS52  @S9S_MB_2U_LIB.S9S_MB_2U(SCH_1):GND
  117  GND            VSS51  @S9S_MB_2U_LIB.S9S_MB_2U(SCH_1):GND
  114  GND            VSS50  @S9S_MB_2U_LIB.S9S_MB_2U(SCH_1):GND
  112  GND            VSS49  @S9S_MB_2U_LIB.S9S_MB_2U(SCH_1):GND
  110  GND            VSS48  @S9S_MB_2U_LIB.S9S_MB_2U(SCH_1):GND
  108  GND            VSS47  @S9S_MB_2U_LIB.S9S_MB_2U(SCH_1):GND
  106  GND            VSS46  @S9S_MB_2U_LIB.S9S_MB_2U(SCH_1):GND
  103  GND            VSS45  @S9S_MB_2U_LIB.S9S_MB_2U(SCH_1):GND
  101  GND            VSS44  @S9S_MB_2U_LIB.S9S_MB_2U(SCH_1):GND
   99  GND            VSS43  @S9S_MB_2U_LIB.S9S_MB_2U(SCH_1):GND
   97  GND            VSS42  @S9S_MB_2U_LIB.S9S_MB_2U(SCH_1):GND
   95  GND            VSS41  @S9S_MB_2U_LIB.S9S_MB_2U(SCH_1):GND
   92  GND            VSS40  @S9S_MB_2U_LIB.S9S_MB_2U(SCH_1):GND
   90  GND            VSS39  @S9S_MB_2U_LIB.S9S_MB_2U(SCH_1):GND
   88  GND            VSS38  @S9S_MB_2U_LIB.S9S_MB_2U(SCH_1):GND
   85  GND            VSS37  @S9S_MB_2U_LIB.S9S_MB_2U(SCH_1):GND
   83  GND            VSS36  @S9S_MB_2U_LIB.S9S_MB_2U(SCH_1):GND
   81  GND            VSS35  @S9S_MB_2U_LIB.S9S_MB_2U(SCH_1):GND
   79  GND            VSS34  @S9S_MB_2U_LIB.S9S_MB_2U(SCH_1):GND
   77  GND            VSS33  @S9S_MB_2U_LIB.S9S_MB_2U(SCH_1):GND
   75  GND            VSS32  @S9S_MB_2U_LIB.S9S_MB_2U(SCH_1):GND
   73  GND            VSS31  @S9S_MB_2U_LIB.S9S_MB_2U(SCH_1):GND
   71  GND            VSS30  @S9S_MB_2U_LIB.S9S_MB_2U(SCH_1):GND
   69  GND            VSS29  @S9S_MB_2U_LIB.S9S_MB_2U(SCH_1):GND
   67  GND            VSS28  @S9S_MB_2U_LIB.S9S_MB_2U(SCH_1):GND
   65  GND            VSS27  @S9S_MB_2U_LIB.S9S_MB_2U(SCH_1):GND
   63  GND            VSS26  @S9S_MB_2U_LIB.S9S_MB_2U(SCH_1):GND
   61  GND            VSS25  @S9S_MB_2U_LIB.S9S_MB_2U(SCH_1):GND
   59  GND            VSS24  @S9S_MB_2U_LIB.S9S_MB_2U(SCH_1):GND
   57  GND            VSS23  @S9S_MB_2U_LIB.S9S_MB_2U(SCH_1):GND
   54  GND            VSS22  @S9S_MB_2U_LIB.S9S_MB_2U(SCH_1):GND
   52  GND            VSS21  @S9S_MB_2U_LIB.S9S_MB_2U(SCH_1):GND
   50  GND            VSS20  @S9S_MB_2U_LIB.S9S_MB_2U(SCH_1):GND
   48  GND            VSS19  @S9S_MB_2U_LIB.S9S_MB_2U(SCH_1):GND
   46  GND            VSS18  @S9S_MB_2U_LIB.S9S_MB_2U(SCH_1):GND
   43  GND            VSS17  @S9S_MB_2U_LIB.S9S_MB_2U(SCH_1):GND
   41  GND            VSS16  @S9S_MB_2U_LIB.S9S_MB_2U(SCH_1):GND
   39  GND            VSS15  @S9S_MB_2U_LIB.S9S_MB_2U(SCH_1):GND
   37  GND            VSS14  @S9S_MB_2U_LIB.S9S_MB_2U(SCH_1):GND
   35  GND            VSS13  @S9S_MB_2U_LIB.S9S_MB_2U(SCH_1):GND
   32  GND            VSS12  @S9S_MB_2U_LIB.S9S_MB_2U(SCH_1):GND
   30  GND            VSS11  @S9S_MB_2U_LIB.S9S_MB_2U(SCH_1):GND
   28  GND            VSS10  @S9S_MB_2U_LIB.S9S_MB_2U(SCH_1):GND
   26  GND             VSS9  @S9S_MB_2U_LIB.S9S_MB_2U(SCH_1):GND
   24  GND             VSS8  @S9S_MB_2U_LIB.S9S_MB_2U(SCH_1):GND
   21  GND             VSS7  @S9S_MB_2U_LIB.S9S_MB_2U(SCH_1):GND
   19  GND             VSS6  @S9S_MB_2U_LIB.S9S_MB_2U(SCH_1):GND
   17  GND             VSS5  @S9S_MB_2U_LIB.S9S_MB_2U(SCH_1):GND
   15  GND             VSS4  @S9S_MB_2U_LIB.S9S_MB_2U(SCH_1):GND
   13  GND             VSS3  @S9S_MB_2U_LIB.S9S_MB_2U(SCH_1):GND
   10  GND             VSS2  @S9S_MB_2U_LIB.S9S_MB_2U(SCH_1):GND
    8  GND             VSS1  @S9S_MB_2U_LIB.S9S_MB_2U(SCH_1):GND
    6  GND             VSS0  @S9S_MB_2U_LIB.S9S_MB_2U(SCH_1):GND
   G3  GND               G3  @S9S_MB_2U_LIB.S9S_MB_2U(SCH_1):GND
   G2  GND               G2  @S9S_MB_2U_LIB.S9S_MB_2U(SCH_1):GND
   G1  GND               G1  @S9S_MB_2U_LIB.S9S_MB_2U(SCH_1):GND

SCONN288_ADR50001P013C01  I177  J29    [SCONN288_ADR50001P013C01-SCONNA]
   93  M_G_CPU1_SB_DQS_DP<9>  DQS9_B_P  @S9S_MB_2U_LIB.S9S_MB_2U(SCH_1):M_G_CPU1_SB_DQS_DP<9>
  283  M_G_CPU1_SB_DQS_DP<8>  DQS8_B_P  @S9S_MB_2U_LIB.S9S_MB_2U(SCH_1):M_G_CPU1_SB_DQS_DP<8>
  272  M_G_CPU1_SB_DQS_DP<7>  DQS7_B_P  @S9S_MB_2U_LIB.S9S_MB_2U(SCH_1):M_G_CPU1_SB_DQS_DP<7>
  261  M_G_CPU1_SB_DQS_DP<6>  DQS6_B_P  @S9S_MB_2U_LIB.S9S_MB_2U(SCH_1):M_G_CPU1_SB_DQS_DP<6>
  250  M_G_CPU1_SB_DQS_DP<5>  DQS5_B_P  @S9S_MB_2U_LIB.S9S_MB_2U(SCH_1):M_G_CPU1_SB_DQS_DP<5>
  239  M_G_CPU1_SB_DQS_DP<4>  DQS4_B_P  @S9S_MB_2U_LIB.S9S_MB_2U(SCH_1):M_G_CPU1_SB_DQS_DP<4>
  137  M_G_CPU1_SB_DQS_DP<3>  DQS3_B_P  @S9S_MB_2U_LIB.S9S_MB_2U(SCH_1):M_G_CPU1_SB_DQS_DP<3>
  126  M_G_CPU1_SB_DQS_DP<2>  DQS2_B_P  @S9S_MB_2U_LIB.S9S_MB_2U(SCH_1):M_G_CPU1_SB_DQS_DP<2>
  115  M_G_CPU1_SB_DQS_DP<1>  DQS1_B_P  @S9S_MB_2U_LIB.S9S_MB_2U(SCH_1):M_G_CPU1_SB_DQS_DP<1>
  104  M_G_CPU1_SB_DQS_DP<0>  DQS0_B_P  @S9S_MB_2U_LIB.S9S_MB_2U(SCH_1):M_G_CPU1_SB_DQS_DP<0>
   94  M_G_CPU1_SB_DQS_DN<9>  DQS9_B_N  @S9S_MB_2U_LIB.S9S_MB_2U(SCH_1):M_G_CPU1_SB_DQS_DN<9>
  282  M_G_CPU1_SB_DQS_DN<8>  DQS8_B_N  @S9S_MB_2U_LIB.S9S_MB_2U(SCH_1):M_G_CPU1_SB_DQS_DN<8>
  271  M_G_CPU1_SB_DQS_DN<7>  DQS7_B_N  @S9S_MB_2U_LIB.S9S_MB_2U(SCH_1):M_G_CPU1_SB_DQS_DN<7>
  260  M_G_CPU1_SB_DQS_DN<6>  DQS6_B_N  @S9S_MB_2U_LIB.S9S_MB_2U(SCH_1):M_G_CPU1_SB_DQS_DN<6>
  249  M_G_CPU1_SB_DQS_DN<5>  DQS5_B_N  @S9S_MB_2U_LIB.S9S_MB_2U(SCH_1):M_G_CPU1_SB_DQS_DN<5>
  238  M_G_CPU1_SB_DQS_DN<4>  DQS4_B_N  @S9S_MB_2U_LIB.S9S_MB_2U(SCH_1):M_G_CPU1_SB_DQS_DN<4>
  138  M_G_CPU1_SB_DQS_DN<3>  DQS3_B_N  @S9S_MB_2U_LIB.S9S_MB_2U(SCH_1):M_G_CPU1_SB_DQS_DN<3>
  127  M_G_CPU1_SB_DQS_DN<2>  DQS2_B_N  @S9S_MB_2U_LIB.S9S_MB_2U(SCH_1):M_G_CPU1_SB_DQS_DN<2>
  116  M_G_CPU1_SB_DQS_DN<1>  DQS1_B_N  @S9S_MB_2U_LIB.S9S_MB_2U(SCH_1):M_G_CPU1_SB_DQS_DN<1>
  105  M_G_CPU1_SB_DQS_DN<0>  DQS0_B_N  @S9S_MB_2U_LIB.S9S_MB_2U(SCH_1):M_G_CPU1_SB_DQS_DN<0>
  201  M_G_CPU1_SA_DQS_DP<9>  DQS9_A_P  @S9S_MB_2U_LIB.S9S_MB_2U(SCH_1):M_G_CPU1_SA_DQS_DP<9>
  190  M_G_CPU1_SA_DQS_DP<8>  DQS8_A_P  @S9S_MB_2U_LIB.S9S_MB_2U(SCH_1):M_G_CPU1_SA_DQS_DP<8>
  179  M_G_CPU1_SA_DQS_DP<7>  DQS7_A_P  @S9S_MB_2U_LIB.S9S_MB_2U(SCH_1):M_G_CPU1_SA_DQS_DP<7>
  168  M_G_CPU1_SA_DQS_DP<6>  DQS6_A_P  @S9S_MB_2U_LIB.S9S_MB_2U(SCH_1):M_G_CPU1_SA_DQS_DP<6>
  157  M_G_CPU1_SA_DQS_DP<5>  DQS5_A_P  @S9S_MB_2U_LIB.S9S_MB_2U(SCH_1):M_G_CPU1_SA_DQS_DP<5>
   55  M_G_CPU1_SA_DQS_DP<4>  DQS4_A_P  @S9S_MB_2U_LIB.S9S_MB_2U(SCH_1):M_G_CPU1_SA_DQS_DP<4>
   44  M_G_CPU1_SA_DQS_DP<3>  DQS3_A_P  @S9S_MB_2U_LIB.S9S_MB_2U(SCH_1):M_G_CPU1_SA_DQS_DP<3>
   33  M_G_CPU1_SA_DQS_DP<2>  DQS2_A_P  @S9S_MB_2U_LIB.S9S_MB_2U(SCH_1):M_G_CPU1_SA_DQS_DP<2>
   22  M_G_CPU1_SA_DQS_DP<1>  DQS1_A_P  @S9S_MB_2U_LIB.S9S_MB_2U(SCH_1):M_G_CPU1_SA_DQS_DP<1>
   11  M_G_CPU1_SA_DQS_DP<0>  DQS0_A_P  @S9S_MB_2U_LIB.S9S_MB_2U(SCH_1):M_G_CPU1_SA_DQS_DP<0>
  200  M_G_CPU1_SA_DQS_DN<9>  DQS9_A_N  @S9S_MB_2U_LIB.S9S_MB_2U(SCH_1):M_G_CPU1_SA_DQS_DN<9>
  189  M_G_CPU1_SA_DQS_DN<8>  DQS8_A_N  @S9S_MB_2U_LIB.S9S_MB_2U(SCH_1):M_G_CPU1_SA_DQS_DN<8>
  178  M_G_CPU1_SA_DQS_DN<7>  DQS7_A_N  @S9S_MB_2U_LIB.S9S_MB_2U(SCH_1):M_G_CPU1_SA_DQS_DN<7>
  167  M_G_CPU1_SA_DQS_DN<6>  DQS6_A_N  @S9S_MB_2U_LIB.S9S_MB_2U(SCH_1):M_G_CPU1_SA_DQS_DN<6>
  156  M_G_CPU1_SA_DQS_DN<5>  DQS5_A_N  @S9S_MB_2U_LIB.S9S_MB_2U(SCH_1):M_G_CPU1_SA_DQS_DN<5>
   56  M_G_CPU1_SA_DQS_DN<4>  DQS4_A_N  @S9S_MB_2U_LIB.S9S_MB_2U(SCH_1):M_G_CPU1_SA_DQS_DN<4>
   45  M_G_CPU1_SA_DQS_DN<3>  DQS3_A_N  @S9S_MB_2U_LIB.S9S_MB_2U(SCH_1):M_G_CPU1_SA_DQS_DN<3>
   34  M_G_CPU1_SA_DQS_DN<2>  DQS2_A_N  @S9S_MB_2U_LIB.S9S_MB_2U(SCH_1):M_G_CPU1_SA_DQS_DN<2>
   23  M_G_CPU1_SA_DQS_DN<1>  DQS1_A_N  @S9S_MB_2U_LIB.S9S_MB_2U(SCH_1):M_G_CPU1_SA_DQS_DN<1>
   12  M_G_CPU1_SA_DQS_DN<0>  DQS0_A_N  @S9S_MB_2U_LIB.S9S_MB_2U(SCH_1):M_G_CPU1_SA_DQS_DN<0>

SCONN288_ADR50001P013C01  I179  J29    [SCONN288_ADR50001P013C01-SCONNA]
  232  NC              RFU6  NC
  231  NC              RFU5  NC
  220  NC              RFU4  NC
  150  NC              RFU3  NC
  149  NC              RFU2  NC
  144  NC              RFU1  NC
    2  NC              RFU0  NC
  207  RST_M_GH_CPU1_FPGA_N  RESET_N  @S9S_MB_2U_LIB.S9S_MB_2U(SCH_1):RST_M_GH_CPU1_FPGA_N
  147  PWRGD_CHG_CPU1_DIMM1  PWR_GOOD||FAIL_N  @S9S_MB_2U_LIB.S9S_MB_2U(SCH_1):PWRGD_CHG_CPU1_DIMM1
  148  PD_CHG_CPU1_DIMM1_SAA    HAS  @S9S_MB_2U_LIB.S9S_MB_2U(SCH_1):PD_CHG_CPU1_DIMM1_SAA
    3  P3V3_AUX       VIN_MGMT  @S9S_MB_2U_LIB.S9S_MB_2U(SCH_1):P3V3_AUX
   87  M_G_CPU1_SB_RSP<0>  LBS||RSP_N_B  @S9S_MB_2U_LIB.S9S_MB_2U(SCH_1):M_G_CPU1_SB_RSP<0>
  227  M_G_CPU1_SB_PAR  PAR_B  @S9S_MB_2U_LIB.S9S_MB_2U(SCH_1):M_G_CPU1_SB_PAR
  113  M_G_CPU1_SB_DQ<9>  DQ_B9  @S9S_MB_2U_LIB.S9S_MB_2U(SCH_1):M_G_CPU1_SB_DQ<9>
  111  M_G_CPU1_SB_DQ<8>  DQ_B8  @S9S_MB_2U_LIB.S9S_MB_2U(SCH_1):M_G_CPU1_SB_DQ<8>
  254  M_G_CPU1_SB_DQ<7>  DQ_B7  @S9S_MB_2U_LIB.S9S_MB_2U(SCH_1):M_G_CPU1_SB_DQ<7>
  252  M_G_CPU1_SB_DQ<6>  DQ_B6  @S9S_MB_2U_LIB.S9S_MB_2U(SCH_1):M_G_CPU1_SB_DQ<6>
  109  M_G_CPU1_SB_DQ<5>  DQ_B5  @S9S_MB_2U_LIB.S9S_MB_2U(SCH_1):M_G_CPU1_SB_DQ<5>
  107  M_G_CPU1_SB_DQ<4>  DQ_B4  @S9S_MB_2U_LIB.S9S_MB_2U(SCH_1):M_G_CPU1_SB_DQ<4>
  247  M_G_CPU1_SB_DQ<3>  DQ_B3  @S9S_MB_2U_LIB.S9S_MB_2U(SCH_1):M_G_CPU1_SB_DQ<3>
  287  M_G_CPU1_SB_DQ<31>  DQ_B31  @S9S_MB_2U_LIB.S9S_MB_2U(SCH_1):M_G_CPU1_SB_DQ<31>
  285  M_G_CPU1_SB_DQ<30>  DQ_B30  @S9S_MB_2U_LIB.S9S_MB_2U(SCH_1):M_G_CPU1_SB_DQ<30>
  245  M_G_CPU1_SB_DQ<2>  DQ_B2  @S9S_MB_2U_LIB.S9S_MB_2U(SCH_1):M_G_CPU1_SB_DQ<2>
  142  M_G_CPU1_SB_DQ<29>  DQ_B29  @S9S_MB_2U_LIB.S9S_MB_2U(SCH_1):M_G_CPU1_SB_DQ<29>
  140  M_G_CPU1_SB_DQ<28>  DQ_B28  @S9S_MB_2U_LIB.S9S_MB_2U(SCH_1):M_G_CPU1_SB_DQ<28>
  280  M_G_CPU1_SB_DQ<27>  DQ_B27  @S9S_MB_2U_LIB.S9S_MB_2U(SCH_1):M_G_CPU1_SB_DQ<27>
  278  M_G_CPU1_SB_DQ<26>  DQ_B26  @S9S_MB_2U_LIB.S9S_MB_2U(SCH_1):M_G_CPU1_SB_DQ<26>
  135  M_G_CPU1_SB_DQ<25>  DQ_B25  @S9S_MB_2U_LIB.S9S_MB_2U(SCH_1):M_G_CPU1_SB_DQ<25>
  133  M_G_CPU1_SB_DQ<24>  DQ_B24  @S9S_MB_2U_LIB.S9S_MB_2U(SCH_1):M_G_CPU1_SB_DQ<24>
  276  M_G_CPU1_SB_DQ<23>  DQ_B23  @S9S_MB_2U_LIB.S9S_MB_2U(SCH_1):M_G_CPU1_SB_DQ<23>
  274  M_G_CPU1_SB_DQ<22>  DQ_B22  @S9S_MB_2U_LIB.S9S_MB_2U(SCH_1):M_G_CPU1_SB_DQ<22>
  131  M_G_CPU1_SB_DQ<21>  DQ_B21  @S9S_MB_2U_LIB.S9S_MB_2U(SCH_1):M_G_CPU1_SB_DQ<21>
  129  M_G_CPU1_SB_DQ<20>  DQ_B20  @S9S_MB_2U_LIB.S9S_MB_2U(SCH_1):M_G_CPU1_SB_DQ<20>
  102  M_G_CPU1_SB_DQ<1>  DQ_B1  @S9S_MB_2U_LIB.S9S_MB_2U(SCH_1):M_G_CPU1_SB_DQ<1>
  269  M_G_CPU1_SB_DQ<19>  DQ_B19  @S9S_MB_2U_LIB.S9S_MB_2U(SCH_1):M_G_CPU1_SB_DQ<19>
  267  M_G_CPU1_SB_DQ<18>  DQ_B18  @S9S_MB_2U_LIB.S9S_MB_2U(SCH_1):M_G_CPU1_SB_DQ<18>
  124  M_G_CPU1_SB_DQ<17>  DQ_B17  @S9S_MB_2U_LIB.S9S_MB_2U(SCH_1):M_G_CPU1_SB_DQ<17>
  122  M_G_CPU1_SB_DQ<16>  DQ_B16  @S9S_MB_2U_LIB.S9S_MB_2U(SCH_1):M_G_CPU1_SB_DQ<16>
  265  M_G_CPU1_SB_DQ<15>  DQ_B15  @S9S_MB_2U_LIB.S9S_MB_2U(SCH_1):M_G_CPU1_SB_DQ<15>
  263  M_G_CPU1_SB_DQ<14>  DQ_B14  @S9S_MB_2U_LIB.S9S_MB_2U(SCH_1):M_G_CPU1_SB_DQ<14>
  120  M_G_CPU1_SB_DQ<13>  DQ_B13  @S9S_MB_2U_LIB.S9S_MB_2U(SCH_1):M_G_CPU1_SB_DQ<13>
  118  M_G_CPU1_SB_DQ<12>  DQ_B12  @S9S_MB_2U_LIB.S9S_MB_2U(SCH_1):M_G_CPU1_SB_DQ<12>
  258  M_G_CPU1_SB_DQ<11>  DQ_B11  @S9S_MB_2U_LIB.S9S_MB_2U(SCH_1):M_G_CPU1_SB_DQ<11>
  256  M_G_CPU1_SB_DQ<10>  DQ_B10  @S9S_MB_2U_LIB.S9S_MB_2U(SCH_1):M_G_CPU1_SB_DQ<10>
  100  M_G_CPU1_SB_DQ<0>  DQ_B0  @S9S_MB_2U_LIB.S9S_MB_2U(SCH_1):M_G_CPU1_SB_DQ<0>
  229  M_G_CPU1_SB_CS_N<1>  CS1_N_B  @S9S_MB_2U_LIB.S9S_MB_2U(SCH_1):M_G_CPU1_SB_CS_N<1>
   84  M_G_CPU1_SB_CS_N<0>  CS0_N_B  @S9S_MB_2U_LIB.S9S_MB_2U(SCH_1):M_G_CPU1_SB_CS_N<0>
  236  M_G_CPU1_SB_CB<7>  CB_B7  @S9S_MB_2U_LIB.S9S_MB_2U(SCH_1):M_G_CPU1_SB_CB<7>
  234  M_G_CPU1_SB_CB<6>  CB_B6  @S9S_MB_2U_LIB.S9S_MB_2U(SCH_1):M_G_CPU1_SB_CB<6>
   91  M_G_CPU1_SB_CB<5>  CB_B5  @S9S_MB_2U_LIB.S9S_MB_2U(SCH_1):M_G_CPU1_SB_CB<5>
   89  M_G_CPU1_SB_CB<4>  CB_B4  @S9S_MB_2U_LIB.S9S_MB_2U(SCH_1):M_G_CPU1_SB_CB<4>
  243  M_G_CPU1_SB_CB<3>  CB_B3  @S9S_MB_2U_LIB.S9S_MB_2U(SCH_1):M_G_CPU1_SB_CB<3>
  241  M_G_CPU1_SB_CB<2>  CB_B2  @S9S_MB_2U_LIB.S9S_MB_2U(SCH_1):M_G_CPU1_SB_CB<2>
   98  M_G_CPU1_SB_CB<1>  CB_B1  @S9S_MB_2U_LIB.S9S_MB_2U(SCH_1):M_G_CPU1_SB_CB<1>
   96  M_G_CPU1_SB_CB<0>  CB_B0  @S9S_MB_2U_LIB.S9S_MB_2U(SCH_1):M_G_CPU1_SB_CB<0>
   82  M_G_CPU1_SB_CA<6>  CA6_B  @S9S_MB_2U_LIB.S9S_MB_2U(SCH_1):M_G_CPU1_SB_CA<6>
  225  M_G_CPU1_SB_CA<5>  CA5_B  @S9S_MB_2U_LIB.S9S_MB_2U(SCH_1):M_G_CPU1_SB_CA<5>
   80  M_G_CPU1_SB_CA<4>  CA4_B  @S9S_MB_2U_LIB.S9S_MB_2U(SCH_1):M_G_CPU1_SB_CA<4>
  223  M_G_CPU1_SB_CA<3>  CA3_B  @S9S_MB_2U_LIB.S9S_MB_2U(SCH_1):M_G_CPU1_SB_CA<3>
   78  M_G_CPU1_SB_CA<2>  CA2_B  @S9S_MB_2U_LIB.S9S_MB_2U(SCH_1):M_G_CPU1_SB_CA<2>
  221  M_G_CPU1_SB_CA<1>  CA1_B  @S9S_MB_2U_LIB.S9S_MB_2U(SCH_1):M_G_CPU1_SB_CA<1>
   76  M_G_CPU1_SB_CA<0>  CA0_B  @S9S_MB_2U_LIB.S9S_MB_2U(SCH_1):M_G_CPU1_SB_CA<0>
   86  M_G_CPU1_SA_RSP<0>  LBD||RSP_N_A  @S9S_MB_2U_LIB.S9S_MB_2U(SCH_1):M_G_CPU1_SA_RSP<0>
   74  M_G_CPU1_SA_PAR  PAR_A  @S9S_MB_2U_LIB.S9S_MB_2U(SCH_1):M_G_CPU1_SA_PAR
   20  M_G_CPU1_SA_DQ<9>  DQ_A9  @S9S_MB_2U_LIB.S9S_MB_2U(SCH_1):M_G_CPU1_SA_DQ<9>
   18  M_G_CPU1_SA_DQ<8>  DQ_A8  @S9S_MB_2U_LIB.S9S_MB_2U(SCH_1):M_G_CPU1_SA_DQ<8>
  161  M_G_CPU1_SA_DQ<7>  DQ_A7  @S9S_MB_2U_LIB.S9S_MB_2U(SCH_1):M_G_CPU1_SA_DQ<7>
  159  M_G_CPU1_SA_DQ<6>  DQ_A6  @S9S_MB_2U_LIB.S9S_MB_2U(SCH_1):M_G_CPU1_SA_DQ<6>
   16  M_G_CPU1_SA_DQ<5>  DQ_A5  @S9S_MB_2U_LIB.S9S_MB_2U(SCH_1):M_G_CPU1_SA_DQ<5>
   14  M_G_CPU1_SA_DQ<4>  DQ_A4  @S9S_MB_2U_LIB.S9S_MB_2U(SCH_1):M_G_CPU1_SA_DQ<4>
  154  M_G_CPU1_SA_DQ<3>  DQ_A3  @S9S_MB_2U_LIB.S9S_MB_2U(SCH_1):M_G_CPU1_SA_DQ<3>
  194  M_G_CPU1_SA_DQ<31>  DQ_A31  @S9S_MB_2U_LIB.S9S_MB_2U(SCH_1):M_G_CPU1_SA_DQ<31>
  192  M_G_CPU1_SA_DQ<30>  DQ_A30  @S9S_MB_2U_LIB.S9S_MB_2U(SCH_1):M_G_CPU1_SA_DQ<30>
  152  M_G_CPU1_SA_DQ<2>  DQ_A2  @S9S_MB_2U_LIB.S9S_MB_2U(SCH_1):M_G_CPU1_SA_DQ<2>
   49  M_G_CPU1_SA_DQ<29>  DQ_A29  @S9S_MB_2U_LIB.S9S_MB_2U(SCH_1):M_G_CPU1_SA_DQ<29>
   47  M_G_CPU1_SA_DQ<28>  DQ_A28  @S9S_MB_2U_LIB.S9S_MB_2U(SCH_1):M_G_CPU1_SA_DQ<28>
  187  M_G_CPU1_SA_DQ<27>  DQ_A27  @S9S_MB_2U_LIB.S9S_MB_2U(SCH_1):M_G_CPU1_SA_DQ<27>
  185  M_G_CPU1_SA_DQ<26>  DQ_A26  @S9S_MB_2U_LIB.S9S_MB_2U(SCH_1):M_G_CPU1_SA_DQ<26>
   42  M_G_CPU1_SA_DQ<25>  DQ_A25  @S9S_MB_2U_LIB.S9S_MB_2U(SCH_1):M_G_CPU1_SA_DQ<25>
   40  M_G_CPU1_SA_DQ<24>  DQ_A24  @S9S_MB_2U_LIB.S9S_MB_2U(SCH_1):M_G_CPU1_SA_DQ<24>
  183  M_G_CPU1_SA_DQ<23>  DQ_A23  @S9S_MB_2U_LIB.S9S_MB_2U(SCH_1):M_G_CPU1_SA_DQ<23>
  181  M_G_CPU1_SA_DQ<22>  DQ_A22  @S9S_MB_2U_LIB.S9S_MB_2U(SCH_1):M_G_CPU1_SA_DQ<22>
   38  M_G_CPU1_SA_DQ<21>  DQ_A21  @S9S_MB_2U_LIB.S9S_MB_2U(SCH_1):M_G_CPU1_SA_DQ<21>
   36  M_G_CPU1_SA_DQ<20>  DQ_A20  @S9S_MB_2U_LIB.S9S_MB_2U(SCH_1):M_G_CPU1_SA_DQ<20>
    9  M_G_CPU1_SA_DQ<1>  DQ_A1  @S9S_MB_2U_LIB.S9S_MB_2U(SCH_1):M_G_CPU1_SA_DQ<1>
  176  M_G_CPU1_SA_DQ<19>  DQ_A19  @S9S_MB_2U_LIB.S9S_MB_2U(SCH_1):M_G_CPU1_SA_DQ<19>
  174  M_G_CPU1_SA_DQ<18>  DQ_A18  @S9S_MB_2U_LIB.S9S_MB_2U(SCH_1):M_G_CPU1_SA_DQ<18>
   31  M_G_CPU1_SA_DQ<17>  DQ_A17  @S9S_MB_2U_LIB.S9S_MB_2U(SCH_1):M_G_CPU1_SA_DQ<17>
   29  M_G_CPU1_SA_DQ<16>  DQ_A16  @S9S_MB_2U_LIB.S9S_MB_2U(SCH_1):M_G_CPU1_SA_DQ<16>
  172  M_G_CPU1_SA_DQ<15>  DQ_A15  @S9S_MB_2U_LIB.S9S_MB_2U(SCH_1):M_G_CPU1_SA_DQ<15>
  170  M_G_CPU1_SA_DQ<14>  DQ_A14  @S9S_MB_2U_LIB.S9S_MB_2U(SCH_1):M_G_CPU1_SA_DQ<14>
   27  M_G_CPU1_SA_DQ<13>  DQ_A13  @S9S_MB_2U_LIB.S9S_MB_2U(SCH_1):M_G_CPU1_SA_DQ<13>
   25  M_G_CPU1_SA_DQ<12>  DQ_A12  @S9S_MB_2U_LIB.S9S_MB_2U(SCH_1):M_G_CPU1_SA_DQ<12>
  165  M_G_CPU1_SA_DQ<11>  DQ_A11  @S9S_MB_2U_LIB.S9S_MB_2U(SCH_1):M_G_CPU1_SA_DQ<11>
  163  M_G_CPU1_SA_DQ<10>  DQ_A10  @S9S_MB_2U_LIB.S9S_MB_2U(SCH_1):M_G_CPU1_SA_DQ<10>
    7  M_G_CPU1_SA_DQ<0>  DQ_A0  @S9S_MB_2U_LIB.S9S_MB_2U(SCH_1):M_G_CPU1_SA_DQ<0>
  209  M_G_CPU1_SA_CS_N<1>  CS1_N_A  @S9S_MB_2U_LIB.S9S_MB_2U(SCH_1):M_G_CPU1_SA_CS_N<1>
   64  M_G_CPU1_SA_CS_N<0>  CS0_N_A  @S9S_MB_2U_LIB.S9S_MB_2U(SCH_1):M_G_CPU1_SA_CS_N<0>
  205  M_G_CPU1_SA_CB<7>  CB_A7  @S9S_MB_2U_LIB.S9S_MB_2U(SCH_1):M_G_CPU1_SA_CB<7>
  203  M_G_CPU1_SA_CB<6>  CB_A6  @S9S_MB_2U_LIB.S9S_MB_2U(SCH_1):M_G_CPU1_SA_CB<6>
   60  M_G_CPU1_SA_CB<5>  CB_A5  @S9S_MB_2U_LIB.S9S_MB_2U(SCH_1):M_G_CPU1_SA_CB<5>
   58  M_G_CPU1_SA_CB<4>  CB_A4  @S9S_MB_2U_LIB.S9S_MB_2U(SCH_1):M_G_CPU1_SA_CB<4>
  198  M_G_CPU1_SA_CB<3>  CB_A3  @S9S_MB_2U_LIB.S9S_MB_2U(SCH_1):M_G_CPU1_SA_CB<3>
  196  M_G_CPU1_SA_CB<2>  CB_A2  @S9S_MB_2U_LIB.S9S_MB_2U(SCH_1):M_G_CPU1_SA_CB<2>
   53  M_G_CPU1_SA_CB<1>  CB_A1  @S9S_MB_2U_LIB.S9S_MB_2U(SCH_1):M_G_CPU1_SA_CB<1>
   51  M_G_CPU1_SA_CB<0>  CB_A0  @S9S_MB_2U_LIB.S9S_MB_2U(SCH_1):M_G_CPU1_SA_CB<0>
   72  M_G_CPU1_SA_CA<6>  CA6_A  @S9S_MB_2U_LIB.S9S_MB_2U(SCH_1):M_G_CPU1_SA_CA<6>
  215  M_G_CPU1_SA_CA<5>  CA5_A  @S9S_MB_2U_LIB.S9S_MB_2U(SCH_1):M_G_CPU1_SA_CA<5>
   70  M_G_CPU1_SA_CA<4>  CA4_A  @S9S_MB_2U_LIB.S9S_MB_2U(SCH_1):M_G_CPU1_SA_CA<4>
  213  M_G_CPU1_SA_CA<3>  CA3_A  @S9S_MB_2U_LIB.S9S_MB_2U(SCH_1):M_G_CPU1_SA_CA<3>
   68  M_G_CPU1_SA_CA<2>  CA2_A  @S9S_MB_2U_LIB.S9S_MB_2U(SCH_1):M_G_CPU1_SA_CA<2>
  211  M_G_CPU1_SA_CA<1>  CA1_A  @S9S_MB_2U_LIB.S9S_MB_2U(SCH_1):M_G_CPU1_SA_CA<1>
   66  M_G_CPU1_SA_CA<0>  CA0_A  @S9S_MB_2U_LIB.S9S_MB_2U(SCH_1):M_G_CPU1_SA_CA<0>
  217  M_G_CPU1_CLK_DP<0>   CK_P  @S9S_MB_2U_LIB.S9S_MB_2U(SCH_1):M_G_CPU1_CLK_DP<0>
  218  M_G_CPU1_CLK_DN<0>   CK_N  @S9S_MB_2U_LIB.S9S_MB_2U(SCH_1):M_G_CPU1_CLK_DN<0>
   62  M_G_CPU1_ALERT_N  ALERT_N  @S9S_MB_2U_LIB.S9S_MB_2U(SCH_1):M_G_CPU1_ALERT_N
    5  I3C_SPD_DDREFGH_CPU1_LVC1_SDA   HSDA  @S9S_MB_2U_LIB.S9S_MB_2U(SCH_1):I3C_SPD_DDREFGH_CPU1_LVC1_SDA
    4  I3C_SPD_DDREFGH_CPU1_LVC1_SCL   HSCL  @S9S_MB_2U_LIB.S9S_MB_2U(SCH_1):I3C_SPD_DDREFGH_CPU1_LVC1_SCL

SCONN288_ADR50001P003C01  I178  J30    [SCONN288_ADR50001P003C01-SCONNA]
  146  P12V_S3_AUX_CPU1_NVDIMM  VIN_BULK2  @S9S_MB_2U_LIB.S9S_MB_2U(SCH_1):P12V_S3_AUX_CPU1_NVDIMM
  145  P12V_S3_AUX_CPU1_NVDIMM  VIN_BULK1  @S9S_MB_2U_LIB.S9S_MB_2U(SCH_1):P12V_S3_AUX_CPU1_NVDIMM
    1  P12V_S3_AUX_CPU1_NVDIMM  VIN_BULK0  @S9S_MB_2U_LIB.S9S_MB_2U(SCH_1):P12V_S3_AUX_CPU1_NVDIMM
  288  GND            VSS126  @S9S_MB_2U_LIB.S9S_MB_2U(SCH_1):GND
  286  GND            VSS125  @S9S_MB_2U_LIB.S9S_MB_2U(SCH_1):GND
  284  GND            VSS124  @S9S_MB_2U_LIB.S9S_MB_2U(SCH_1):GND
  281  GND            VSS123  @S9S_MB_2U_LIB.S9S_MB_2U(SCH_1):GND
  279  GND            VSS122  @S9S_MB_2U_LIB.S9S_MB_2U(SCH_1):GND
  277  GND            VSS121  @S9S_MB_2U_LIB.S9S_MB_2U(SCH_1):GND
  275  GND            VSS120  @S9S_MB_2U_LIB.S9S_MB_2U(SCH_1):GND
  273  GND            VSS119  @S9S_MB_2U_LIB.S9S_MB_2U(SCH_1):GND
  270  GND            VSS118  @S9S_MB_2U_LIB.S9S_MB_2U(SCH_1):GND
  268  GND            VSS117  @S9S_MB_2U_LIB.S9S_MB_2U(SCH_1):GND
  266  GND            VSS116  @S9S_MB_2U_LIB.S9S_MB_2U(SCH_1):GND
  264  GND            VSS115  @S9S_MB_2U_LIB.S9S_MB_2U(SCH_1):GND
  262  GND            VSS114  @S9S_MB_2U_LIB.S9S_MB_2U(SCH_1):GND
  259  GND            VSS113  @S9S_MB_2U_LIB.S9S_MB_2U(SCH_1):GND
  257  GND            VSS112  @S9S_MB_2U_LIB.S9S_MB_2U(SCH_1):GND
  255  GND            VSS111  @S9S_MB_2U_LIB.S9S_MB_2U(SCH_1):GND
  253  GND            VSS110  @S9S_MB_2U_LIB.S9S_MB_2U(SCH_1):GND
  251  GND            VSS109  @S9S_MB_2U_LIB.S9S_MB_2U(SCH_1):GND
  248  GND            VSS108  @S9S_MB_2U_LIB.S9S_MB_2U(SCH_1):GND
  246  GND            VSS107  @S9S_MB_2U_LIB.S9S_MB_2U(SCH_1):GND
  244  GND            VSS106  @S9S_MB_2U_LIB.S9S_MB_2U(SCH_1):GND
  242  GND            VSS105  @S9S_MB_2U_LIB.S9S_MB_2U(SCH_1):GND
  240  GND            VSS104  @S9S_MB_2U_LIB.S9S_MB_2U(SCH_1):GND
  237  GND            VSS103  @S9S_MB_2U_LIB.S9S_MB_2U(SCH_1):GND
  235  GND            VSS102  @S9S_MB_2U_LIB.S9S_MB_2U(SCH_1):GND
  233  GND            VSS101  @S9S_MB_2U_LIB.S9S_MB_2U(SCH_1):GND
  230  GND            VSS100  @S9S_MB_2U_LIB.S9S_MB_2U(SCH_1):GND
  228  GND            VSS99  @S9S_MB_2U_LIB.S9S_MB_2U(SCH_1):GND
  226  GND            VSS98  @S9S_MB_2U_LIB.S9S_MB_2U(SCH_1):GND
  224  GND            VSS97  @S9S_MB_2U_LIB.S9S_MB_2U(SCH_1):GND
  222  GND            VSS96  @S9S_MB_2U_LIB.S9S_MB_2U(SCH_1):GND
  219  GND            VSS95  @S9S_MB_2U_LIB.S9S_MB_2U(SCH_1):GND
  216  GND            VSS94  @S9S_MB_2U_LIB.S9S_MB_2U(SCH_1):GND
  214  GND            VSS93  @S9S_MB_2U_LIB.S9S_MB_2U(SCH_1):GND
  212  GND            VSS92  @S9S_MB_2U_LIB.S9S_MB_2U(SCH_1):GND
  210  GND            VSS91  @S9S_MB_2U_LIB.S9S_MB_2U(SCH_1):GND
  208  GND            VSS90  @S9S_MB_2U_LIB.S9S_MB_2U(SCH_1):GND
  206  GND            VSS89  @S9S_MB_2U_LIB.S9S_MB_2U(SCH_1):GND
  204  GND            VSS88  @S9S_MB_2U_LIB.S9S_MB_2U(SCH_1):GND
  202  GND            VSS87  @S9S_MB_2U_LIB.S9S_MB_2U(SCH_1):GND
  199  GND            VSS86  @S9S_MB_2U_LIB.S9S_MB_2U(SCH_1):GND
  197  GND            VSS85  @S9S_MB_2U_LIB.S9S_MB_2U(SCH_1):GND
  195  GND            VSS84  @S9S_MB_2U_LIB.S9S_MB_2U(SCH_1):GND
  193  GND            VSS83  @S9S_MB_2U_LIB.S9S_MB_2U(SCH_1):GND
  191  GND            VSS82  @S9S_MB_2U_LIB.S9S_MB_2U(SCH_1):GND
  188  GND            VSS81  @S9S_MB_2U_LIB.S9S_MB_2U(SCH_1):GND
  186  GND            VSS80  @S9S_MB_2U_LIB.S9S_MB_2U(SCH_1):GND
  184  GND            VSS79  @S9S_MB_2U_LIB.S9S_MB_2U(SCH_1):GND
  182  GND            VSS78  @S9S_MB_2U_LIB.S9S_MB_2U(SCH_1):GND
  180  GND            VSS77  @S9S_MB_2U_LIB.S9S_MB_2U(SCH_1):GND
  177  GND            VSS76  @S9S_MB_2U_LIB.S9S_MB_2U(SCH_1):GND
  175  GND            VSS75  @S9S_MB_2U_LIB.S9S_MB_2U(SCH_1):GND
  173  GND            VSS74  @S9S_MB_2U_LIB.S9S_MB_2U(SCH_1):GND
  171  GND            VSS73  @S9S_MB_2U_LIB.S9S_MB_2U(SCH_1):GND
  169  GND            VSS72  @S9S_MB_2U_LIB.S9S_MB_2U(SCH_1):GND
  166  GND            VSS71  @S9S_MB_2U_LIB.S9S_MB_2U(SCH_1):GND
  164  GND            VSS70  @S9S_MB_2U_LIB.S9S_MB_2U(SCH_1):GND
  162  GND            VSS69  @S9S_MB_2U_LIB.S9S_MB_2U(SCH_1):GND
  160  GND            VSS68  @S9S_MB_2U_LIB.S9S_MB_2U(SCH_1):GND
  158  GND            VSS67  @S9S_MB_2U_LIB.S9S_MB_2U(SCH_1):GND
  155  GND            VSS66  @S9S_MB_2U_LIB.S9S_MB_2U(SCH_1):GND
  153  GND            VSS65  @S9S_MB_2U_LIB.S9S_MB_2U(SCH_1):GND
  151  GND            VSS64  @S9S_MB_2U_LIB.S9S_MB_2U(SCH_1):GND
  143  GND            VSS63  @S9S_MB_2U_LIB.S9S_MB_2U(SCH_1):GND
  141  GND            VSS62  @S9S_MB_2U_LIB.S9S_MB_2U(SCH_1):GND
  139  GND            VSS61  @S9S_MB_2U_LIB.S9S_MB_2U(SCH_1):GND
  136  GND            VSS60  @S9S_MB_2U_LIB.S9S_MB_2U(SCH_1):GND
  134  GND            VSS59  @S9S_MB_2U_LIB.S9S_MB_2U(SCH_1):GND
  132  GND            VSS58  @S9S_MB_2U_LIB.S9S_MB_2U(SCH_1):GND
  130  GND            VSS57  @S9S_MB_2U_LIB.S9S_MB_2U(SCH_1):GND
  128  GND            VSS56  @S9S_MB_2U_LIB.S9S_MB_2U(SCH_1):GND
  125  GND            VSS55  @S9S_MB_2U_LIB.S9S_MB_2U(SCH_1):GND
  123  GND            VSS54  @S9S_MB_2U_LIB.S9S_MB_2U(SCH_1):GND
  121  GND            VSS53  @S9S_MB_2U_LIB.S9S_MB_2U(SCH_1):GND
  119  GND            VSS52  @S9S_MB_2U_LIB.S9S_MB_2U(SCH_1):GND
  117  GND            VSS51  @S9S_MB_2U_LIB.S9S_MB_2U(SCH_1):GND
  114  GND            VSS50  @S9S_MB_2U_LIB.S9S_MB_2U(SCH_1):GND
  112  GND            VSS49  @S9S_MB_2U_LIB.S9S_MB_2U(SCH_1):GND
  110  GND            VSS48  @S9S_MB_2U_LIB.S9S_MB_2U(SCH_1):GND
  108  GND            VSS47  @S9S_MB_2U_LIB.S9S_MB_2U(SCH_1):GND
  106  GND            VSS46  @S9S_MB_2U_LIB.S9S_MB_2U(SCH_1):GND
  103  GND            VSS45  @S9S_MB_2U_LIB.S9S_MB_2U(SCH_1):GND
  101  GND            VSS44  @S9S_MB_2U_LIB.S9S_MB_2U(SCH_1):GND
   99  GND            VSS43  @S9S_MB_2U_LIB.S9S_MB_2U(SCH_1):GND
   97  GND            VSS42  @S9S_MB_2U_LIB.S9S_MB_2U(SCH_1):GND
   95  GND            VSS41  @S9S_MB_2U_LIB.S9S_MB_2U(SCH_1):GND
   92  GND            VSS40  @S9S_MB_2U_LIB.S9S_MB_2U(SCH_1):GND
   90  GND            VSS39  @S9S_MB_2U_LIB.S9S_MB_2U(SCH_1):GND
   88  GND            VSS38  @S9S_MB_2U_LIB.S9S_MB_2U(SCH_1):GND
   85  GND            VSS37  @S9S_MB_2U_LIB.S9S_MB_2U(SCH_1):GND
   83  GND            VSS36  @S9S_MB_2U_LIB.S9S_MB_2U(SCH_1):GND
   81  GND            VSS35  @S9S_MB_2U_LIB.S9S_MB_2U(SCH_1):GND
   79  GND            VSS34  @S9S_MB_2U_LIB.S9S_MB_2U(SCH_1):GND
   77  GND            VSS33  @S9S_MB_2U_LIB.S9S_MB_2U(SCH_1):GND
   75  GND            VSS32  @S9S_MB_2U_LIB.S9S_MB_2U(SCH_1):GND
   73  GND            VSS31  @S9S_MB_2U_LIB.S9S_MB_2U(SCH_1):GND
   71  GND            VSS30  @S9S_MB_2U_LIB.S9S_MB_2U(SCH_1):GND
   69  GND            VSS29  @S9S_MB_2U_LIB.S9S_MB_2U(SCH_1):GND
   67  GND            VSS28  @S9S_MB_2U_LIB.S9S_MB_2U(SCH_1):GND
   65  GND            VSS27  @S9S_MB_2U_LIB.S9S_MB_2U(SCH_1):GND
   63  GND            VSS26  @S9S_MB_2U_LIB.S9S_MB_2U(SCH_1):GND
   61  GND            VSS25  @S9S_MB_2U_LIB.S9S_MB_2U(SCH_1):GND
   59  GND            VSS24  @S9S_MB_2U_LIB.S9S_MB_2U(SCH_1):GND
   57  GND            VSS23  @S9S_MB_2U_LIB.S9S_MB_2U(SCH_1):GND
   54  GND            VSS22  @S9S_MB_2U_LIB.S9S_MB_2U(SCH_1):GND
   52  GND            VSS21  @S9S_MB_2U_LIB.S9S_MB_2U(SCH_1):GND
   50  GND            VSS20  @S9S_MB_2U_LIB.S9S_MB_2U(SCH_1):GND
   48  GND            VSS19  @S9S_MB_2U_LIB.S9S_MB_2U(SCH_1):GND
   46  GND            VSS18  @S9S_MB_2U_LIB.S9S_MB_2U(SCH_1):GND
   43  GND            VSS17  @S9S_MB_2U_LIB.S9S_MB_2U(SCH_1):GND
   41  GND            VSS16  @S9S_MB_2U_LIB.S9S_MB_2U(SCH_1):GND
   39  GND            VSS15  @S9S_MB_2U_LIB.S9S_MB_2U(SCH_1):GND
   37  GND            VSS14  @S9S_MB_2U_LIB.S9S_MB_2U(SCH_1):GND
   35  GND            VSS13  @S9S_MB_2U_LIB.S9S_MB_2U(SCH_1):GND
   32  GND            VSS12  @S9S_MB_2U_LIB.S9S_MB_2U(SCH_1):GND
   30  GND            VSS11  @S9S_MB_2U_LIB.S9S_MB_2U(SCH_1):GND
   28  GND            VSS10  @S9S_MB_2U_LIB.S9S_MB_2U(SCH_1):GND
   26  GND             VSS9  @S9S_MB_2U_LIB.S9S_MB_2U(SCH_1):GND
   24  GND             VSS8  @S9S_MB_2U_LIB.S9S_MB_2U(SCH_1):GND
   21  GND             VSS7  @S9S_MB_2U_LIB.S9S_MB_2U(SCH_1):GND
   19  GND             VSS6  @S9S_MB_2U_LIB.S9S_MB_2U(SCH_1):GND
   17  GND             VSS5  @S9S_MB_2U_LIB.S9S_MB_2U(SCH_1):GND
   15  GND             VSS4  @S9S_MB_2U_LIB.S9S_MB_2U(SCH_1):GND
   13  GND             VSS3  @S9S_MB_2U_LIB.S9S_MB_2U(SCH_1):GND
   10  GND             VSS2  @S9S_MB_2U_LIB.S9S_MB_2U(SCH_1):GND
    8  GND             VSS1  @S9S_MB_2U_LIB.S9S_MB_2U(SCH_1):GND
    6  GND             VSS0  @S9S_MB_2U_LIB.S9S_MB_2U(SCH_1):GND
   G3  GND               G3  @S9S_MB_2U_LIB.S9S_MB_2U(SCH_1):GND
   G2  GND               G2  @S9S_MB_2U_LIB.S9S_MB_2U(SCH_1):GND
   G1  GND               G1  @S9S_MB_2U_LIB.S9S_MB_2U(SCH_1):GND

SCONN288_ADR50001P003C01  I177  J30    [SCONN288_ADR50001P003C01-SCONNA]
   93  M_G_CPU1_SB_DQS_DP<9>  DQS9_B_P  @S9S_MB_2U_LIB.S9S_MB_2U(SCH_1):M_G_CPU1_SB_DQS_DP<9>
  283  M_G_CPU1_SB_DQS_DP<8>  DQS8_B_P  @S9S_MB_2U_LIB.S9S_MB_2U(SCH_1):M_G_CPU1_SB_DQS_DP<8>
  272  M_G_CPU1_SB_DQS_DP<7>  DQS7_B_P  @S9S_MB_2U_LIB.S9S_MB_2U(SCH_1):M_G_CPU1_SB_DQS_DP<7>
  261  M_G_CPU1_SB_DQS_DP<6>  DQS6_B_P  @S9S_MB_2U_LIB.S9S_MB_2U(SCH_1):M_G_CPU1_SB_DQS_DP<6>
  250  M_G_CPU1_SB_DQS_DP<5>  DQS5_B_P  @S9S_MB_2U_LIB.S9S_MB_2U(SCH_1):M_G_CPU1_SB_DQS_DP<5>
  239  M_G_CPU1_SB_DQS_DP<4>  DQS4_B_P  @S9S_MB_2U_LIB.S9S_MB_2U(SCH_1):M_G_CPU1_SB_DQS_DP<4>
  137  M_G_CPU1_SB_DQS_DP<3>  DQS3_B_P  @S9S_MB_2U_LIB.S9S_MB_2U(SCH_1):M_G_CPU1_SB_DQS_DP<3>
  126  M_G_CPU1_SB_DQS_DP<2>  DQS2_B_P  @S9S_MB_2U_LIB.S9S_MB_2U(SCH_1):M_G_CPU1_SB_DQS_DP<2>
  115  M_G_CPU1_SB_DQS_DP<1>  DQS1_B_P  @S9S_MB_2U_LIB.S9S_MB_2U(SCH_1):M_G_CPU1_SB_DQS_DP<1>
  104  M_G_CPU1_SB_DQS_DP<0>  DQS0_B_P  @S9S_MB_2U_LIB.S9S_MB_2U(SCH_1):M_G_CPU1_SB_DQS_DP<0>
   94  M_G_CPU1_SB_DQS_DN<9>  DQS9_B_N  @S9S_MB_2U_LIB.S9S_MB_2U(SCH_1):M_G_CPU1_SB_DQS_DN<9>
  282  M_G_CPU1_SB_DQS_DN<8>  DQS8_B_N  @S9S_MB_2U_LIB.S9S_MB_2U(SCH_1):M_G_CPU1_SB_DQS_DN<8>
  271  M_G_CPU1_SB_DQS_DN<7>  DQS7_B_N  @S9S_MB_2U_LIB.S9S_MB_2U(SCH_1):M_G_CPU1_SB_DQS_DN<7>
  260  M_G_CPU1_SB_DQS_DN<6>  DQS6_B_N  @S9S_MB_2U_LIB.S9S_MB_2U(SCH_1):M_G_CPU1_SB_DQS_DN<6>
  249  M_G_CPU1_SB_DQS_DN<5>  DQS5_B_N  @S9S_MB_2U_LIB.S9S_MB_2U(SCH_1):M_G_CPU1_SB_DQS_DN<5>
  238  M_G_CPU1_SB_DQS_DN<4>  DQS4_B_N  @S9S_MB_2U_LIB.S9S_MB_2U(SCH_1):M_G_CPU1_SB_DQS_DN<4>
  138  M_G_CPU1_SB_DQS_DN<3>  DQS3_B_N  @S9S_MB_2U_LIB.S9S_MB_2U(SCH_1):M_G_CPU1_SB_DQS_DN<3>
  127  M_G_CPU1_SB_DQS_DN<2>  DQS2_B_N  @S9S_MB_2U_LIB.S9S_MB_2U(SCH_1):M_G_CPU1_SB_DQS_DN<2>
  116  M_G_CPU1_SB_DQS_DN<1>  DQS1_B_N  @S9S_MB_2U_LIB.S9S_MB_2U(SCH_1):M_G_CPU1_SB_DQS_DN<1>
  105  M_G_CPU1_SB_DQS_DN<0>  DQS0_B_N  @S9S_MB_2U_LIB.S9S_MB_2U(SCH_1):M_G_CPU1_SB_DQS_DN<0>
  201  M_G_CPU1_SA_DQS_DP<9>  DQS9_A_P  @S9S_MB_2U_LIB.S9S_MB_2U(SCH_1):M_G_CPU1_SA_DQS_DP<9>
  190  M_G_CPU1_SA_DQS_DP<8>  DQS8_A_P  @S9S_MB_2U_LIB.S9S_MB_2U(SCH_1):M_G_CPU1_SA_DQS_DP<8>
  179  M_G_CPU1_SA_DQS_DP<7>  DQS7_A_P  @S9S_MB_2U_LIB.S9S_MB_2U(SCH_1):M_G_CPU1_SA_DQS_DP<7>
  168  M_G_CPU1_SA_DQS_DP<6>  DQS6_A_P  @S9S_MB_2U_LIB.S9S_MB_2U(SCH_1):M_G_CPU1_SA_DQS_DP<6>
  157  M_G_CPU1_SA_DQS_DP<5>  DQS5_A_P  @S9S_MB_2U_LIB.S9S_MB_2U(SCH_1):M_G_CPU1_SA_DQS_DP<5>
   55  M_G_CPU1_SA_DQS_DP<4>  DQS4_A_P  @S9S_MB_2U_LIB.S9S_MB_2U(SCH_1):M_G_CPU1_SA_DQS_DP<4>
   44  M_G_CPU1_SA_DQS_DP<3>  DQS3_A_P  @S9S_MB_2U_LIB.S9S_MB_2U(SCH_1):M_G_CPU1_SA_DQS_DP<3>
   33  M_G_CPU1_SA_DQS_DP<2>  DQS2_A_P  @S9S_MB_2U_LIB.S9S_MB_2U(SCH_1):M_G_CPU1_SA_DQS_DP<2>
   22  M_G_CPU1_SA_DQS_DP<1>  DQS1_A_P  @S9S_MB_2U_LIB.S9S_MB_2U(SCH_1):M_G_CPU1_SA_DQS_DP<1>
   11  M_G_CPU1_SA_DQS_DP<0>  DQS0_A_P  @S9S_MB_2U_LIB.S9S_MB_2U(SCH_1):M_G_CPU1_SA_DQS_DP<0>
  200  M_G_CPU1_SA_DQS_DN<9>  DQS9_A_N  @S9S_MB_2U_LIB.S9S_MB_2U(SCH_1):M_G_CPU1_SA_DQS_DN<9>
  189  M_G_CPU1_SA_DQS_DN<8>  DQS8_A_N  @S9S_MB_2U_LIB.S9S_MB_2U(SCH_1):M_G_CPU1_SA_DQS_DN<8>
  178  M_G_CPU1_SA_DQS_DN<7>  DQS7_A_N  @S9S_MB_2U_LIB.S9S_MB_2U(SCH_1):M_G_CPU1_SA_DQS_DN<7>
  167  M_G_CPU1_SA_DQS_DN<6>  DQS6_A_N  @S9S_MB_2U_LIB.S9S_MB_2U(SCH_1):M_G_CPU1_SA_DQS_DN<6>
  156  M_G_CPU1_SA_DQS_DN<5>  DQS5_A_N  @S9S_MB_2U_LIB.S9S_MB_2U(SCH_1):M_G_CPU1_SA_DQS_DN<5>
   56  M_G_CPU1_SA_DQS_DN<4>  DQS4_A_N  @S9S_MB_2U_LIB.S9S_MB_2U(SCH_1):M_G_CPU1_SA_DQS_DN<4>
   45  M_G_CPU1_SA_DQS_DN<3>  DQS3_A_N  @S9S_MB_2U_LIB.S9S_MB_2U(SCH_1):M_G_CPU1_SA_DQS_DN<3>
   34  M_G_CPU1_SA_DQS_DN<2>  DQS2_A_N  @S9S_MB_2U_LIB.S9S_MB_2U(SCH_1):M_G_CPU1_SA_DQS_DN<2>
   23  M_G_CPU1_SA_DQS_DN<1>  DQS1_A_N  @S9S_MB_2U_LIB.S9S_MB_2U(SCH_1):M_G_CPU1_SA_DQS_DN<1>
   12  M_G_CPU1_SA_DQS_DN<0>  DQS0_A_N  @S9S_MB_2U_LIB.S9S_MB_2U(SCH_1):M_G_CPU1_SA_DQS_DN<0>

SCONN288_ADR50001P003C01  I179  J30    [SCONN288_ADR50001P003C01-SCONNA]
  232  NC              RFU6  NC
  231  NC              RFU5  NC
  220  NC              RFU4  NC
  150  NC              RFU3  NC
  149  NC              RFU2  NC
  144  NC              RFU1  NC
    2  NC              RFU0  NC
  207  RST_M_GH_CPU1_FPGA_N  RESET_N  @S9S_MB_2U_LIB.S9S_MB_2U(SCH_1):RST_M_GH_CPU1_FPGA_N
  147  PWRGD_CHG_CPU1_DIMM2  PWR_GOOD||FAIL_N  @S9S_MB_2U_LIB.S9S_MB_2U(SCH_1):PWRGD_CHG_CPU1_DIMM2
  148  PD_CHG_CPU1_DIMM2_SAA    HAS  @S9S_MB_2U_LIB.S9S_MB_2U(SCH_1):PD_CHG_CPU1_DIMM2_SAA
    3  P3V3_AUX       VIN_MGMT  @S9S_MB_2U_LIB.S9S_MB_2U(SCH_1):P3V3_AUX
   87  M_G_CPU1_SB_RSP<1>  LBS||RSP_N_B  @S9S_MB_2U_LIB.S9S_MB_2U(SCH_1):M_G_CPU1_SB_RSP<1>
  227  M_G_CPU1_SB_PAR  PAR_B  @S9S_MB_2U_LIB.S9S_MB_2U(SCH_1):M_G_CPU1_SB_PAR
  113  M_G_CPU1_SB_DQ<9>  DQ_B9  @S9S_MB_2U_LIB.S9S_MB_2U(SCH_1):M_G_CPU1_SB_DQ<9>
  111  M_G_CPU1_SB_DQ<8>  DQ_B8  @S9S_MB_2U_LIB.S9S_MB_2U(SCH_1):M_G_CPU1_SB_DQ<8>
  254  M_G_CPU1_SB_DQ<7>  DQ_B7  @S9S_MB_2U_LIB.S9S_MB_2U(SCH_1):M_G_CPU1_SB_DQ<7>
  252  M_G_CPU1_SB_DQ<6>  DQ_B6  @S9S_MB_2U_LIB.S9S_MB_2U(SCH_1):M_G_CPU1_SB_DQ<6>
  109  M_G_CPU1_SB_DQ<5>  DQ_B5  @S9S_MB_2U_LIB.S9S_MB_2U(SCH_1):M_G_CPU1_SB_DQ<5>
  107  M_G_CPU1_SB_DQ<4>  DQ_B4  @S9S_MB_2U_LIB.S9S_MB_2U(SCH_1):M_G_CPU1_SB_DQ<4>
  247  M_G_CPU1_SB_DQ<3>  DQ_B3  @S9S_MB_2U_LIB.S9S_MB_2U(SCH_1):M_G_CPU1_SB_DQ<3>
  287  M_G_CPU1_SB_DQ<31>  DQ_B31  @S9S_MB_2U_LIB.S9S_MB_2U(SCH_1):M_G_CPU1_SB_DQ<31>
  285  M_G_CPU1_SB_DQ<30>  DQ_B30  @S9S_MB_2U_LIB.S9S_MB_2U(SCH_1):M_G_CPU1_SB_DQ<30>
  245  M_G_CPU1_SB_DQ<2>  DQ_B2  @S9S_MB_2U_LIB.S9S_MB_2U(SCH_1):M_G_CPU1_SB_DQ<2>
  142  M_G_CPU1_SB_DQ<29>  DQ_B29  @S9S_MB_2U_LIB.S9S_MB_2U(SCH_1):M_G_CPU1_SB_DQ<29>
  140  M_G_CPU1_SB_DQ<28>  DQ_B28  @S9S_MB_2U_LIB.S9S_MB_2U(SCH_1):M_G_CPU1_SB_DQ<28>
  280  M_G_CPU1_SB_DQ<27>  DQ_B27  @S9S_MB_2U_LIB.S9S_MB_2U(SCH_1):M_G_CPU1_SB_DQ<27>
  278  M_G_CPU1_SB_DQ<26>  DQ_B26  @S9S_MB_2U_LIB.S9S_MB_2U(SCH_1):M_G_CPU1_SB_DQ<26>
  135  M_G_CPU1_SB_DQ<25>  DQ_B25  @S9S_MB_2U_LIB.S9S_MB_2U(SCH_1):M_G_CPU1_SB_DQ<25>
  133  M_G_CPU1_SB_DQ<24>  DQ_B24  @S9S_MB_2U_LIB.S9S_MB_2U(SCH_1):M_G_CPU1_SB_DQ<24>
  276  M_G_CPU1_SB_DQ<23>  DQ_B23  @S9S_MB_2U_LIB.S9S_MB_2U(SCH_1):M_G_CPU1_SB_DQ<23>
  274  M_G_CPU1_SB_DQ<22>  DQ_B22  @S9S_MB_2U_LIB.S9S_MB_2U(SCH_1):M_G_CPU1_SB_DQ<22>
  131  M_G_CPU1_SB_DQ<21>  DQ_B21  @S9S_MB_2U_LIB.S9S_MB_2U(SCH_1):M_G_CPU1_SB_DQ<21>
  129  M_G_CPU1_SB_DQ<20>  DQ_B20  @S9S_MB_2U_LIB.S9S_MB_2U(SCH_1):M_G_CPU1_SB_DQ<20>
  102  M_G_CPU1_SB_DQ<1>  DQ_B1  @S9S_MB_2U_LIB.S9S_MB_2U(SCH_1):M_G_CPU1_SB_DQ<1>
  269  M_G_CPU1_SB_DQ<19>  DQ_B19  @S9S_MB_2U_LIB.S9S_MB_2U(SCH_1):M_G_CPU1_SB_DQ<19>
  267  M_G_CPU1_SB_DQ<18>  DQ_B18  @S9S_MB_2U_LIB.S9S_MB_2U(SCH_1):M_G_CPU1_SB_DQ<18>
  124  M_G_CPU1_SB_DQ<17>  DQ_B17  @S9S_MB_2U_LIB.S9S_MB_2U(SCH_1):M_G_CPU1_SB_DQ<17>
  122  M_G_CPU1_SB_DQ<16>  DQ_B16  @S9S_MB_2U_LIB.S9S_MB_2U(SCH_1):M_G_CPU1_SB_DQ<16>
  265  M_G_CPU1_SB_DQ<15>  DQ_B15  @S9S_MB_2U_LIB.S9S_MB_2U(SCH_1):M_G_CPU1_SB_DQ<15>
  263  M_G_CPU1_SB_DQ<14>  DQ_B14  @S9S_MB_2U_LIB.S9S_MB_2U(SCH_1):M_G_CPU1_SB_DQ<14>
  120  M_G_CPU1_SB_DQ<13>  DQ_B13  @S9S_MB_2U_LIB.S9S_MB_2U(SCH_1):M_G_CPU1_SB_DQ<13>
  118  M_G_CPU1_SB_DQ<12>  DQ_B12  @S9S_MB_2U_LIB.S9S_MB_2U(SCH_1):M_G_CPU1_SB_DQ<12>
  258  M_G_CPU1_SB_DQ<11>  DQ_B11  @S9S_MB_2U_LIB.S9S_MB_2U(SCH_1):M_G_CPU1_SB_DQ<11>
  256  M_G_CPU1_SB_DQ<10>  DQ_B10  @S9S_MB_2U_LIB.S9S_MB_2U(SCH_1):M_G_CPU1_SB_DQ<10>
  100  M_G_CPU1_SB_DQ<0>  DQ_B0  @S9S_MB_2U_LIB.S9S_MB_2U(SCH_1):M_G_CPU1_SB_DQ<0>
  229  M_G_CPU1_SB_CS_N<3>  CS1_N_B  @S9S_MB_2U_LIB.S9S_MB_2U(SCH_1):M_G_CPU1_SB_CS_N<3>
   84  M_G_CPU1_SB_CS_N<2>  CS0_N_B  @S9S_MB_2U_LIB.S9S_MB_2U(SCH_1):M_G_CPU1_SB_CS_N<2>
  236  M_G_CPU1_SB_CB<7>  CB_B7  @S9S_MB_2U_LIB.S9S_MB_2U(SCH_1):M_G_CPU1_SB_CB<7>
  234  M_G_CPU1_SB_CB<6>  CB_B6  @S9S_MB_2U_LIB.S9S_MB_2U(SCH_1):M_G_CPU1_SB_CB<6>
   91  M_G_CPU1_SB_CB<5>  CB_B5  @S9S_MB_2U_LIB.S9S_MB_2U(SCH_1):M_G_CPU1_SB_CB<5>
   89  M_G_CPU1_SB_CB<4>  CB_B4  @S9S_MB_2U_LIB.S9S_MB_2U(SCH_1):M_G_CPU1_SB_CB<4>
  243  M_G_CPU1_SB_CB<3>  CB_B3  @S9S_MB_2U_LIB.S9S_MB_2U(SCH_1):M_G_CPU1_SB_CB<3>
  241  M_G_CPU1_SB_CB<2>  CB_B2  @S9S_MB_2U_LIB.S9S_MB_2U(SCH_1):M_G_CPU1_SB_CB<2>
   98  M_G_CPU1_SB_CB<1>  CB_B1  @S9S_MB_2U_LIB.S9S_MB_2U(SCH_1):M_G_CPU1_SB_CB<1>
   96  M_G_CPU1_SB_CB<0>  CB_B0  @S9S_MB_2U_LIB.S9S_MB_2U(SCH_1):M_G_CPU1_SB_CB<0>
   82  M_G_CPU1_SB_CA<6>  CA6_B  @S9S_MB_2U_LIB.S9S_MB_2U(SCH_1):M_G_CPU1_SB_CA<6>
  225  M_G_CPU1_SB_CA<5>  CA5_B  @S9S_MB_2U_LIB.S9S_MB_2U(SCH_1):M_G_CPU1_SB_CA<5>
   80  M_G_CPU1_SB_CA<4>  CA4_B  @S9S_MB_2U_LIB.S9S_MB_2U(SCH_1):M_G_CPU1_SB_CA<4>
  223  M_G_CPU1_SB_CA<3>  CA3_B  @S9S_MB_2U_LIB.S9S_MB_2U(SCH_1):M_G_CPU1_SB_CA<3>
   78  M_G_CPU1_SB_CA<2>  CA2_B  @S9S_MB_2U_LIB.S9S_MB_2U(SCH_1):M_G_CPU1_SB_CA<2>
  221  M_G_CPU1_SB_CA<1>  CA1_B  @S9S_MB_2U_LIB.S9S_MB_2U(SCH_1):M_G_CPU1_SB_CA<1>
   76  M_G_CPU1_SB_CA<0>  CA0_B  @S9S_MB_2U_LIB.S9S_MB_2U(SCH_1):M_G_CPU1_SB_CA<0>
   86  M_G_CPU1_SA_RSP<1>  LBD||RSP_N_A  @S9S_MB_2U_LIB.S9S_MB_2U(SCH_1):M_G_CPU1_SA_RSP<1>
   74  M_G_CPU1_SA_PAR  PAR_A  @S9S_MB_2U_LIB.S9S_MB_2U(SCH_1):M_G_CPU1_SA_PAR
   20  M_G_CPU1_SA_DQ<9>  DQ_A9  @S9S_MB_2U_LIB.S9S_MB_2U(SCH_1):M_G_CPU1_SA_DQ<9>
   18  M_G_CPU1_SA_DQ<8>  DQ_A8  @S9S_MB_2U_LIB.S9S_MB_2U(SCH_1):M_G_CPU1_SA_DQ<8>
  161  M_G_CPU1_SA_DQ<7>  DQ_A7  @S9S_MB_2U_LIB.S9S_MB_2U(SCH_1):M_G_CPU1_SA_DQ<7>
  159  M_G_CPU1_SA_DQ<6>  DQ_A6  @S9S_MB_2U_LIB.S9S_MB_2U(SCH_1):M_G_CPU1_SA_DQ<6>
   16  M_G_CPU1_SA_DQ<5>  DQ_A5  @S9S_MB_2U_LIB.S9S_MB_2U(SCH_1):M_G_CPU1_SA_DQ<5>
   14  M_G_CPU1_SA_DQ<4>  DQ_A4  @S9S_MB_2U_LIB.S9S_MB_2U(SCH_1):M_G_CPU1_SA_DQ<4>
  154  M_G_CPU1_SA_DQ<3>  DQ_A3  @S9S_MB_2U_LIB.S9S_MB_2U(SCH_1):M_G_CPU1_SA_DQ<3>
  194  M_G_CPU1_SA_DQ<31>  DQ_A31  @S9S_MB_2U_LIB.S9S_MB_2U(SCH_1):M_G_CPU1_SA_DQ<31>
  192  M_G_CPU1_SA_DQ<30>  DQ_A30  @S9S_MB_2U_LIB.S9S_MB_2U(SCH_1):M_G_CPU1_SA_DQ<30>
  152  M_G_CPU1_SA_DQ<2>  DQ_A2  @S9S_MB_2U_LIB.S9S_MB_2U(SCH_1):M_G_CPU1_SA_DQ<2>
   49  M_G_CPU1_SA_DQ<29>  DQ_A29  @S9S_MB_2U_LIB.S9S_MB_2U(SCH_1):M_G_CPU1_SA_DQ<29>
   47  M_G_CPU1_SA_DQ<28>  DQ_A28  @S9S_MB_2U_LIB.S9S_MB_2U(SCH_1):M_G_CPU1_SA_DQ<28>
  187  M_G_CPU1_SA_DQ<27>  DQ_A27  @S9S_MB_2U_LIB.S9S_MB_2U(SCH_1):M_G_CPU1_SA_DQ<27>
  185  M_G_CPU1_SA_DQ<26>  DQ_A26  @S9S_MB_2U_LIB.S9S_MB_2U(SCH_1):M_G_CPU1_SA_DQ<26>
   42  M_G_CPU1_SA_DQ<25>  DQ_A25  @S9S_MB_2U_LIB.S9S_MB_2U(SCH_1):M_G_CPU1_SA_DQ<25>
   40  M_G_CPU1_SA_DQ<24>  DQ_A24  @S9S_MB_2U_LIB.S9S_MB_2U(SCH_1):M_G_CPU1_SA_DQ<24>
  183  M_G_CPU1_SA_DQ<23>  DQ_A23  @S9S_MB_2U_LIB.S9S_MB_2U(SCH_1):M_G_CPU1_SA_DQ<23>
  181  M_G_CPU1_SA_DQ<22>  DQ_A22  @S9S_MB_2U_LIB.S9S_MB_2U(SCH_1):M_G_CPU1_SA_DQ<22>
   38  M_G_CPU1_SA_DQ<21>  DQ_A21  @S9S_MB_2U_LIB.S9S_MB_2U(SCH_1):M_G_CPU1_SA_DQ<21>
   36  M_G_CPU1_SA_DQ<20>  DQ_A20  @S9S_MB_2U_LIB.S9S_MB_2U(SCH_1):M_G_CPU1_SA_DQ<20>
    9  M_G_CPU1_SA_DQ<1>  DQ_A1  @S9S_MB_2U_LIB.S9S_MB_2U(SCH_1):M_G_CPU1_SA_DQ<1>
  176  M_G_CPU1_SA_DQ<19>  DQ_A19  @S9S_MB_2U_LIB.S9S_MB_2U(SCH_1):M_G_CPU1_SA_DQ<19>
  174  M_G_CPU1_SA_DQ<18>  DQ_A18  @S9S_MB_2U_LIB.S9S_MB_2U(SCH_1):M_G_CPU1_SA_DQ<18>
   31  M_G_CPU1_SA_DQ<17>  DQ_A17  @S9S_MB_2U_LIB.S9S_MB_2U(SCH_1):M_G_CPU1_SA_DQ<17>
   29  M_G_CPU1_SA_DQ<16>  DQ_A16  @S9S_MB_2U_LIB.S9S_MB_2U(SCH_1):M_G_CPU1_SA_DQ<16>
  172  M_G_CPU1_SA_DQ<15>  DQ_A15  @S9S_MB_2U_LIB.S9S_MB_2U(SCH_1):M_G_CPU1_SA_DQ<15>
  170  M_G_CPU1_SA_DQ<14>  DQ_A14  @S9S_MB_2U_LIB.S9S_MB_2U(SCH_1):M_G_CPU1_SA_DQ<14>
   27  M_G_CPU1_SA_DQ<13>  DQ_A13  @S9S_MB_2U_LIB.S9S_MB_2U(SCH_1):M_G_CPU1_SA_DQ<13>
   25  M_G_CPU1_SA_DQ<12>  DQ_A12  @S9S_MB_2U_LIB.S9S_MB_2U(SCH_1):M_G_CPU1_SA_DQ<12>
  165  M_G_CPU1_SA_DQ<11>  DQ_A11  @S9S_MB_2U_LIB.S9S_MB_2U(SCH_1):M_G_CPU1_SA_DQ<11>
  163  M_G_CPU1_SA_DQ<10>  DQ_A10  @S9S_MB_2U_LIB.S9S_MB_2U(SCH_1):M_G_CPU1_SA_DQ<10>
    7  M_G_CPU1_SA_DQ<0>  DQ_A0  @S9S_MB_2U_LIB.S9S_MB_2U(SCH_1):M_G_CPU1_SA_DQ<0>
  209  M_G_CPU1_SA_CS_N<3>  CS1_N_A  @S9S_MB_2U_LIB.S9S_MB_2U(SCH_1):M_G_CPU1_SA_CS_N<3>
   64  M_G_CPU1_SA_CS_N<2>  CS0_N_A  @S9S_MB_2U_LIB.S9S_MB_2U(SCH_1):M_G_CPU1_SA_CS_N<2>
  205  M_G_CPU1_SA_CB<7>  CB_A7  @S9S_MB_2U_LIB.S9S_MB_2U(SCH_1):M_G_CPU1_SA_CB<7>
  203  M_G_CPU1_SA_CB<6>  CB_A6  @S9S_MB_2U_LIB.S9S_MB_2U(SCH_1):M_G_CPU1_SA_CB<6>
   60  M_G_CPU1_SA_CB<5>  CB_A5  @S9S_MB_2U_LIB.S9S_MB_2U(SCH_1):M_G_CPU1_SA_CB<5>
   58  M_G_CPU1_SA_CB<4>  CB_A4  @S9S_MB_2U_LIB.S9S_MB_2U(SCH_1):M_G_CPU1_SA_CB<4>
  198  M_G_CPU1_SA_CB<3>  CB_A3  @S9S_MB_2U_LIB.S9S_MB_2U(SCH_1):M_G_CPU1_SA_CB<3>
  196  M_G_CPU1_SA_CB<2>  CB_A2  @S9S_MB_2U_LIB.S9S_MB_2U(SCH_1):M_G_CPU1_SA_CB<2>
   53  M_G_CPU1_SA_CB<1>  CB_A1  @S9S_MB_2U_LIB.S9S_MB_2U(SCH_1):M_G_CPU1_SA_CB<1>
   51  M_G_CPU1_SA_CB<0>  CB_A0  @S9S_MB_2U_LIB.S9S_MB_2U(SCH_1):M_G_CPU1_SA_CB<0>
   72  M_G_CPU1_SA_CA<6>  CA6_A  @S9S_MB_2U_LIB.S9S_MB_2U(SCH_1):M_G_CPU1_SA_CA<6>
  215  M_G_CPU1_SA_CA<5>  CA5_A  @S9S_MB_2U_LIB.S9S_MB_2U(SCH_1):M_G_CPU1_SA_CA<5>
   70  M_G_CPU1_SA_CA<4>  CA4_A  @S9S_MB_2U_LIB.S9S_MB_2U(SCH_1):M_G_CPU1_SA_CA<4>
  213  M_G_CPU1_SA_CA<3>  CA3_A  @S9S_MB_2U_LIB.S9S_MB_2U(SCH_1):M_G_CPU1_SA_CA<3>
   68  M_G_CPU1_SA_CA<2>  CA2_A  @S9S_MB_2U_LIB.S9S_MB_2U(SCH_1):M_G_CPU1_SA_CA<2>
  211  M_G_CPU1_SA_CA<1>  CA1_A  @S9S_MB_2U_LIB.S9S_MB_2U(SCH_1):M_G_CPU1_SA_CA<1>
   66  M_G_CPU1_SA_CA<0>  CA0_A  @S9S_MB_2U_LIB.S9S_MB_2U(SCH_1):M_G_CPU1_SA_CA<0>
  217  M_G_CPU1_CLK_DP<1>   CK_P  @S9S_MB_2U_LIB.S9S_MB_2U(SCH_1):M_G_CPU1_CLK_DP<1>
  218  M_G_CPU1_CLK_DN<1>   CK_N  @S9S_MB_2U_LIB.S9S_MB_2U(SCH_1):M_G_CPU1_CLK_DN<1>
   62  M_G_CPU1_ALERT_N  ALERT_N  @S9S_MB_2U_LIB.S9S_MB_2U(SCH_1):M_G_CPU1_ALERT_N
    5  I3C_SPD_DDREFGH_CPU1_LVC1_SDA   HSDA  @S9S_MB_2U_LIB.S9S_MB_2U(SCH_1):I3C_SPD_DDREFGH_CPU1_LVC1_SDA
    4  I3C_SPD_DDREFGH_CPU1_LVC1_SCL   HSCL  @S9S_MB_2U_LIB.S9S_MB_2U(SCH_1):I3C_SPD_DDREFGH_CPU1_LVC1_SCL

SCONN288_ADR50001P013C01  I178  J31    [SCONN288_ADR50001P013C01-SCONNA]
  146  P12V_S3_AUX_CPU1_NVDIMM  VIN_BULK2  @S9S_MB_2U_LIB.S9S_MB_2U(SCH_1):P12V_S3_AUX_CPU1_NVDIMM
  145  P12V_S3_AUX_CPU1_NVDIMM  VIN_BULK1  @S9S_MB_2U_LIB.S9S_MB_2U(SCH_1):P12V_S3_AUX_CPU1_NVDIMM
    1  P12V_S3_AUX_CPU1_NVDIMM  VIN_BULK0  @S9S_MB_2U_LIB.S9S_MB_2U(SCH_1):P12V_S3_AUX_CPU1_NVDIMM
  288  GND            VSS126  @S9S_MB_2U_LIB.S9S_MB_2U(SCH_1):GND
  286  GND            VSS125  @S9S_MB_2U_LIB.S9S_MB_2U(SCH_1):GND
  284  GND            VSS124  @S9S_MB_2U_LIB.S9S_MB_2U(SCH_1):GND
  281  GND            VSS123  @S9S_MB_2U_LIB.S9S_MB_2U(SCH_1):GND
  279  GND            VSS122  @S9S_MB_2U_LIB.S9S_MB_2U(SCH_1):GND
  277  GND            VSS121  @S9S_MB_2U_LIB.S9S_MB_2U(SCH_1):GND
  275  GND            VSS120  @S9S_MB_2U_LIB.S9S_MB_2U(SCH_1):GND
  273  GND            VSS119  @S9S_MB_2U_LIB.S9S_MB_2U(SCH_1):GND
  270  GND            VSS118  @S9S_MB_2U_LIB.S9S_MB_2U(SCH_1):GND
  268  GND            VSS117  @S9S_MB_2U_LIB.S9S_MB_2U(SCH_1):GND
  266  GND            VSS116  @S9S_MB_2U_LIB.S9S_MB_2U(SCH_1):GND
  264  GND            VSS115  @S9S_MB_2U_LIB.S9S_MB_2U(SCH_1):GND
  262  GND            VSS114  @S9S_MB_2U_LIB.S9S_MB_2U(SCH_1):GND
  259  GND            VSS113  @S9S_MB_2U_LIB.S9S_MB_2U(SCH_1):GND
  257  GND            VSS112  @S9S_MB_2U_LIB.S9S_MB_2U(SCH_1):GND
  255  GND            VSS111  @S9S_MB_2U_LIB.S9S_MB_2U(SCH_1):GND
  253  GND            VSS110  @S9S_MB_2U_LIB.S9S_MB_2U(SCH_1):GND
  251  GND            VSS109  @S9S_MB_2U_LIB.S9S_MB_2U(SCH_1):GND
  248  GND            VSS108  @S9S_MB_2U_LIB.S9S_MB_2U(SCH_1):GND
  246  GND            VSS107  @S9S_MB_2U_LIB.S9S_MB_2U(SCH_1):GND
  244  GND            VSS106  @S9S_MB_2U_LIB.S9S_MB_2U(SCH_1):GND
  242  GND            VSS105  @S9S_MB_2U_LIB.S9S_MB_2U(SCH_1):GND
  240  GND            VSS104  @S9S_MB_2U_LIB.S9S_MB_2U(SCH_1):GND
  237  GND            VSS103  @S9S_MB_2U_LIB.S9S_MB_2U(SCH_1):GND
  235  GND            VSS102  @S9S_MB_2U_LIB.S9S_MB_2U(SCH_1):GND
  233  GND            VSS101  @S9S_MB_2U_LIB.S9S_MB_2U(SCH_1):GND
  230  GND            VSS100  @S9S_MB_2U_LIB.S9S_MB_2U(SCH_1):GND
  228  GND            VSS99  @S9S_MB_2U_LIB.S9S_MB_2U(SCH_1):GND
  226  GND            VSS98  @S9S_MB_2U_LIB.S9S_MB_2U(SCH_1):GND
  224  GND            VSS97  @S9S_MB_2U_LIB.S9S_MB_2U(SCH_1):GND
  222  GND            VSS96  @S9S_MB_2U_LIB.S9S_MB_2U(SCH_1):GND
  219  GND            VSS95  @S9S_MB_2U_LIB.S9S_MB_2U(SCH_1):GND
  216  GND            VSS94  @S9S_MB_2U_LIB.S9S_MB_2U(SCH_1):GND
  214  GND            VSS93  @S9S_MB_2U_LIB.S9S_MB_2U(SCH_1):GND
  212  GND            VSS92  @S9S_MB_2U_LIB.S9S_MB_2U(SCH_1):GND
  210  GND            VSS91  @S9S_MB_2U_LIB.S9S_MB_2U(SCH_1):GND
  208  GND            VSS90  @S9S_MB_2U_LIB.S9S_MB_2U(SCH_1):GND
  206  GND            VSS89  @S9S_MB_2U_LIB.S9S_MB_2U(SCH_1):GND
  204  GND            VSS88  @S9S_MB_2U_LIB.S9S_MB_2U(SCH_1):GND
  202  GND            VSS87  @S9S_MB_2U_LIB.S9S_MB_2U(SCH_1):GND
  199  GND            VSS86  @S9S_MB_2U_LIB.S9S_MB_2U(SCH_1):GND
  197  GND            VSS85  @S9S_MB_2U_LIB.S9S_MB_2U(SCH_1):GND
  195  GND            VSS84  @S9S_MB_2U_LIB.S9S_MB_2U(SCH_1):GND
  193  GND            VSS83  @S9S_MB_2U_LIB.S9S_MB_2U(SCH_1):GND
  191  GND            VSS82  @S9S_MB_2U_LIB.S9S_MB_2U(SCH_1):GND
  188  GND            VSS81  @S9S_MB_2U_LIB.S9S_MB_2U(SCH_1):GND
  186  GND            VSS80  @S9S_MB_2U_LIB.S9S_MB_2U(SCH_1):GND
  184  GND            VSS79  @S9S_MB_2U_LIB.S9S_MB_2U(SCH_1):GND
  182  GND            VSS78  @S9S_MB_2U_LIB.S9S_MB_2U(SCH_1):GND
  180  GND            VSS77  @S9S_MB_2U_LIB.S9S_MB_2U(SCH_1):GND
  177  GND            VSS76  @S9S_MB_2U_LIB.S9S_MB_2U(SCH_1):GND
  175  GND            VSS75  @S9S_MB_2U_LIB.S9S_MB_2U(SCH_1):GND
  173  GND            VSS74  @S9S_MB_2U_LIB.S9S_MB_2U(SCH_1):GND
  171  GND            VSS73  @S9S_MB_2U_LIB.S9S_MB_2U(SCH_1):GND
  169  GND            VSS72  @S9S_MB_2U_LIB.S9S_MB_2U(SCH_1):GND
  166  GND            VSS71  @S9S_MB_2U_LIB.S9S_MB_2U(SCH_1):GND
  164  GND            VSS70  @S9S_MB_2U_LIB.S9S_MB_2U(SCH_1):GND
  162  GND            VSS69  @S9S_MB_2U_LIB.S9S_MB_2U(SCH_1):GND
  160  GND            VSS68  @S9S_MB_2U_LIB.S9S_MB_2U(SCH_1):GND
  158  GND            VSS67  @S9S_MB_2U_LIB.S9S_MB_2U(SCH_1):GND
  155  GND            VSS66  @S9S_MB_2U_LIB.S9S_MB_2U(SCH_1):GND
  153  GND            VSS65  @S9S_MB_2U_LIB.S9S_MB_2U(SCH_1):GND
  151  GND            VSS64  @S9S_MB_2U_LIB.S9S_MB_2U(SCH_1):GND
  143  GND            VSS63  @S9S_MB_2U_LIB.S9S_MB_2U(SCH_1):GND
  141  GND            VSS62  @S9S_MB_2U_LIB.S9S_MB_2U(SCH_1):GND
  139  GND            VSS61  @S9S_MB_2U_LIB.S9S_MB_2U(SCH_1):GND
  136  GND            VSS60  @S9S_MB_2U_LIB.S9S_MB_2U(SCH_1):GND
  134  GND            VSS59  @S9S_MB_2U_LIB.S9S_MB_2U(SCH_1):GND
  132  GND            VSS58  @S9S_MB_2U_LIB.S9S_MB_2U(SCH_1):GND
  130  GND            VSS57  @S9S_MB_2U_LIB.S9S_MB_2U(SCH_1):GND
  128  GND            VSS56  @S9S_MB_2U_LIB.S9S_MB_2U(SCH_1):GND
  125  GND            VSS55  @S9S_MB_2U_LIB.S9S_MB_2U(SCH_1):GND
  123  GND            VSS54  @S9S_MB_2U_LIB.S9S_MB_2U(SCH_1):GND
  121  GND            VSS53  @S9S_MB_2U_LIB.S9S_MB_2U(SCH_1):GND
  119  GND            VSS52  @S9S_MB_2U_LIB.S9S_MB_2U(SCH_1):GND
  117  GND            VSS51  @S9S_MB_2U_LIB.S9S_MB_2U(SCH_1):GND
  114  GND            VSS50  @S9S_MB_2U_LIB.S9S_MB_2U(SCH_1):GND
  112  GND            VSS49  @S9S_MB_2U_LIB.S9S_MB_2U(SCH_1):GND
  110  GND            VSS48  @S9S_MB_2U_LIB.S9S_MB_2U(SCH_1):GND
  108  GND            VSS47  @S9S_MB_2U_LIB.S9S_MB_2U(SCH_1):GND
  106  GND            VSS46  @S9S_MB_2U_LIB.S9S_MB_2U(SCH_1):GND
  103  GND            VSS45  @S9S_MB_2U_LIB.S9S_MB_2U(SCH_1):GND
  101  GND            VSS44  @S9S_MB_2U_LIB.S9S_MB_2U(SCH_1):GND
   99  GND            VSS43  @S9S_MB_2U_LIB.S9S_MB_2U(SCH_1):GND
   97  GND            VSS42  @S9S_MB_2U_LIB.S9S_MB_2U(SCH_1):GND
   95  GND            VSS41  @S9S_MB_2U_LIB.S9S_MB_2U(SCH_1):GND
   92  GND            VSS40  @S9S_MB_2U_LIB.S9S_MB_2U(SCH_1):GND
   90  GND            VSS39  @S9S_MB_2U_LIB.S9S_MB_2U(SCH_1):GND
   88  GND            VSS38  @S9S_MB_2U_LIB.S9S_MB_2U(SCH_1):GND
   85  GND            VSS37  @S9S_MB_2U_LIB.S9S_MB_2U(SCH_1):GND
   83  GND            VSS36  @S9S_MB_2U_LIB.S9S_MB_2U(SCH_1):GND
   81  GND            VSS35  @S9S_MB_2U_LIB.S9S_MB_2U(SCH_1):GND
   79  GND            VSS34  @S9S_MB_2U_LIB.S9S_MB_2U(SCH_1):GND
   77  GND            VSS33  @S9S_MB_2U_LIB.S9S_MB_2U(SCH_1):GND
   75  GND            VSS32  @S9S_MB_2U_LIB.S9S_MB_2U(SCH_1):GND
   73  GND            VSS31  @S9S_MB_2U_LIB.S9S_MB_2U(SCH_1):GND
   71  GND            VSS30  @S9S_MB_2U_LIB.S9S_MB_2U(SCH_1):GND
   69  GND            VSS29  @S9S_MB_2U_LIB.S9S_MB_2U(SCH_1):GND
   67  GND            VSS28  @S9S_MB_2U_LIB.S9S_MB_2U(SCH_1):GND
   65  GND            VSS27  @S9S_MB_2U_LIB.S9S_MB_2U(SCH_1):GND
   63  GND            VSS26  @S9S_MB_2U_LIB.S9S_MB_2U(SCH_1):GND
   61  GND            VSS25  @S9S_MB_2U_LIB.S9S_MB_2U(SCH_1):GND
   59  GND            VSS24  @S9S_MB_2U_LIB.S9S_MB_2U(SCH_1):GND
   57  GND            VSS23  @S9S_MB_2U_LIB.S9S_MB_2U(SCH_1):GND
   54  GND            VSS22  @S9S_MB_2U_LIB.S9S_MB_2U(SCH_1):GND
   52  GND            VSS21  @S9S_MB_2U_LIB.S9S_MB_2U(SCH_1):GND
   50  GND            VSS20  @S9S_MB_2U_LIB.S9S_MB_2U(SCH_1):GND
   48  GND            VSS19  @S9S_MB_2U_LIB.S9S_MB_2U(SCH_1):GND
   46  GND            VSS18  @S9S_MB_2U_LIB.S9S_MB_2U(SCH_1):GND
   43  GND            VSS17  @S9S_MB_2U_LIB.S9S_MB_2U(SCH_1):GND
   41  GND            VSS16  @S9S_MB_2U_LIB.S9S_MB_2U(SCH_1):GND
   39  GND            VSS15  @S9S_MB_2U_LIB.S9S_MB_2U(SCH_1):GND
   37  GND            VSS14  @S9S_MB_2U_LIB.S9S_MB_2U(SCH_1):GND
   35  GND            VSS13  @S9S_MB_2U_LIB.S9S_MB_2U(SCH_1):GND
   32  GND            VSS12  @S9S_MB_2U_LIB.S9S_MB_2U(SCH_1):GND
   30  GND            VSS11  @S9S_MB_2U_LIB.S9S_MB_2U(SCH_1):GND
   28  GND            VSS10  @S9S_MB_2U_LIB.S9S_MB_2U(SCH_1):GND
   26  GND             VSS9  @S9S_MB_2U_LIB.S9S_MB_2U(SCH_1):GND
   24  GND             VSS8  @S9S_MB_2U_LIB.S9S_MB_2U(SCH_1):GND
   21  GND             VSS7  @S9S_MB_2U_LIB.S9S_MB_2U(SCH_1):GND
   19  GND             VSS6  @S9S_MB_2U_LIB.S9S_MB_2U(SCH_1):GND
   17  GND             VSS5  @S9S_MB_2U_LIB.S9S_MB_2U(SCH_1):GND
   15  GND             VSS4  @S9S_MB_2U_LIB.S9S_MB_2U(SCH_1):GND
   13  GND             VSS3  @S9S_MB_2U_LIB.S9S_MB_2U(SCH_1):GND
   10  GND             VSS2  @S9S_MB_2U_LIB.S9S_MB_2U(SCH_1):GND
    8  GND             VSS1  @S9S_MB_2U_LIB.S9S_MB_2U(SCH_1):GND
    6  GND             VSS0  @S9S_MB_2U_LIB.S9S_MB_2U(SCH_1):GND
   G3  GND               G3  @S9S_MB_2U_LIB.S9S_MB_2U(SCH_1):GND
   G2  GND               G2  @S9S_MB_2U_LIB.S9S_MB_2U(SCH_1):GND
   G1  GND               G1  @S9S_MB_2U_LIB.S9S_MB_2U(SCH_1):GND

SCONN288_ADR50001P013C01  I179  J31    [SCONN288_ADR50001P013C01-SCONNA]
   93  M_H_CPU1_SB_DQS_DP<9>  DQS9_B_P  @S9S_MB_2U_LIB.S9S_MB_2U(SCH_1):M_H_CPU1_SB_DQS_DP<9>
  283  M_H_CPU1_SB_DQS_DP<8>  DQS8_B_P  @S9S_MB_2U_LIB.S9S_MB_2U(SCH_1):M_H_CPU1_SB_DQS_DP<8>
  272  M_H_CPU1_SB_DQS_DP<7>  DQS7_B_P  @S9S_MB_2U_LIB.S9S_MB_2U(SCH_1):M_H_CPU1_SB_DQS_DP<7>
  261  M_H_CPU1_SB_DQS_DP<6>  DQS6_B_P  @S9S_MB_2U_LIB.S9S_MB_2U(SCH_1):M_H_CPU1_SB_DQS_DP<6>
  250  M_H_CPU1_SB_DQS_DP<5>  DQS5_B_P  @S9S_MB_2U_LIB.S9S_MB_2U(SCH_1):M_H_CPU1_SB_DQS_DP<5>
  239  M_H_CPU1_SB_DQS_DP<4>  DQS4_B_P  @S9S_MB_2U_LIB.S9S_MB_2U(SCH_1):M_H_CPU1_SB_DQS_DP<4>
  137  M_H_CPU1_SB_DQS_DP<3>  DQS3_B_P  @S9S_MB_2U_LIB.S9S_MB_2U(SCH_1):M_H_CPU1_SB_DQS_DP<3>
  126  M_H_CPU1_SB_DQS_DP<2>  DQS2_B_P  @S9S_MB_2U_LIB.S9S_MB_2U(SCH_1):M_H_CPU1_SB_DQS_DP<2>
  115  M_H_CPU1_SB_DQS_DP<1>  DQS1_B_P  @S9S_MB_2U_LIB.S9S_MB_2U(SCH_1):M_H_CPU1_SB_DQS_DP<1>
  104  M_H_CPU1_SB_DQS_DP<0>  DQS0_B_P  @S9S_MB_2U_LIB.S9S_MB_2U(SCH_1):M_H_CPU1_SB_DQS_DP<0>
   94  M_H_CPU1_SB_DQS_DN<9>  DQS9_B_N  @S9S_MB_2U_LIB.S9S_MB_2U(SCH_1):M_H_CPU1_SB_DQS_DN<9>
  282  M_H_CPU1_SB_DQS_DN<8>  DQS8_B_N  @S9S_MB_2U_LIB.S9S_MB_2U(SCH_1):M_H_CPU1_SB_DQS_DN<8>
  271  M_H_CPU1_SB_DQS_DN<7>  DQS7_B_N  @S9S_MB_2U_LIB.S9S_MB_2U(SCH_1):M_H_CPU1_SB_DQS_DN<7>
  260  M_H_CPU1_SB_DQS_DN<6>  DQS6_B_N  @S9S_MB_2U_LIB.S9S_MB_2U(SCH_1):M_H_CPU1_SB_DQS_DN<6>
  249  M_H_CPU1_SB_DQS_DN<5>  DQS5_B_N  @S9S_MB_2U_LIB.S9S_MB_2U(SCH_1):M_H_CPU1_SB_DQS_DN<5>
  238  M_H_CPU1_SB_DQS_DN<4>  DQS4_B_N  @S9S_MB_2U_LIB.S9S_MB_2U(SCH_1):M_H_CPU1_SB_DQS_DN<4>
  138  M_H_CPU1_SB_DQS_DN<3>  DQS3_B_N  @S9S_MB_2U_LIB.S9S_MB_2U(SCH_1):M_H_CPU1_SB_DQS_DN<3>
  127  M_H_CPU1_SB_DQS_DN<2>  DQS2_B_N  @S9S_MB_2U_LIB.S9S_MB_2U(SCH_1):M_H_CPU1_SB_DQS_DN<2>
  116  M_H_CPU1_SB_DQS_DN<1>  DQS1_B_N  @S9S_MB_2U_LIB.S9S_MB_2U(SCH_1):M_H_CPU1_SB_DQS_DN<1>
  105  M_H_CPU1_SB_DQS_DN<0>  DQS0_B_N  @S9S_MB_2U_LIB.S9S_MB_2U(SCH_1):M_H_CPU1_SB_DQS_DN<0>
  201  M_H_CPU1_SA_DQS_DP<9>  DQS9_A_P  @S9S_MB_2U_LIB.S9S_MB_2U(SCH_1):M_H_CPU1_SA_DQS_DP<9>
  190  M_H_CPU1_SA_DQS_DP<8>  DQS8_A_P  @S9S_MB_2U_LIB.S9S_MB_2U(SCH_1):M_H_CPU1_SA_DQS_DP<8>
  179  M_H_CPU1_SA_DQS_DP<7>  DQS7_A_P  @S9S_MB_2U_LIB.S9S_MB_2U(SCH_1):M_H_CPU1_SA_DQS_DP<7>
  168  M_H_CPU1_SA_DQS_DP<6>  DQS6_A_P  @S9S_MB_2U_LIB.S9S_MB_2U(SCH_1):M_H_CPU1_SA_DQS_DP<6>
  157  M_H_CPU1_SA_DQS_DP<5>  DQS5_A_P  @S9S_MB_2U_LIB.S9S_MB_2U(SCH_1):M_H_CPU1_SA_DQS_DP<5>
   55  M_H_CPU1_SA_DQS_DP<4>  DQS4_A_P  @S9S_MB_2U_LIB.S9S_MB_2U(SCH_1):M_H_CPU1_SA_DQS_DP<4>
   44  M_H_CPU1_SA_DQS_DP<3>  DQS3_A_P  @S9S_MB_2U_LIB.S9S_MB_2U(SCH_1):M_H_CPU1_SA_DQS_DP<3>
   33  M_H_CPU1_SA_DQS_DP<2>  DQS2_A_P  @S9S_MB_2U_LIB.S9S_MB_2U(SCH_1):M_H_CPU1_SA_DQS_DP<2>
   22  M_H_CPU1_SA_DQS_DP<1>  DQS1_A_P  @S9S_MB_2U_LIB.S9S_MB_2U(SCH_1):M_H_CPU1_SA_DQS_DP<1>
   11  M_H_CPU1_SA_DQS_DP<0>  DQS0_A_P  @S9S_MB_2U_LIB.S9S_MB_2U(SCH_1):M_H_CPU1_SA_DQS_DP<0>
  200  M_H_CPU1_SA_DQS_DN<9>  DQS9_A_N  @S9S_MB_2U_LIB.S9S_MB_2U(SCH_1):M_H_CPU1_SA_DQS_DN<9>
  189  M_H_CPU1_SA_DQS_DN<8>  DQS8_A_N  @S9S_MB_2U_LIB.S9S_MB_2U(SCH_1):M_H_CPU1_SA_DQS_DN<8>
  178  M_H_CPU1_SA_DQS_DN<7>  DQS7_A_N  @S9S_MB_2U_LIB.S9S_MB_2U(SCH_1):M_H_CPU1_SA_DQS_DN<7>
  167  M_H_CPU1_SA_DQS_DN<6>  DQS6_A_N  @S9S_MB_2U_LIB.S9S_MB_2U(SCH_1):M_H_CPU1_SA_DQS_DN<6>
  156  M_H_CPU1_SA_DQS_DN<5>  DQS5_A_N  @S9S_MB_2U_LIB.S9S_MB_2U(SCH_1):M_H_CPU1_SA_DQS_DN<5>
   56  M_H_CPU1_SA_DQS_DN<4>  DQS4_A_N  @S9S_MB_2U_LIB.S9S_MB_2U(SCH_1):M_H_CPU1_SA_DQS_DN<4>
   45  M_H_CPU1_SA_DQS_DN<3>  DQS3_A_N  @S9S_MB_2U_LIB.S9S_MB_2U(SCH_1):M_H_CPU1_SA_DQS_DN<3>
   34  M_H_CPU1_SA_DQS_DN<2>  DQS2_A_N  @S9S_MB_2U_LIB.S9S_MB_2U(SCH_1):M_H_CPU1_SA_DQS_DN<2>
   23  M_H_CPU1_SA_DQS_DN<1>  DQS1_A_N  @S9S_MB_2U_LIB.S9S_MB_2U(SCH_1):M_H_CPU1_SA_DQS_DN<1>
   12  M_H_CPU1_SA_DQS_DN<0>  DQS0_A_N  @S9S_MB_2U_LIB.S9S_MB_2U(SCH_1):M_H_CPU1_SA_DQS_DN<0>

SCONN288_ADR50001P013C01  I180  J31    [SCONN288_ADR50001P013C01-SCONNA]
  232  NC              RFU6  NC
  231  NC              RFU5  NC
  220  NC              RFU4  NC
  150  NC              RFU3  NC
  149  NC              RFU2  NC
  144  NC              RFU1  NC
    2  NC              RFU0  NC
  207  RST_M_GH_CPU1_FPGA_N  RESET_N  @S9S_MB_2U_LIB.S9S_MB_2U(SCH_1):RST_M_GH_CPU1_FPGA_N
  147  PWRGD_CHH_CPU1_DIMM1  PWR_GOOD||FAIL_N  @S9S_MB_2U_LIB.S9S_MB_2U(SCH_1):PWRGD_CHH_CPU1_DIMM1
  148  PD_CHH_CPU1_DIMM1_SAA    HAS  @S9S_MB_2U_LIB.S9S_MB_2U(SCH_1):PD_CHH_CPU1_DIMM1_SAA
    3  P3V3_AUX       VIN_MGMT  @S9S_MB_2U_LIB.S9S_MB_2U(SCH_1):P3V3_AUX
   87  M_H_CPU1_SB_RSP<0>  LBS||RSP_N_B  @S9S_MB_2U_LIB.S9S_MB_2U(SCH_1):M_H_CPU1_SB_RSP<0>
  227  M_H_CPU1_SB_PAR  PAR_B  @S9S_MB_2U_LIB.S9S_MB_2U(SCH_1):M_H_CPU1_SB_PAR
  113  M_H_CPU1_SB_DQ<9>  DQ_B9  @S9S_MB_2U_LIB.S9S_MB_2U(SCH_1):M_H_CPU1_SB_DQ<9>
  111  M_H_CPU1_SB_DQ<8>  DQ_B8  @S9S_MB_2U_LIB.S9S_MB_2U(SCH_1):M_H_CPU1_SB_DQ<8>
  254  M_H_CPU1_SB_DQ<7>  DQ_B7  @S9S_MB_2U_LIB.S9S_MB_2U(SCH_1):M_H_CPU1_SB_DQ<7>
  252  M_H_CPU1_SB_DQ<6>  DQ_B6  @S9S_MB_2U_LIB.S9S_MB_2U(SCH_1):M_H_CPU1_SB_DQ<6>
  109  M_H_CPU1_SB_DQ<5>  DQ_B5  @S9S_MB_2U_LIB.S9S_MB_2U(SCH_1):M_H_CPU1_SB_DQ<5>
  107  M_H_CPU1_SB_DQ<4>  DQ_B4  @S9S_MB_2U_LIB.S9S_MB_2U(SCH_1):M_H_CPU1_SB_DQ<4>
  247  M_H_CPU1_SB_DQ<3>  DQ_B3  @S9S_MB_2U_LIB.S9S_MB_2U(SCH_1):M_H_CPU1_SB_DQ<3>
  287  M_H_CPU1_SB_DQ<31>  DQ_B31  @S9S_MB_2U_LIB.S9S_MB_2U(SCH_1):M_H_CPU1_SB_DQ<31>
  285  M_H_CPU1_SB_DQ<30>  DQ_B30  @S9S_MB_2U_LIB.S9S_MB_2U(SCH_1):M_H_CPU1_SB_DQ<30>
  245  M_H_CPU1_SB_DQ<2>  DQ_B2  @S9S_MB_2U_LIB.S9S_MB_2U(SCH_1):M_H_CPU1_SB_DQ<2>
  142  M_H_CPU1_SB_DQ<29>  DQ_B29  @S9S_MB_2U_LIB.S9S_MB_2U(SCH_1):M_H_CPU1_SB_DQ<29>
  140  M_H_CPU1_SB_DQ<28>  DQ_B28  @S9S_MB_2U_LIB.S9S_MB_2U(SCH_1):M_H_CPU1_SB_DQ<28>
  280  M_H_CPU1_SB_DQ<27>  DQ_B27  @S9S_MB_2U_LIB.S9S_MB_2U(SCH_1):M_H_CPU1_SB_DQ<27>
  278  M_H_CPU1_SB_DQ<26>  DQ_B26  @S9S_MB_2U_LIB.S9S_MB_2U(SCH_1):M_H_CPU1_SB_DQ<26>
  135  M_H_CPU1_SB_DQ<25>  DQ_B25  @S9S_MB_2U_LIB.S9S_MB_2U(SCH_1):M_H_CPU1_SB_DQ<25>
  133  M_H_CPU1_SB_DQ<24>  DQ_B24  @S9S_MB_2U_LIB.S9S_MB_2U(SCH_1):M_H_CPU1_SB_DQ<24>
  276  M_H_CPU1_SB_DQ<23>  DQ_B23  @S9S_MB_2U_LIB.S9S_MB_2U(SCH_1):M_H_CPU1_SB_DQ<23>
  274  M_H_CPU1_SB_DQ<22>  DQ_B22  @S9S_MB_2U_LIB.S9S_MB_2U(SCH_1):M_H_CPU1_SB_DQ<22>
  131  M_H_CPU1_SB_DQ<21>  DQ_B21  @S9S_MB_2U_LIB.S9S_MB_2U(SCH_1):M_H_CPU1_SB_DQ<21>
  129  M_H_CPU1_SB_DQ<20>  DQ_B20  @S9S_MB_2U_LIB.S9S_MB_2U(SCH_1):M_H_CPU1_SB_DQ<20>
  102  M_H_CPU1_SB_DQ<1>  DQ_B1  @S9S_MB_2U_LIB.S9S_MB_2U(SCH_1):M_H_CPU1_SB_DQ<1>
  269  M_H_CPU1_SB_DQ<19>  DQ_B19  @S9S_MB_2U_LIB.S9S_MB_2U(SCH_1):M_H_CPU1_SB_DQ<19>
  267  M_H_CPU1_SB_DQ<18>  DQ_B18  @S9S_MB_2U_LIB.S9S_MB_2U(SCH_1):M_H_CPU1_SB_DQ<18>
  124  M_H_CPU1_SB_DQ<17>  DQ_B17  @S9S_MB_2U_LIB.S9S_MB_2U(SCH_1):M_H_CPU1_SB_DQ<17>
  122  M_H_CPU1_SB_DQ<16>  DQ_B16  @S9S_MB_2U_LIB.S9S_MB_2U(SCH_1):M_H_CPU1_SB_DQ<16>
  265  M_H_CPU1_SB_DQ<15>  DQ_B15  @S9S_MB_2U_LIB.S9S_MB_2U(SCH_1):M_H_CPU1_SB_DQ<15>
  263  M_H_CPU1_SB_DQ<14>  DQ_B14  @S9S_MB_2U_LIB.S9S_MB_2U(SCH_1):M_H_CPU1_SB_DQ<14>
  120  M_H_CPU1_SB_DQ<13>  DQ_B13  @S9S_MB_2U_LIB.S9S_MB_2U(SCH_1):M_H_CPU1_SB_DQ<13>
  118  M_H_CPU1_SB_DQ<12>  DQ_B12  @S9S_MB_2U_LIB.S9S_MB_2U(SCH_1):M_H_CPU1_SB_DQ<12>
  258  M_H_CPU1_SB_DQ<11>  DQ_B11  @S9S_MB_2U_LIB.S9S_MB_2U(SCH_1):M_H_CPU1_SB_DQ<11>
  256  M_H_CPU1_SB_DQ<10>  DQ_B10  @S9S_MB_2U_LIB.S9S_MB_2U(SCH_1):M_H_CPU1_SB_DQ<10>
  100  M_H_CPU1_SB_DQ<0>  DQ_B0  @S9S_MB_2U_LIB.S9S_MB_2U(SCH_1):M_H_CPU1_SB_DQ<0>
  229  M_H_CPU1_SB_CS_N<1>  CS1_N_B  @S9S_MB_2U_LIB.S9S_MB_2U(SCH_1):M_H_CPU1_SB_CS_N<1>
   84  M_H_CPU1_SB_CS_N<0>  CS0_N_B  @S9S_MB_2U_LIB.S9S_MB_2U(SCH_1):M_H_CPU1_SB_CS_N<0>
  236  M_H_CPU1_SB_CB<7>  CB_B7  @S9S_MB_2U_LIB.S9S_MB_2U(SCH_1):M_H_CPU1_SB_CB<7>
  234  M_H_CPU1_SB_CB<6>  CB_B6  @S9S_MB_2U_LIB.S9S_MB_2U(SCH_1):M_H_CPU1_SB_CB<6>
   91  M_H_CPU1_SB_CB<5>  CB_B5  @S9S_MB_2U_LIB.S9S_MB_2U(SCH_1):M_H_CPU1_SB_CB<5>
   89  M_H_CPU1_SB_CB<4>  CB_B4  @S9S_MB_2U_LIB.S9S_MB_2U(SCH_1):M_H_CPU1_SB_CB<4>
  243  M_H_CPU1_SB_CB<3>  CB_B3  @S9S_MB_2U_LIB.S9S_MB_2U(SCH_1):M_H_CPU1_SB_CB<3>
  241  M_H_CPU1_SB_CB<2>  CB_B2  @S9S_MB_2U_LIB.S9S_MB_2U(SCH_1):M_H_CPU1_SB_CB<2>
   98  M_H_CPU1_SB_CB<1>  CB_B1  @S9S_MB_2U_LIB.S9S_MB_2U(SCH_1):M_H_CPU1_SB_CB<1>
   96  M_H_CPU1_SB_CB<0>  CB_B0  @S9S_MB_2U_LIB.S9S_MB_2U(SCH_1):M_H_CPU1_SB_CB<0>
   82  M_H_CPU1_SB_CA<6>  CA6_B  @S9S_MB_2U_LIB.S9S_MB_2U(SCH_1):M_H_CPU1_SB_CA<6>
  225  M_H_CPU1_SB_CA<5>  CA5_B  @S9S_MB_2U_LIB.S9S_MB_2U(SCH_1):M_H_CPU1_SB_CA<5>
   80  M_H_CPU1_SB_CA<4>  CA4_B  @S9S_MB_2U_LIB.S9S_MB_2U(SCH_1):M_H_CPU1_SB_CA<4>
  223  M_H_CPU1_SB_CA<3>  CA3_B  @S9S_MB_2U_LIB.S9S_MB_2U(SCH_1):M_H_CPU1_SB_CA<3>
   78  M_H_CPU1_SB_CA<2>  CA2_B  @S9S_MB_2U_LIB.S9S_MB_2U(SCH_1):M_H_CPU1_SB_CA<2>
  221  M_H_CPU1_SB_CA<1>  CA1_B  @S9S_MB_2U_LIB.S9S_MB_2U(SCH_1):M_H_CPU1_SB_CA<1>
   76  M_H_CPU1_SB_CA<0>  CA0_B  @S9S_MB_2U_LIB.S9S_MB_2U(SCH_1):M_H_CPU1_SB_CA<0>
   86  M_H_CPU1_SA_RSP<0>  LBD||RSP_N_A  @S9S_MB_2U_LIB.S9S_MB_2U(SCH_1):M_H_CPU1_SA_RSP<0>
   74  M_H_CPU1_SA_PAR  PAR_A  @S9S_MB_2U_LIB.S9S_MB_2U(SCH_1):M_H_CPU1_SA_PAR
   20  M_H_CPU1_SA_DQ<9>  DQ_A9  @S9S_MB_2U_LIB.S9S_MB_2U(SCH_1):M_H_CPU1_SA_DQ<9>
   18  M_H_CPU1_SA_DQ<8>  DQ_A8  @S9S_MB_2U_LIB.S9S_MB_2U(SCH_1):M_H_CPU1_SA_DQ<8>
  161  M_H_CPU1_SA_DQ<7>  DQ_A7  @S9S_MB_2U_LIB.S9S_MB_2U(SCH_1):M_H_CPU1_SA_DQ<7>
  159  M_H_CPU1_SA_DQ<6>  DQ_A6  @S9S_MB_2U_LIB.S9S_MB_2U(SCH_1):M_H_CPU1_SA_DQ<6>
   16  M_H_CPU1_SA_DQ<5>  DQ_A5  @S9S_MB_2U_LIB.S9S_MB_2U(SCH_1):M_H_CPU1_SA_DQ<5>
   14  M_H_CPU1_SA_DQ<4>  DQ_A4  @S9S_MB_2U_LIB.S9S_MB_2U(SCH_1):M_H_CPU1_SA_DQ<4>
  154  M_H_CPU1_SA_DQ<3>  DQ_A3  @S9S_MB_2U_LIB.S9S_MB_2U(SCH_1):M_H_CPU1_SA_DQ<3>
  194  M_H_CPU1_SA_DQ<31>  DQ_A31  @S9S_MB_2U_LIB.S9S_MB_2U(SCH_1):M_H_CPU1_SA_DQ<31>
  192  M_H_CPU1_SA_DQ<30>  DQ_A30  @S9S_MB_2U_LIB.S9S_MB_2U(SCH_1):M_H_CPU1_SA_DQ<30>
  152  M_H_CPU1_SA_DQ<2>  DQ_A2  @S9S_MB_2U_LIB.S9S_MB_2U(SCH_1):M_H_CPU1_SA_DQ<2>
   49  M_H_CPU1_SA_DQ<29>  DQ_A29  @S9S_MB_2U_LIB.S9S_MB_2U(SCH_1):M_H_CPU1_SA_DQ<29>
   47  M_H_CPU1_SA_DQ<28>  DQ_A28  @S9S_MB_2U_LIB.S9S_MB_2U(SCH_1):M_H_CPU1_SA_DQ<28>
  187  M_H_CPU1_SA_DQ<27>  DQ_A27  @S9S_MB_2U_LIB.S9S_MB_2U(SCH_1):M_H_CPU1_SA_DQ<27>
  185  M_H_CPU1_SA_DQ<26>  DQ_A26  @S9S_MB_2U_LIB.S9S_MB_2U(SCH_1):M_H_CPU1_SA_DQ<26>
   42  M_H_CPU1_SA_DQ<25>  DQ_A25  @S9S_MB_2U_LIB.S9S_MB_2U(SCH_1):M_H_CPU1_SA_DQ<25>
   40  M_H_CPU1_SA_DQ<24>  DQ_A24  @S9S_MB_2U_LIB.S9S_MB_2U(SCH_1):M_H_CPU1_SA_DQ<24>
  183  M_H_CPU1_SA_DQ<23>  DQ_A23  @S9S_MB_2U_LIB.S9S_MB_2U(SCH_1):M_H_CPU1_SA_DQ<23>
  181  M_H_CPU1_SA_DQ<22>  DQ_A22  @S9S_MB_2U_LIB.S9S_MB_2U(SCH_1):M_H_CPU1_SA_DQ<22>
   38  M_H_CPU1_SA_DQ<21>  DQ_A21  @S9S_MB_2U_LIB.S9S_MB_2U(SCH_1):M_H_CPU1_SA_DQ<21>
   36  M_H_CPU1_SA_DQ<20>  DQ_A20  @S9S_MB_2U_LIB.S9S_MB_2U(SCH_1):M_H_CPU1_SA_DQ<20>
    9  M_H_CPU1_SA_DQ<1>  DQ_A1  @S9S_MB_2U_LIB.S9S_MB_2U(SCH_1):M_H_CPU1_SA_DQ<1>
  176  M_H_CPU1_SA_DQ<19>  DQ_A19  @S9S_MB_2U_LIB.S9S_MB_2U(SCH_1):M_H_CPU1_SA_DQ<19>
  174  M_H_CPU1_SA_DQ<18>  DQ_A18  @S9S_MB_2U_LIB.S9S_MB_2U(SCH_1):M_H_CPU1_SA_DQ<18>
   31  M_H_CPU1_SA_DQ<17>  DQ_A17  @S9S_MB_2U_LIB.S9S_MB_2U(SCH_1):M_H_CPU1_SA_DQ<17>
   29  M_H_CPU1_SA_DQ<16>  DQ_A16  @S9S_MB_2U_LIB.S9S_MB_2U(SCH_1):M_H_CPU1_SA_DQ<16>
  172  M_H_CPU1_SA_DQ<15>  DQ_A15  @S9S_MB_2U_LIB.S9S_MB_2U(SCH_1):M_H_CPU1_SA_DQ<15>
  170  M_H_CPU1_SA_DQ<14>  DQ_A14  @S9S_MB_2U_LIB.S9S_MB_2U(SCH_1):M_H_CPU1_SA_DQ<14>
   27  M_H_CPU1_SA_DQ<13>  DQ_A13  @S9S_MB_2U_LIB.S9S_MB_2U(SCH_1):M_H_CPU1_SA_DQ<13>
   25  M_H_CPU1_SA_DQ<12>  DQ_A12  @S9S_MB_2U_LIB.S9S_MB_2U(SCH_1):M_H_CPU1_SA_DQ<12>
  165  M_H_CPU1_SA_DQ<11>  DQ_A11  @S9S_MB_2U_LIB.S9S_MB_2U(SCH_1):M_H_CPU1_SA_DQ<11>
  163  M_H_CPU1_SA_DQ<10>  DQ_A10  @S9S_MB_2U_LIB.S9S_MB_2U(SCH_1):M_H_CPU1_SA_DQ<10>
    7  M_H_CPU1_SA_DQ<0>  DQ_A0  @S9S_MB_2U_LIB.S9S_MB_2U(SCH_1):M_H_CPU1_SA_DQ<0>
  209  M_H_CPU1_SA_CS_N<1>  CS1_N_A  @S9S_MB_2U_LIB.S9S_MB_2U(SCH_1):M_H_CPU1_SA_CS_N<1>
   64  M_H_CPU1_SA_CS_N<0>  CS0_N_A  @S9S_MB_2U_LIB.S9S_MB_2U(SCH_1):M_H_CPU1_SA_CS_N<0>
  205  M_H_CPU1_SA_CB<7>  CB_A7  @S9S_MB_2U_LIB.S9S_MB_2U(SCH_1):M_H_CPU1_SA_CB<7>
  203  M_H_CPU1_SA_CB<6>  CB_A6  @S9S_MB_2U_LIB.S9S_MB_2U(SCH_1):M_H_CPU1_SA_CB<6>
   60  M_H_CPU1_SA_CB<5>  CB_A5  @S9S_MB_2U_LIB.S9S_MB_2U(SCH_1):M_H_CPU1_SA_CB<5>
   58  M_H_CPU1_SA_CB<4>  CB_A4  @S9S_MB_2U_LIB.S9S_MB_2U(SCH_1):M_H_CPU1_SA_CB<4>
  198  M_H_CPU1_SA_CB<3>  CB_A3  @S9S_MB_2U_LIB.S9S_MB_2U(SCH_1):M_H_CPU1_SA_CB<3>
  196  M_H_CPU1_SA_CB<2>  CB_A2  @S9S_MB_2U_LIB.S9S_MB_2U(SCH_1):M_H_CPU1_SA_CB<2>
   53  M_H_CPU1_SA_CB<1>  CB_A1  @S9S_MB_2U_LIB.S9S_MB_2U(SCH_1):M_H_CPU1_SA_CB<1>
   51  M_H_CPU1_SA_CB<0>  CB_A0  @S9S_MB_2U_LIB.S9S_MB_2U(SCH_1):M_H_CPU1_SA_CB<0>
   72  M_H_CPU1_SA_CA<6>  CA6_A  @S9S_MB_2U_LIB.S9S_MB_2U(SCH_1):M_H_CPU1_SA_CA<6>
  215  M_H_CPU1_SA_CA<5>  CA5_A  @S9S_MB_2U_LIB.S9S_MB_2U(SCH_1):M_H_CPU1_SA_CA<5>
   70  M_H_CPU1_SA_CA<4>  CA4_A  @S9S_MB_2U_LIB.S9S_MB_2U(SCH_1):M_H_CPU1_SA_CA<4>
  213  M_H_CPU1_SA_CA<3>  CA3_A  @S9S_MB_2U_LIB.S9S_MB_2U(SCH_1):M_H_CPU1_SA_CA<3>
   68  M_H_CPU1_SA_CA<2>  CA2_A  @S9S_MB_2U_LIB.S9S_MB_2U(SCH_1):M_H_CPU1_SA_CA<2>
  211  M_H_CPU1_SA_CA<1>  CA1_A  @S9S_MB_2U_LIB.S9S_MB_2U(SCH_1):M_H_CPU1_SA_CA<1>
   66  M_H_CPU1_SA_CA<0>  CA0_A  @S9S_MB_2U_LIB.S9S_MB_2U(SCH_1):M_H_CPU1_SA_CA<0>
  217  M_H_CPU1_CLK_DP<0>   CK_P  @S9S_MB_2U_LIB.S9S_MB_2U(SCH_1):M_H_CPU1_CLK_DP<0>
  218  M_H_CPU1_CLK_DN<0>   CK_N  @S9S_MB_2U_LIB.S9S_MB_2U(SCH_1):M_H_CPU1_CLK_DN<0>
   62  M_H_CPU1_ALERT_N  ALERT_N  @S9S_MB_2U_LIB.S9S_MB_2U(SCH_1):M_H_CPU1_ALERT_N
    5  I3C_SPD_DDREFGH_CPU1_LVC1_SDA   HSDA  @S9S_MB_2U_LIB.S9S_MB_2U(SCH_1):I3C_SPD_DDREFGH_CPU1_LVC1_SDA
    4  I3C_SPD_DDREFGH_CPU1_LVC1_SCL   HSCL  @S9S_MB_2U_LIB.S9S_MB_2U(SCH_1):I3C_SPD_DDREFGH_CPU1_LVC1_SCL

SCONN288_ADR50001P003C01  I177  J32    [SCONN288_ADR50001P003C01-SCONNA]
  146  P12V_S3_AUX_CPU1_NVDIMM  VIN_BULK2  @S9S_MB_2U_LIB.S9S_MB_2U(SCH_1):P12V_S3_AUX_CPU1_NVDIMM
  145  P12V_S3_AUX_CPU1_NVDIMM  VIN_BULK1  @S9S_MB_2U_LIB.S9S_MB_2U(SCH_1):P12V_S3_AUX_CPU1_NVDIMM
    1  P12V_S3_AUX_CPU1_NVDIMM  VIN_BULK0  @S9S_MB_2U_LIB.S9S_MB_2U(SCH_1):P12V_S3_AUX_CPU1_NVDIMM
  288  GND            VSS126  @S9S_MB_2U_LIB.S9S_MB_2U(SCH_1):GND
  286  GND            VSS125  @S9S_MB_2U_LIB.S9S_MB_2U(SCH_1):GND
  284  GND            VSS124  @S9S_MB_2U_LIB.S9S_MB_2U(SCH_1):GND
  281  GND            VSS123  @S9S_MB_2U_LIB.S9S_MB_2U(SCH_1):GND
  279  GND            VSS122  @S9S_MB_2U_LIB.S9S_MB_2U(SCH_1):GND
  277  GND            VSS121  @S9S_MB_2U_LIB.S9S_MB_2U(SCH_1):GND
  275  GND            VSS120  @S9S_MB_2U_LIB.S9S_MB_2U(SCH_1):GND
  273  GND            VSS119  @S9S_MB_2U_LIB.S9S_MB_2U(SCH_1):GND
  270  GND            VSS118  @S9S_MB_2U_LIB.S9S_MB_2U(SCH_1):GND
  268  GND            VSS117  @S9S_MB_2U_LIB.S9S_MB_2U(SCH_1):GND
  266  GND            VSS116  @S9S_MB_2U_LIB.S9S_MB_2U(SCH_1):GND
  264  GND            VSS115  @S9S_MB_2U_LIB.S9S_MB_2U(SCH_1):GND
  262  GND            VSS114  @S9S_MB_2U_LIB.S9S_MB_2U(SCH_1):GND
  259  GND            VSS113  @S9S_MB_2U_LIB.S9S_MB_2U(SCH_1):GND
  257  GND            VSS112  @S9S_MB_2U_LIB.S9S_MB_2U(SCH_1):GND
  255  GND            VSS111  @S9S_MB_2U_LIB.S9S_MB_2U(SCH_1):GND
  253  GND            VSS110  @S9S_MB_2U_LIB.S9S_MB_2U(SCH_1):GND
  251  GND            VSS109  @S9S_MB_2U_LIB.S9S_MB_2U(SCH_1):GND
  248  GND            VSS108  @S9S_MB_2U_LIB.S9S_MB_2U(SCH_1):GND
  246  GND            VSS107  @S9S_MB_2U_LIB.S9S_MB_2U(SCH_1):GND
  244  GND            VSS106  @S9S_MB_2U_LIB.S9S_MB_2U(SCH_1):GND
  242  GND            VSS105  @S9S_MB_2U_LIB.S9S_MB_2U(SCH_1):GND
  240  GND            VSS104  @S9S_MB_2U_LIB.S9S_MB_2U(SCH_1):GND
  237  GND            VSS103  @S9S_MB_2U_LIB.S9S_MB_2U(SCH_1):GND
  235  GND            VSS102  @S9S_MB_2U_LIB.S9S_MB_2U(SCH_1):GND
  233  GND            VSS101  @S9S_MB_2U_LIB.S9S_MB_2U(SCH_1):GND
  230  GND            VSS100  @S9S_MB_2U_LIB.S9S_MB_2U(SCH_1):GND
  228  GND            VSS99  @S9S_MB_2U_LIB.S9S_MB_2U(SCH_1):GND
  226  GND            VSS98  @S9S_MB_2U_LIB.S9S_MB_2U(SCH_1):GND
  224  GND            VSS97  @S9S_MB_2U_LIB.S9S_MB_2U(SCH_1):GND
  222  GND            VSS96  @S9S_MB_2U_LIB.S9S_MB_2U(SCH_1):GND
  219  GND            VSS95  @S9S_MB_2U_LIB.S9S_MB_2U(SCH_1):GND
  216  GND            VSS94  @S9S_MB_2U_LIB.S9S_MB_2U(SCH_1):GND
  214  GND            VSS93  @S9S_MB_2U_LIB.S9S_MB_2U(SCH_1):GND
  212  GND            VSS92  @S9S_MB_2U_LIB.S9S_MB_2U(SCH_1):GND
  210  GND            VSS91  @S9S_MB_2U_LIB.S9S_MB_2U(SCH_1):GND
  208  GND            VSS90  @S9S_MB_2U_LIB.S9S_MB_2U(SCH_1):GND
  206  GND            VSS89  @S9S_MB_2U_LIB.S9S_MB_2U(SCH_1):GND
  204  GND            VSS88  @S9S_MB_2U_LIB.S9S_MB_2U(SCH_1):GND
  202  GND            VSS87  @S9S_MB_2U_LIB.S9S_MB_2U(SCH_1):GND
  199  GND            VSS86  @S9S_MB_2U_LIB.S9S_MB_2U(SCH_1):GND
  197  GND            VSS85  @S9S_MB_2U_LIB.S9S_MB_2U(SCH_1):GND
  195  GND            VSS84  @S9S_MB_2U_LIB.S9S_MB_2U(SCH_1):GND
  193  GND            VSS83  @S9S_MB_2U_LIB.S9S_MB_2U(SCH_1):GND
  191  GND            VSS82  @S9S_MB_2U_LIB.S9S_MB_2U(SCH_1):GND
  188  GND            VSS81  @S9S_MB_2U_LIB.S9S_MB_2U(SCH_1):GND
  186  GND            VSS80  @S9S_MB_2U_LIB.S9S_MB_2U(SCH_1):GND
  184  GND            VSS79  @S9S_MB_2U_LIB.S9S_MB_2U(SCH_1):GND
  182  GND            VSS78  @S9S_MB_2U_LIB.S9S_MB_2U(SCH_1):GND
  180  GND            VSS77  @S9S_MB_2U_LIB.S9S_MB_2U(SCH_1):GND
  177  GND            VSS76  @S9S_MB_2U_LIB.S9S_MB_2U(SCH_1):GND
  175  GND            VSS75  @S9S_MB_2U_LIB.S9S_MB_2U(SCH_1):GND
  173  GND            VSS74  @S9S_MB_2U_LIB.S9S_MB_2U(SCH_1):GND
  171  GND            VSS73  @S9S_MB_2U_LIB.S9S_MB_2U(SCH_1):GND
  169  GND            VSS72  @S9S_MB_2U_LIB.S9S_MB_2U(SCH_1):GND
  166  GND            VSS71  @S9S_MB_2U_LIB.S9S_MB_2U(SCH_1):GND
  164  GND            VSS70  @S9S_MB_2U_LIB.S9S_MB_2U(SCH_1):GND
  162  GND            VSS69  @S9S_MB_2U_LIB.S9S_MB_2U(SCH_1):GND
  160  GND            VSS68  @S9S_MB_2U_LIB.S9S_MB_2U(SCH_1):GND
  158  GND            VSS67  @S9S_MB_2U_LIB.S9S_MB_2U(SCH_1):GND
  155  GND            VSS66  @S9S_MB_2U_LIB.S9S_MB_2U(SCH_1):GND
  153  GND            VSS65  @S9S_MB_2U_LIB.S9S_MB_2U(SCH_1):GND
  151  GND            VSS64  @S9S_MB_2U_LIB.S9S_MB_2U(SCH_1):GND
  143  GND            VSS63  @S9S_MB_2U_LIB.S9S_MB_2U(SCH_1):GND
  141  GND            VSS62  @S9S_MB_2U_LIB.S9S_MB_2U(SCH_1):GND
  139  GND            VSS61  @S9S_MB_2U_LIB.S9S_MB_2U(SCH_1):GND
  136  GND            VSS60  @S9S_MB_2U_LIB.S9S_MB_2U(SCH_1):GND
  134  GND            VSS59  @S9S_MB_2U_LIB.S9S_MB_2U(SCH_1):GND
  132  GND            VSS58  @S9S_MB_2U_LIB.S9S_MB_2U(SCH_1):GND
  130  GND            VSS57  @S9S_MB_2U_LIB.S9S_MB_2U(SCH_1):GND
  128  GND            VSS56  @S9S_MB_2U_LIB.S9S_MB_2U(SCH_1):GND
  125  GND            VSS55  @S9S_MB_2U_LIB.S9S_MB_2U(SCH_1):GND
  123  GND            VSS54  @S9S_MB_2U_LIB.S9S_MB_2U(SCH_1):GND
  121  GND            VSS53  @S9S_MB_2U_LIB.S9S_MB_2U(SCH_1):GND
  119  GND            VSS52  @S9S_MB_2U_LIB.S9S_MB_2U(SCH_1):GND
  117  GND            VSS51  @S9S_MB_2U_LIB.S9S_MB_2U(SCH_1):GND
  114  GND            VSS50  @S9S_MB_2U_LIB.S9S_MB_2U(SCH_1):GND
  112  GND            VSS49  @S9S_MB_2U_LIB.S9S_MB_2U(SCH_1):GND
  110  GND            VSS48  @S9S_MB_2U_LIB.S9S_MB_2U(SCH_1):GND
  108  GND            VSS47  @S9S_MB_2U_LIB.S9S_MB_2U(SCH_1):GND
  106  GND            VSS46  @S9S_MB_2U_LIB.S9S_MB_2U(SCH_1):GND
  103  GND            VSS45  @S9S_MB_2U_LIB.S9S_MB_2U(SCH_1):GND
  101  GND            VSS44  @S9S_MB_2U_LIB.S9S_MB_2U(SCH_1):GND
   99  GND            VSS43  @S9S_MB_2U_LIB.S9S_MB_2U(SCH_1):GND
   97  GND            VSS42  @S9S_MB_2U_LIB.S9S_MB_2U(SCH_1):GND
   95  GND            VSS41  @S9S_MB_2U_LIB.S9S_MB_2U(SCH_1):GND
   92  GND            VSS40  @S9S_MB_2U_LIB.S9S_MB_2U(SCH_1):GND
   90  GND            VSS39  @S9S_MB_2U_LIB.S9S_MB_2U(SCH_1):GND
   88  GND            VSS38  @S9S_MB_2U_LIB.S9S_MB_2U(SCH_1):GND
   85  GND            VSS37  @S9S_MB_2U_LIB.S9S_MB_2U(SCH_1):GND
   83  GND            VSS36  @S9S_MB_2U_LIB.S9S_MB_2U(SCH_1):GND
   81  GND            VSS35  @S9S_MB_2U_LIB.S9S_MB_2U(SCH_1):GND
   79  GND            VSS34  @S9S_MB_2U_LIB.S9S_MB_2U(SCH_1):GND
   77  GND            VSS33  @S9S_MB_2U_LIB.S9S_MB_2U(SCH_1):GND
   75  GND            VSS32  @S9S_MB_2U_LIB.S9S_MB_2U(SCH_1):GND
   73  GND            VSS31  @S9S_MB_2U_LIB.S9S_MB_2U(SCH_1):GND
   71  GND            VSS30  @S9S_MB_2U_LIB.S9S_MB_2U(SCH_1):GND
   69  GND            VSS29  @S9S_MB_2U_LIB.S9S_MB_2U(SCH_1):GND
   67  GND            VSS28  @S9S_MB_2U_LIB.S9S_MB_2U(SCH_1):GND
   65  GND            VSS27  @S9S_MB_2U_LIB.S9S_MB_2U(SCH_1):GND
   63  GND            VSS26  @S9S_MB_2U_LIB.S9S_MB_2U(SCH_1):GND
   61  GND            VSS25  @S9S_MB_2U_LIB.S9S_MB_2U(SCH_1):GND
   59  GND            VSS24  @S9S_MB_2U_LIB.S9S_MB_2U(SCH_1):GND
   57  GND            VSS23  @S9S_MB_2U_LIB.S9S_MB_2U(SCH_1):GND
   54  GND            VSS22  @S9S_MB_2U_LIB.S9S_MB_2U(SCH_1):GND
   52  GND            VSS21  @S9S_MB_2U_LIB.S9S_MB_2U(SCH_1):GND
   50  GND            VSS20  @S9S_MB_2U_LIB.S9S_MB_2U(SCH_1):GND
   48  GND            VSS19  @S9S_MB_2U_LIB.S9S_MB_2U(SCH_1):GND
   46  GND            VSS18  @S9S_MB_2U_LIB.S9S_MB_2U(SCH_1):GND
   43  GND            VSS17  @S9S_MB_2U_LIB.S9S_MB_2U(SCH_1):GND
   41  GND            VSS16  @S9S_MB_2U_LIB.S9S_MB_2U(SCH_1):GND
   39  GND            VSS15  @S9S_MB_2U_LIB.S9S_MB_2U(SCH_1):GND
   37  GND            VSS14  @S9S_MB_2U_LIB.S9S_MB_2U(SCH_1):GND
   35  GND            VSS13  @S9S_MB_2U_LIB.S9S_MB_2U(SCH_1):GND
   32  GND            VSS12  @S9S_MB_2U_LIB.S9S_MB_2U(SCH_1):GND
   30  GND            VSS11  @S9S_MB_2U_LIB.S9S_MB_2U(SCH_1):GND
   28  GND            VSS10  @S9S_MB_2U_LIB.S9S_MB_2U(SCH_1):GND
   26  GND             VSS9  @S9S_MB_2U_LIB.S9S_MB_2U(SCH_1):GND
   24  GND             VSS8  @S9S_MB_2U_LIB.S9S_MB_2U(SCH_1):GND
   21  GND             VSS7  @S9S_MB_2U_LIB.S9S_MB_2U(SCH_1):GND
   19  GND             VSS6  @S9S_MB_2U_LIB.S9S_MB_2U(SCH_1):GND
   17  GND             VSS5  @S9S_MB_2U_LIB.S9S_MB_2U(SCH_1):GND
   15  GND             VSS4  @S9S_MB_2U_LIB.S9S_MB_2U(SCH_1):GND
   13  GND             VSS3  @S9S_MB_2U_LIB.S9S_MB_2U(SCH_1):GND
   10  GND             VSS2  @S9S_MB_2U_LIB.S9S_MB_2U(SCH_1):GND
    8  GND             VSS1  @S9S_MB_2U_LIB.S9S_MB_2U(SCH_1):GND
    6  GND             VSS0  @S9S_MB_2U_LIB.S9S_MB_2U(SCH_1):GND
   G3  GND               G3  @S9S_MB_2U_LIB.S9S_MB_2U(SCH_1):GND
   G2  GND               G2  @S9S_MB_2U_LIB.S9S_MB_2U(SCH_1):GND
   G1  GND               G1  @S9S_MB_2U_LIB.S9S_MB_2U(SCH_1):GND

SCONN288_ADR50001P003C01  I178  J32    [SCONN288_ADR50001P003C01-SCONNA]
   93  M_H_CPU1_SB_DQS_DP<9>  DQS9_B_P  @S9S_MB_2U_LIB.S9S_MB_2U(SCH_1):M_H_CPU1_SB_DQS_DP<9>
  283  M_H_CPU1_SB_DQS_DP<8>  DQS8_B_P  @S9S_MB_2U_LIB.S9S_MB_2U(SCH_1):M_H_CPU1_SB_DQS_DP<8>
  272  M_H_CPU1_SB_DQS_DP<7>  DQS7_B_P  @S9S_MB_2U_LIB.S9S_MB_2U(SCH_1):M_H_CPU1_SB_DQS_DP<7>
  261  M_H_CPU1_SB_DQS_DP<6>  DQS6_B_P  @S9S_MB_2U_LIB.S9S_MB_2U(SCH_1):M_H_CPU1_SB_DQS_DP<6>
  250  M_H_CPU1_SB_DQS_DP<5>  DQS5_B_P  @S9S_MB_2U_LIB.S9S_MB_2U(SCH_1):M_H_CPU1_SB_DQS_DP<5>
  239  M_H_CPU1_SB_DQS_DP<4>  DQS4_B_P  @S9S_MB_2U_LIB.S9S_MB_2U(SCH_1):M_H_CPU1_SB_DQS_DP<4>
  137  M_H_CPU1_SB_DQS_DP<3>  DQS3_B_P  @S9S_MB_2U_LIB.S9S_MB_2U(SCH_1):M_H_CPU1_SB_DQS_DP<3>
  126  M_H_CPU1_SB_DQS_DP<2>  DQS2_B_P  @S9S_MB_2U_LIB.S9S_MB_2U(SCH_1):M_H_CPU1_SB_DQS_DP<2>
  115  M_H_CPU1_SB_DQS_DP<1>  DQS1_B_P  @S9S_MB_2U_LIB.S9S_MB_2U(SCH_1):M_H_CPU1_SB_DQS_DP<1>
  104  M_H_CPU1_SB_DQS_DP<0>  DQS0_B_P  @S9S_MB_2U_LIB.S9S_MB_2U(SCH_1):M_H_CPU1_SB_DQS_DP<0>
   94  M_H_CPU1_SB_DQS_DN<9>  DQS9_B_N  @S9S_MB_2U_LIB.S9S_MB_2U(SCH_1):M_H_CPU1_SB_DQS_DN<9>
  282  M_H_CPU1_SB_DQS_DN<8>  DQS8_B_N  @S9S_MB_2U_LIB.S9S_MB_2U(SCH_1):M_H_CPU1_SB_DQS_DN<8>
  271  M_H_CPU1_SB_DQS_DN<7>  DQS7_B_N  @S9S_MB_2U_LIB.S9S_MB_2U(SCH_1):M_H_CPU1_SB_DQS_DN<7>
  260  M_H_CPU1_SB_DQS_DN<6>  DQS6_B_N  @S9S_MB_2U_LIB.S9S_MB_2U(SCH_1):M_H_CPU1_SB_DQS_DN<6>
  249  M_H_CPU1_SB_DQS_DN<5>  DQS5_B_N  @S9S_MB_2U_LIB.S9S_MB_2U(SCH_1):M_H_CPU1_SB_DQS_DN<5>
  238  M_H_CPU1_SB_DQS_DN<4>  DQS4_B_N  @S9S_MB_2U_LIB.S9S_MB_2U(SCH_1):M_H_CPU1_SB_DQS_DN<4>
  138  M_H_CPU1_SB_DQS_DN<3>  DQS3_B_N  @S9S_MB_2U_LIB.S9S_MB_2U(SCH_1):M_H_CPU1_SB_DQS_DN<3>
  127  M_H_CPU1_SB_DQS_DN<2>  DQS2_B_N  @S9S_MB_2U_LIB.S9S_MB_2U(SCH_1):M_H_CPU1_SB_DQS_DN<2>
  116  M_H_CPU1_SB_DQS_DN<1>  DQS1_B_N  @S9S_MB_2U_LIB.S9S_MB_2U(SCH_1):M_H_CPU1_SB_DQS_DN<1>
  105  M_H_CPU1_SB_DQS_DN<0>  DQS0_B_N  @S9S_MB_2U_LIB.S9S_MB_2U(SCH_1):M_H_CPU1_SB_DQS_DN<0>
  201  M_H_CPU1_SA_DQS_DP<9>  DQS9_A_P  @S9S_MB_2U_LIB.S9S_MB_2U(SCH_1):M_H_CPU1_SA_DQS_DP<9>
  190  M_H_CPU1_SA_DQS_DP<8>  DQS8_A_P  @S9S_MB_2U_LIB.S9S_MB_2U(SCH_1):M_H_CPU1_SA_DQS_DP<8>
  179  M_H_CPU1_SA_DQS_DP<7>  DQS7_A_P  @S9S_MB_2U_LIB.S9S_MB_2U(SCH_1):M_H_CPU1_SA_DQS_DP<7>
  168  M_H_CPU1_SA_DQS_DP<6>  DQS6_A_P  @S9S_MB_2U_LIB.S9S_MB_2U(SCH_1):M_H_CPU1_SA_DQS_DP<6>
  157  M_H_CPU1_SA_DQS_DP<5>  DQS5_A_P  @S9S_MB_2U_LIB.S9S_MB_2U(SCH_1):M_H_CPU1_SA_DQS_DP<5>
   55  M_H_CPU1_SA_DQS_DP<4>  DQS4_A_P  @S9S_MB_2U_LIB.S9S_MB_2U(SCH_1):M_H_CPU1_SA_DQS_DP<4>
   44  M_H_CPU1_SA_DQS_DP<3>  DQS3_A_P  @S9S_MB_2U_LIB.S9S_MB_2U(SCH_1):M_H_CPU1_SA_DQS_DP<3>
   33  M_H_CPU1_SA_DQS_DP<2>  DQS2_A_P  @S9S_MB_2U_LIB.S9S_MB_2U(SCH_1):M_H_CPU1_SA_DQS_DP<2>
   22  M_H_CPU1_SA_DQS_DP<1>  DQS1_A_P  @S9S_MB_2U_LIB.S9S_MB_2U(SCH_1):M_H_CPU1_SA_DQS_DP<1>
   11  M_H_CPU1_SA_DQS_DP<0>  DQS0_A_P  @S9S_MB_2U_LIB.S9S_MB_2U(SCH_1):M_H_CPU1_SA_DQS_DP<0>
  200  M_H_CPU1_SA_DQS_DN<9>  DQS9_A_N  @S9S_MB_2U_LIB.S9S_MB_2U(SCH_1):M_H_CPU1_SA_DQS_DN<9>
  189  M_H_CPU1_SA_DQS_DN<8>  DQS8_A_N  @S9S_MB_2U_LIB.S9S_MB_2U(SCH_1):M_H_CPU1_SA_DQS_DN<8>
  178  M_H_CPU1_SA_DQS_DN<7>  DQS7_A_N  @S9S_MB_2U_LIB.S9S_MB_2U(SCH_1):M_H_CPU1_SA_DQS_DN<7>
  167  M_H_CPU1_SA_DQS_DN<6>  DQS6_A_N  @S9S_MB_2U_LIB.S9S_MB_2U(SCH_1):M_H_CPU1_SA_DQS_DN<6>
  156  M_H_CPU1_SA_DQS_DN<5>  DQS5_A_N  @S9S_MB_2U_LIB.S9S_MB_2U(SCH_1):M_H_CPU1_SA_DQS_DN<5>
   56  M_H_CPU1_SA_DQS_DN<4>  DQS4_A_N  @S9S_MB_2U_LIB.S9S_MB_2U(SCH_1):M_H_CPU1_SA_DQS_DN<4>
   45  M_H_CPU1_SA_DQS_DN<3>  DQS3_A_N  @S9S_MB_2U_LIB.S9S_MB_2U(SCH_1):M_H_CPU1_SA_DQS_DN<3>
   34  M_H_CPU1_SA_DQS_DN<2>  DQS2_A_N  @S9S_MB_2U_LIB.S9S_MB_2U(SCH_1):M_H_CPU1_SA_DQS_DN<2>
   23  M_H_CPU1_SA_DQS_DN<1>  DQS1_A_N  @S9S_MB_2U_LIB.S9S_MB_2U(SCH_1):M_H_CPU1_SA_DQS_DN<1>
   12  M_H_CPU1_SA_DQS_DN<0>  DQS0_A_N  @S9S_MB_2U_LIB.S9S_MB_2U(SCH_1):M_H_CPU1_SA_DQS_DN<0>

SCONN288_ADR50001P003C01  I179  J32    [SCONN288_ADR50001P003C01-SCONNA]
  232  NC              RFU6  NC
  231  NC              RFU5  NC
  220  NC              RFU4  NC
  150  NC              RFU3  NC
  149  NC              RFU2  NC
  144  NC              RFU1  NC
    2  NC              RFU0  NC
  207  RST_M_GH_CPU1_FPGA_N  RESET_N  @S9S_MB_2U_LIB.S9S_MB_2U(SCH_1):RST_M_GH_CPU1_FPGA_N
  147  PWRGD_CHH_CPU1_DIMM2  PWR_GOOD||FAIL_N  @S9S_MB_2U_LIB.S9S_MB_2U(SCH_1):PWRGD_CHH_CPU1_DIMM2
  148  PD_CHH_CPU1_DIMM2_SAA    HAS  @S9S_MB_2U_LIB.S9S_MB_2U(SCH_1):PD_CHH_CPU1_DIMM2_SAA
    3  P3V3_AUX       VIN_MGMT  @S9S_MB_2U_LIB.S9S_MB_2U(SCH_1):P3V3_AUX
   87  M_H_CPU1_SB_RSP<1>  LBS||RSP_N_B  @S9S_MB_2U_LIB.S9S_MB_2U(SCH_1):M_H_CPU1_SB_RSP<1>
  227  M_H_CPU1_SB_PAR  PAR_B  @S9S_MB_2U_LIB.S9S_MB_2U(SCH_1):M_H_CPU1_SB_PAR
  113  M_H_CPU1_SB_DQ<9>  DQ_B9  @S9S_MB_2U_LIB.S9S_MB_2U(SCH_1):M_H_CPU1_SB_DQ<9>
  111  M_H_CPU1_SB_DQ<8>  DQ_B8  @S9S_MB_2U_LIB.S9S_MB_2U(SCH_1):M_H_CPU1_SB_DQ<8>
  254  M_H_CPU1_SB_DQ<7>  DQ_B7  @S9S_MB_2U_LIB.S9S_MB_2U(SCH_1):M_H_CPU1_SB_DQ<7>
  252  M_H_CPU1_SB_DQ<6>  DQ_B6  @S9S_MB_2U_LIB.S9S_MB_2U(SCH_1):M_H_CPU1_SB_DQ<6>
  109  M_H_CPU1_SB_DQ<5>  DQ_B5  @S9S_MB_2U_LIB.S9S_MB_2U(SCH_1):M_H_CPU1_SB_DQ<5>
  107  M_H_CPU1_SB_DQ<4>  DQ_B4  @S9S_MB_2U_LIB.S9S_MB_2U(SCH_1):M_H_CPU1_SB_DQ<4>
  247  M_H_CPU1_SB_DQ<3>  DQ_B3  @S9S_MB_2U_LIB.S9S_MB_2U(SCH_1):M_H_CPU1_SB_DQ<3>
  287  M_H_CPU1_SB_DQ<31>  DQ_B31  @S9S_MB_2U_LIB.S9S_MB_2U(SCH_1):M_H_CPU1_SB_DQ<31>
  285  M_H_CPU1_SB_DQ<30>  DQ_B30  @S9S_MB_2U_LIB.S9S_MB_2U(SCH_1):M_H_CPU1_SB_DQ<30>
  245  M_H_CPU1_SB_DQ<2>  DQ_B2  @S9S_MB_2U_LIB.S9S_MB_2U(SCH_1):M_H_CPU1_SB_DQ<2>
  142  M_H_CPU1_SB_DQ<29>  DQ_B29  @S9S_MB_2U_LIB.S9S_MB_2U(SCH_1):M_H_CPU1_SB_DQ<29>
  140  M_H_CPU1_SB_DQ<28>  DQ_B28  @S9S_MB_2U_LIB.S9S_MB_2U(SCH_1):M_H_CPU1_SB_DQ<28>
  280  M_H_CPU1_SB_DQ<27>  DQ_B27  @S9S_MB_2U_LIB.S9S_MB_2U(SCH_1):M_H_CPU1_SB_DQ<27>
  278  M_H_CPU1_SB_DQ<26>  DQ_B26  @S9S_MB_2U_LIB.S9S_MB_2U(SCH_1):M_H_CPU1_SB_DQ<26>
  135  M_H_CPU1_SB_DQ<25>  DQ_B25  @S9S_MB_2U_LIB.S9S_MB_2U(SCH_1):M_H_CPU1_SB_DQ<25>
  133  M_H_CPU1_SB_DQ<24>  DQ_B24  @S9S_MB_2U_LIB.S9S_MB_2U(SCH_1):M_H_CPU1_SB_DQ<24>
  276  M_H_CPU1_SB_DQ<23>  DQ_B23  @S9S_MB_2U_LIB.S9S_MB_2U(SCH_1):M_H_CPU1_SB_DQ<23>
  274  M_H_CPU1_SB_DQ<22>  DQ_B22  @S9S_MB_2U_LIB.S9S_MB_2U(SCH_1):M_H_CPU1_SB_DQ<22>
  131  M_H_CPU1_SB_DQ<21>  DQ_B21  @S9S_MB_2U_LIB.S9S_MB_2U(SCH_1):M_H_CPU1_SB_DQ<21>
  129  M_H_CPU1_SB_DQ<20>  DQ_B20  @S9S_MB_2U_LIB.S9S_MB_2U(SCH_1):M_H_CPU1_SB_DQ<20>
  102  M_H_CPU1_SB_DQ<1>  DQ_B1  @S9S_MB_2U_LIB.S9S_MB_2U(SCH_1):M_H_CPU1_SB_DQ<1>
  269  M_H_CPU1_SB_DQ<19>  DQ_B19  @S9S_MB_2U_LIB.S9S_MB_2U(SCH_1):M_H_CPU1_SB_DQ<19>
  267  M_H_CPU1_SB_DQ<18>  DQ_B18  @S9S_MB_2U_LIB.S9S_MB_2U(SCH_1):M_H_CPU1_SB_DQ<18>
  124  M_H_CPU1_SB_DQ<17>  DQ_B17  @S9S_MB_2U_LIB.S9S_MB_2U(SCH_1):M_H_CPU1_SB_DQ<17>
  122  M_H_CPU1_SB_DQ<16>  DQ_B16  @S9S_MB_2U_LIB.S9S_MB_2U(SCH_1):M_H_CPU1_SB_DQ<16>
  265  M_H_CPU1_SB_DQ<15>  DQ_B15  @S9S_MB_2U_LIB.S9S_MB_2U(SCH_1):M_H_CPU1_SB_DQ<15>
  263  M_H_CPU1_SB_DQ<14>  DQ_B14  @S9S_MB_2U_LIB.S9S_MB_2U(SCH_1):M_H_CPU1_SB_DQ<14>
  120  M_H_CPU1_SB_DQ<13>  DQ_B13  @S9S_MB_2U_LIB.S9S_MB_2U(SCH_1):M_H_CPU1_SB_DQ<13>
  118  M_H_CPU1_SB_DQ<12>  DQ_B12  @S9S_MB_2U_LIB.S9S_MB_2U(SCH_1):M_H_CPU1_SB_DQ<12>
  258  M_H_CPU1_SB_DQ<11>  DQ_B11  @S9S_MB_2U_LIB.S9S_MB_2U(SCH_1):M_H_CPU1_SB_DQ<11>
  256  M_H_CPU1_SB_DQ<10>  DQ_B10  @S9S_MB_2U_LIB.S9S_MB_2U(SCH_1):M_H_CPU1_SB_DQ<10>
  100  M_H_CPU1_SB_DQ<0>  DQ_B0  @S9S_MB_2U_LIB.S9S_MB_2U(SCH_1):M_H_CPU1_SB_DQ<0>
  229  M_H_CPU1_SB_CS_N<3>  CS1_N_B  @S9S_MB_2U_LIB.S9S_MB_2U(SCH_1):M_H_CPU1_SB_CS_N<3>
   84  M_H_CPU1_SB_CS_N<2>  CS0_N_B  @S9S_MB_2U_LIB.S9S_MB_2U(SCH_1):M_H_CPU1_SB_CS_N<2>
  236  M_H_CPU1_SB_CB<7>  CB_B7  @S9S_MB_2U_LIB.S9S_MB_2U(SCH_1):M_H_CPU1_SB_CB<7>
  234  M_H_CPU1_SB_CB<6>  CB_B6  @S9S_MB_2U_LIB.S9S_MB_2U(SCH_1):M_H_CPU1_SB_CB<6>
   91  M_H_CPU1_SB_CB<5>  CB_B5  @S9S_MB_2U_LIB.S9S_MB_2U(SCH_1):M_H_CPU1_SB_CB<5>
   89  M_H_CPU1_SB_CB<4>  CB_B4  @S9S_MB_2U_LIB.S9S_MB_2U(SCH_1):M_H_CPU1_SB_CB<4>
  243  M_H_CPU1_SB_CB<3>  CB_B3  @S9S_MB_2U_LIB.S9S_MB_2U(SCH_1):M_H_CPU1_SB_CB<3>
  241  M_H_CPU1_SB_CB<2>  CB_B2  @S9S_MB_2U_LIB.S9S_MB_2U(SCH_1):M_H_CPU1_SB_CB<2>
   98  M_H_CPU1_SB_CB<1>  CB_B1  @S9S_MB_2U_LIB.S9S_MB_2U(SCH_1):M_H_CPU1_SB_CB<1>
   96  M_H_CPU1_SB_CB<0>  CB_B0  @S9S_MB_2U_LIB.S9S_MB_2U(SCH_1):M_H_CPU1_SB_CB<0>
   82  M_H_CPU1_SB_CA<6>  CA6_B  @S9S_MB_2U_LIB.S9S_MB_2U(SCH_1):M_H_CPU1_SB_CA<6>
  225  M_H_CPU1_SB_CA<5>  CA5_B  @S9S_MB_2U_LIB.S9S_MB_2U(SCH_1):M_H_CPU1_SB_CA<5>
   80  M_H_CPU1_SB_CA<4>  CA4_B  @S9S_MB_2U_LIB.S9S_MB_2U(SCH_1):M_H_CPU1_SB_CA<4>
  223  M_H_CPU1_SB_CA<3>  CA3_B  @S9S_MB_2U_LIB.S9S_MB_2U(SCH_1):M_H_CPU1_SB_CA<3>
   78  M_H_CPU1_SB_CA<2>  CA2_B  @S9S_MB_2U_LIB.S9S_MB_2U(SCH_1):M_H_CPU1_SB_CA<2>
  221  M_H_CPU1_SB_CA<1>  CA1_B  @S9S_MB_2U_LIB.S9S_MB_2U(SCH_1):M_H_CPU1_SB_CA<1>
   76  M_H_CPU1_SB_CA<0>  CA0_B  @S9S_MB_2U_LIB.S9S_MB_2U(SCH_1):M_H_CPU1_SB_CA<0>
   86  M_H_CPU1_SA_RSP<1>  LBD||RSP_N_A  @S9S_MB_2U_LIB.S9S_MB_2U(SCH_1):M_H_CPU1_SA_RSP<1>
   74  M_H_CPU1_SA_PAR  PAR_A  @S9S_MB_2U_LIB.S9S_MB_2U(SCH_1):M_H_CPU1_SA_PAR
   20  M_H_CPU1_SA_DQ<9>  DQ_A9  @S9S_MB_2U_LIB.S9S_MB_2U(SCH_1):M_H_CPU1_SA_DQ<9>
   18  M_H_CPU1_SA_DQ<8>  DQ_A8  @S9S_MB_2U_LIB.S9S_MB_2U(SCH_1):M_H_CPU1_SA_DQ<8>
  161  M_H_CPU1_SA_DQ<7>  DQ_A7  @S9S_MB_2U_LIB.S9S_MB_2U(SCH_1):M_H_CPU1_SA_DQ<7>
  159  M_H_CPU1_SA_DQ<6>  DQ_A6  @S9S_MB_2U_LIB.S9S_MB_2U(SCH_1):M_H_CPU1_SA_DQ<6>
   16  M_H_CPU1_SA_DQ<5>  DQ_A5  @S9S_MB_2U_LIB.S9S_MB_2U(SCH_1):M_H_CPU1_SA_DQ<5>
   14  M_H_CPU1_SA_DQ<4>  DQ_A4  @S9S_MB_2U_LIB.S9S_MB_2U(SCH_1):M_H_CPU1_SA_DQ<4>
  154  M_H_CPU1_SA_DQ<3>  DQ_A3  @S9S_MB_2U_LIB.S9S_MB_2U(SCH_1):M_H_CPU1_SA_DQ<3>
  194  M_H_CPU1_SA_DQ<31>  DQ_A31  @S9S_MB_2U_LIB.S9S_MB_2U(SCH_1):M_H_CPU1_SA_DQ<31>
  192  M_H_CPU1_SA_DQ<30>  DQ_A30  @S9S_MB_2U_LIB.S9S_MB_2U(SCH_1):M_H_CPU1_SA_DQ<30>
  152  M_H_CPU1_SA_DQ<2>  DQ_A2  @S9S_MB_2U_LIB.S9S_MB_2U(SCH_1):M_H_CPU1_SA_DQ<2>
   49  M_H_CPU1_SA_DQ<29>  DQ_A29  @S9S_MB_2U_LIB.S9S_MB_2U(SCH_1):M_H_CPU1_SA_DQ<29>
   47  M_H_CPU1_SA_DQ<28>  DQ_A28  @S9S_MB_2U_LIB.S9S_MB_2U(SCH_1):M_H_CPU1_SA_DQ<28>
  187  M_H_CPU1_SA_DQ<27>  DQ_A27  @S9S_MB_2U_LIB.S9S_MB_2U(SCH_1):M_H_CPU1_SA_DQ<27>
  185  M_H_CPU1_SA_DQ<26>  DQ_A26  @S9S_MB_2U_LIB.S9S_MB_2U(SCH_1):M_H_CPU1_SA_DQ<26>
   42  M_H_CPU1_SA_DQ<25>  DQ_A25  @S9S_MB_2U_LIB.S9S_MB_2U(SCH_1):M_H_CPU1_SA_DQ<25>
   40  M_H_CPU1_SA_DQ<24>  DQ_A24  @S9S_MB_2U_LIB.S9S_MB_2U(SCH_1):M_H_CPU1_SA_DQ<24>
  183  M_H_CPU1_SA_DQ<23>  DQ_A23  @S9S_MB_2U_LIB.S9S_MB_2U(SCH_1):M_H_CPU1_SA_DQ<23>
  181  M_H_CPU1_SA_DQ<22>  DQ_A22  @S9S_MB_2U_LIB.S9S_MB_2U(SCH_1):M_H_CPU1_SA_DQ<22>
   38  M_H_CPU1_SA_DQ<21>  DQ_A21  @S9S_MB_2U_LIB.S9S_MB_2U(SCH_1):M_H_CPU1_SA_DQ<21>
   36  M_H_CPU1_SA_DQ<20>  DQ_A20  @S9S_MB_2U_LIB.S9S_MB_2U(SCH_1):M_H_CPU1_SA_DQ<20>
    9  M_H_CPU1_SA_DQ<1>  DQ_A1  @S9S_MB_2U_LIB.S9S_MB_2U(SCH_1):M_H_CPU1_SA_DQ<1>
  176  M_H_CPU1_SA_DQ<19>  DQ_A19  @S9S_MB_2U_LIB.S9S_MB_2U(SCH_1):M_H_CPU1_SA_DQ<19>
  174  M_H_CPU1_SA_DQ<18>  DQ_A18  @S9S_MB_2U_LIB.S9S_MB_2U(SCH_1):M_H_CPU1_SA_DQ<18>
   31  M_H_CPU1_SA_DQ<17>  DQ_A17  @S9S_MB_2U_LIB.S9S_MB_2U(SCH_1):M_H_CPU1_SA_DQ<17>
   29  M_H_CPU1_SA_DQ<16>  DQ_A16  @S9S_MB_2U_LIB.S9S_MB_2U(SCH_1):M_H_CPU1_SA_DQ<16>
  172  M_H_CPU1_SA_DQ<15>  DQ_A15  @S9S_MB_2U_LIB.S9S_MB_2U(SCH_1):M_H_CPU1_SA_DQ<15>
  170  M_H_CPU1_SA_DQ<14>  DQ_A14  @S9S_MB_2U_LIB.S9S_MB_2U(SCH_1):M_H_CPU1_SA_DQ<14>
   27  M_H_CPU1_SA_DQ<13>  DQ_A13  @S9S_MB_2U_LIB.S9S_MB_2U(SCH_1):M_H_CPU1_SA_DQ<13>
   25  M_H_CPU1_SA_DQ<12>  DQ_A12  @S9S_MB_2U_LIB.S9S_MB_2U(SCH_1):M_H_CPU1_SA_DQ<12>
  165  M_H_CPU1_SA_DQ<11>  DQ_A11  @S9S_MB_2U_LIB.S9S_MB_2U(SCH_1):M_H_CPU1_SA_DQ<11>
  163  M_H_CPU1_SA_DQ<10>  DQ_A10  @S9S_MB_2U_LIB.S9S_MB_2U(SCH_1):M_H_CPU1_SA_DQ<10>
    7  M_H_CPU1_SA_DQ<0>  DQ_A0  @S9S_MB_2U_LIB.S9S_MB_2U(SCH_1):M_H_CPU1_SA_DQ<0>
  209  M_H_CPU1_SA_CS_N<3>  CS1_N_A  @S9S_MB_2U_LIB.S9S_MB_2U(SCH_1):M_H_CPU1_SA_CS_N<3>
   64  M_H_CPU1_SA_CS_N<2>  CS0_N_A  @S9S_MB_2U_LIB.S9S_MB_2U(SCH_1):M_H_CPU1_SA_CS_N<2>
  205  M_H_CPU1_SA_CB<7>  CB_A7  @S9S_MB_2U_LIB.S9S_MB_2U(SCH_1):M_H_CPU1_SA_CB<7>
  203  M_H_CPU1_SA_CB<6>  CB_A6  @S9S_MB_2U_LIB.S9S_MB_2U(SCH_1):M_H_CPU1_SA_CB<6>
   60  M_H_CPU1_SA_CB<5>  CB_A5  @S9S_MB_2U_LIB.S9S_MB_2U(SCH_1):M_H_CPU1_SA_CB<5>
   58  M_H_CPU1_SA_CB<4>  CB_A4  @S9S_MB_2U_LIB.S9S_MB_2U(SCH_1):M_H_CPU1_SA_CB<4>
  198  M_H_CPU1_SA_CB<3>  CB_A3  @S9S_MB_2U_LIB.S9S_MB_2U(SCH_1):M_H_CPU1_SA_CB<3>
  196  M_H_CPU1_SA_CB<2>  CB_A2  @S9S_MB_2U_LIB.S9S_MB_2U(SCH_1):M_H_CPU1_SA_CB<2>
   53  M_H_CPU1_SA_CB<1>  CB_A1  @S9S_MB_2U_LIB.S9S_MB_2U(SCH_1):M_H_CPU1_SA_CB<1>
   51  M_H_CPU1_SA_CB<0>  CB_A0  @S9S_MB_2U_LIB.S9S_MB_2U(SCH_1):M_H_CPU1_SA_CB<0>
   72  M_H_CPU1_SA_CA<6>  CA6_A  @S9S_MB_2U_LIB.S9S_MB_2U(SCH_1):M_H_CPU1_SA_CA<6>
  215  M_H_CPU1_SA_CA<5>  CA5_A  @S9S_MB_2U_LIB.S9S_MB_2U(SCH_1):M_H_CPU1_SA_CA<5>
   70  M_H_CPU1_SA_CA<4>  CA4_A  @S9S_MB_2U_LIB.S9S_MB_2U(SCH_1):M_H_CPU1_SA_CA<4>
  213  M_H_CPU1_SA_CA<3>  CA3_A  @S9S_MB_2U_LIB.S9S_MB_2U(SCH_1):M_H_CPU1_SA_CA<3>
   68  M_H_CPU1_SA_CA<2>  CA2_A  @S9S_MB_2U_LIB.S9S_MB_2U(SCH_1):M_H_CPU1_SA_CA<2>
  211  M_H_CPU1_SA_CA<1>  CA1_A  @S9S_MB_2U_LIB.S9S_MB_2U(SCH_1):M_H_CPU1_SA_CA<1>
   66  M_H_CPU1_SA_CA<0>  CA0_A  @S9S_MB_2U_LIB.S9S_MB_2U(SCH_1):M_H_CPU1_SA_CA<0>
  217  M_H_CPU1_CLK_DP<1>   CK_P  @S9S_MB_2U_LIB.S9S_MB_2U(SCH_1):M_H_CPU1_CLK_DP<1>
  218  M_H_CPU1_CLK_DN<1>   CK_N  @S9S_MB_2U_LIB.S9S_MB_2U(SCH_1):M_H_CPU1_CLK_DN<1>
   62  M_H_CPU1_ALERT_N  ALERT_N  @S9S_MB_2U_LIB.S9S_MB_2U(SCH_1):M_H_CPU1_ALERT_N
    5  I3C_SPD_DDREFGH_CPU1_LVC1_SDA   HSDA  @S9S_MB_2U_LIB.S9S_MB_2U(SCH_1):I3C_SPD_DDREFGH_CPU1_LVC1_SDA
    4  I3C_SPD_DDREFGH_CPU1_LVC1_SCL   HSCL  @S9S_MB_2U_LIB.S9S_MB_2U(SCH_1):I3C_SPD_DDREFGH_CPU1_LVC1_SCL

SCONN84_123318136  I53  J33    [SCONN84_123318136-SCONN84_1-23A]
   B9  NC             DUALPORTEN_N  NC
  A10  NC             LED_ACTIVITYA10  NC
  A15  NC             REFCLKP1  NC
  A14  NC             REFCLKN1  NC
   A8  SMB_EDSFF2A_3V3AUX_SDA_R  SMBDAT  @S9S_MB_2U_LIB.S9S_MB_2U(SCH_1):SMB_EDSFF2A_3V3AUX_SDA_R
   A7  SMB_EDSFF2A_3V3AUX_SCL_R  SMBCLK  @S9S_MB_2U_LIB.S9S_MB_2U(SCH_1):SMB_EDSFF2A_3V3AUX_SCL_R
   A9  RST_SMB_EDSFF2A_N  SMBRST_N  @S9S_MB_2U_LIB.S9S_MB_2U(SCH_1):RST_SMB_EDSFF2A_N
  B10  RST_PCIE_EDSFF2A_PERST_N  PERST0_N  @S9S_MB_2U_LIB.S9S_MB_2U(SCH_1):RST_PCIE_EDSFF2A_PERST_N
  A11  PU_EDSFF2A_PERST1_CLKREQ_N  PERST1_N_CLKREQ_N  @S9S_MB_2U_LIB.S9S_MB_2U(SCH_1):PU_EDSFF2A_PERST1_CLKREQ_N
  A12  PD_PCIE_EDSFF2A_PRSNT_0_N  PRSNT0_N  @S9S_MB_2U_LIB.S9S_MB_2U(SCH_1):PD_PCIE_EDSFF2A_PRSNT_0_N
  B12  PD_EDSFF2A_PWRDIS  PWRDIS  @S9S_MB_2U_LIB.S9S_MB_2U(SCH_1):PD_EDSFF2A_PWRDIS
  B17  P5E_CPU0_PE4_TX_C_DP<7>  PERN0  @S9S_MB_2U_LIB.S9S_MB_2U(SCH_1):P5E_CPU0_PE4_TX_C_DP<7>
  B20  P5E_CPU0_PE4_TX_C_DP<6>  PERN1  @S9S_MB_2U_LIB.S9S_MB_2U(SCH_1):P5E_CPU0_PE4_TX_C_DP<6>
  B23  P5E_CPU0_PE4_TX_C_DP<5>  PERN2  @S9S_MB_2U_LIB.S9S_MB_2U(SCH_1):P5E_CPU0_PE4_TX_C_DP<5>
  B26  P5E_CPU0_PE4_TX_C_DP<4>  PERN3  @S9S_MB_2U_LIB.S9S_MB_2U(SCH_1):P5E_CPU0_PE4_TX_C_DP<4>
  B30  P5E_CPU0_PE4_TX_C_DP<3>  PERN4  @S9S_MB_2U_LIB.S9S_MB_2U(SCH_1):P5E_CPU0_PE4_TX_C_DP<3>
  B33  P5E_CPU0_PE4_TX_C_DP<2>  PERN5  @S9S_MB_2U_LIB.S9S_MB_2U(SCH_1):P5E_CPU0_PE4_TX_C_DP<2>
  B36  P5E_CPU0_PE4_TX_C_DP<1>  PERN6  @S9S_MB_2U_LIB.S9S_MB_2U(SCH_1):P5E_CPU0_PE4_TX_C_DP<1>
  B39  P5E_CPU0_PE4_TX_C_DP<0>  PERN7  @S9S_MB_2U_LIB.S9S_MB_2U(SCH_1):P5E_CPU0_PE4_TX_C_DP<0>
  B18  P5E_CPU0_PE4_TX_C_DN<7>  PERP0  @S9S_MB_2U_LIB.S9S_MB_2U(SCH_1):P5E_CPU0_PE4_TX_C_DN<7>
  B21  P5E_CPU0_PE4_TX_C_DN<6>  PERP1  @S9S_MB_2U_LIB.S9S_MB_2U(SCH_1):P5E_CPU0_PE4_TX_C_DN<6>
  B24  P5E_CPU0_PE4_TX_C_DN<5>  PERP2  @S9S_MB_2U_LIB.S9S_MB_2U(SCH_1):P5E_CPU0_PE4_TX_C_DN<5>
  B27  P5E_CPU0_PE4_TX_C_DN<4>  PERP3  @S9S_MB_2U_LIB.S9S_MB_2U(SCH_1):P5E_CPU0_PE4_TX_C_DN<4>
  B31  P5E_CPU0_PE4_TX_C_DN<3>  PERP4  @S9S_MB_2U_LIB.S9S_MB_2U(SCH_1):P5E_CPU0_PE4_TX_C_DN<3>
  B34  P5E_CPU0_PE4_TX_C_DN<2>  PERP5  @S9S_MB_2U_LIB.S9S_MB_2U(SCH_1):P5E_CPU0_PE4_TX_C_DN<2>
  B37  P5E_CPU0_PE4_TX_C_DN<1>  PERP6  @S9S_MB_2U_LIB.S9S_MB_2U(SCH_1):P5E_CPU0_PE4_TX_C_DN<1>
  B40  P5E_CPU0_PE4_TX_C_DN<0>  PERP7  @S9S_MB_2U_LIB.S9S_MB_2U(SCH_1):P5E_CPU0_PE4_TX_C_DN<0>
  A18  P5E_CPU0_PE4_RX_DP<7>  PETP0  @S9S_MB_2U_LIB.S9S_MB_2U(SCH_1):P5E_CPU0_PE4_RX_DP<7>
  A21  P5E_CPU0_PE4_RX_DP<6>  PETP1  @S9S_MB_2U_LIB.S9S_MB_2U(SCH_1):P5E_CPU0_PE4_RX_DP<6>
  A23  P5E_CPU0_PE4_RX_DP<5>  PETN2  @S9S_MB_2U_LIB.S9S_MB_2U(SCH_1):P5E_CPU0_PE4_RX_DP<5>
  A27  P5E_CPU0_PE4_RX_DP<4>  PETP3  @S9S_MB_2U_LIB.S9S_MB_2U(SCH_1):P5E_CPU0_PE4_RX_DP<4>
  A31  P5E_CPU0_PE4_RX_DP<3>  PETP4  @S9S_MB_2U_LIB.S9S_MB_2U(SCH_1):P5E_CPU0_PE4_RX_DP<3>
  A34  P5E_CPU0_PE4_RX_DP<2>  PETP5  @S9S_MB_2U_LIB.S9S_MB_2U(SCH_1):P5E_CPU0_PE4_RX_DP<2>
  A36  P5E_CPU0_PE4_RX_DP<1>  PETN6  @S9S_MB_2U_LIB.S9S_MB_2U(SCH_1):P5E_CPU0_PE4_RX_DP<1>
  A40  P5E_CPU0_PE4_RX_DP<0>  PETP7  @S9S_MB_2U_LIB.S9S_MB_2U(SCH_1):P5E_CPU0_PE4_RX_DP<0>
  A17  P5E_CPU0_PE4_RX_DN<7>  PETN0  @S9S_MB_2U_LIB.S9S_MB_2U(SCH_1):P5E_CPU0_PE4_RX_DN<7>
  A20  P5E_CPU0_PE4_RX_DN<6>  PETN1  @S9S_MB_2U_LIB.S9S_MB_2U(SCH_1):P5E_CPU0_PE4_RX_DN<6>
  A24  P5E_CPU0_PE4_RX_DN<5>  PETP2  @S9S_MB_2U_LIB.S9S_MB_2U(SCH_1):P5E_CPU0_PE4_RX_DN<5>
  A26  P5E_CPU0_PE4_RX_DN<4>  PETN3  @S9S_MB_2U_LIB.S9S_MB_2U(SCH_1):P5E_CPU0_PE4_RX_DN<4>
  A30  P5E_CPU0_PE4_RX_DN<3>  PETN4  @S9S_MB_2U_LIB.S9S_MB_2U(SCH_1):P5E_CPU0_PE4_RX_DN<3>
  A33  P5E_CPU0_PE4_RX_DN<2>  PETN5  @S9S_MB_2U_LIB.S9S_MB_2U(SCH_1):P5E_CPU0_PE4_RX_DN<2>
  A37  P5E_CPU0_PE4_RX_DN<1>  PETP6  @S9S_MB_2U_LIB.S9S_MB_2U(SCH_1):P5E_CPU0_PE4_RX_DN<1>
  A39  P5E_CPU0_PE4_RX_DN<0>  PETN7  @S9S_MB_2U_LIB.S9S_MB_2U(SCH_1):P5E_CPU0_PE4_RX_DN<0>
  B11  P3V3_AUX       3_3VAUX  @S9S_MB_2U_LIB.S9S_MB_2U(SCH_1):P3V3_AUX
  A42  P3V3             RFU  @S9S_MB_2U_LIB.S9S_MB_2U(SCH_1):P3V3
   B6  P12V_REAR_CPU  12VB6  @S9S_MB_2U_LIB.S9S_MB_2U(SCH_1):P12V_REAR_CPU
   B5  P12V_REAR_CPU  12VB5  @S9S_MB_2U_LIB.S9S_MB_2U(SCH_1):P12V_REAR_CPU
   B4  P12V_REAR_CPU  12VB4  @S9S_MB_2U_LIB.S9S_MB_2U(SCH_1):P12V_REAR_CPU
   B3  P12V_REAR_CPU  12VB3  @S9S_MB_2U_LIB.S9S_MB_2U(SCH_1):P12V_REAR_CPU
   B2  P12V_REAR_CPU  12VB2  @S9S_MB_2U_LIB.S9S_MB_2U(SCH_1):P12V_REAR_CPU
   B1  P12V_REAR_CPU  12VB1  @S9S_MB_2U_LIB.S9S_MB_2U(SCH_1):P12V_REAR_CPU
  B41  GND            GNDB41  @S9S_MB_2U_LIB.S9S_MB_2U(SCH_1):GND
  B38  GND            GNDB38  @S9S_MB_2U_LIB.S9S_MB_2U(SCH_1):GND
  B35  GND            GNDB35  @S9S_MB_2U_LIB.S9S_MB_2U(SCH_1):GND
  B32  GND            GNDB32  @S9S_MB_2U_LIB.S9S_MB_2U(SCH_1):GND
  B29  GND            GNDB29  @S9S_MB_2U_LIB.S9S_MB_2U(SCH_1):GND
  B28  GND            GNDB28  @S9S_MB_2U_LIB.S9S_MB_2U(SCH_1):GND
  B25  GND            GNDB25  @S9S_MB_2U_LIB.S9S_MB_2U(SCH_1):GND
  B22  GND            GNDB22  @S9S_MB_2U_LIB.S9S_MB_2U(SCH_1):GND
  B19  GND            GNDB19  @S9S_MB_2U_LIB.S9S_MB_2U(SCH_1):GND
  B16  GND            GNDB16  @S9S_MB_2U_LIB.S9S_MB_2U(SCH_1):GND
  B13  GND            GNDB13  @S9S_MB_2U_LIB.S9S_MB_2U(SCH_1):GND
  A41  GND            GNDA41  @S9S_MB_2U_LIB.S9S_MB_2U(SCH_1):GND
  A38  GND            GNDA38  @S9S_MB_2U_LIB.S9S_MB_2U(SCH_1):GND
  A35  GND            GNDA35  @S9S_MB_2U_LIB.S9S_MB_2U(SCH_1):GND
  A32  GND            GNDA32  @S9S_MB_2U_LIB.S9S_MB_2U(SCH_1):GND
  A29  GND            GNDA29  @S9S_MB_2U_LIB.S9S_MB_2U(SCH_1):GND
  A28  GND            GNDA28  @S9S_MB_2U_LIB.S9S_MB_2U(SCH_1):GND
  A25  GND            GNDA25  @S9S_MB_2U_LIB.S9S_MB_2U(SCH_1):GND
  A22  GND            GNDA22  @S9S_MB_2U_LIB.S9S_MB_2U(SCH_1):GND
  A19  GND            GNDA19  @S9S_MB_2U_LIB.S9S_MB_2U(SCH_1):GND
  A16  GND            GNDA16  @S9S_MB_2U_LIB.S9S_MB_2U(SCH_1):GND
  A13  GND            GNDA13  @S9S_MB_2U_LIB.S9S_MB_2U(SCH_1):GND
   A6  GND            GNDA6  @S9S_MB_2U_LIB.S9S_MB_2U(SCH_1):GND
   A5  GND            GNDA5  @S9S_MB_2U_LIB.S9S_MB_2U(SCH_1):GND
   A4  GND            GNDA4  @S9S_MB_2U_LIB.S9S_MB_2U(SCH_1):GND
   A3  GND            GNDA3  @S9S_MB_2U_LIB.S9S_MB_2U(SCH_1):GND
   A2  GND            GNDA2  @S9S_MB_2U_LIB.S9S_MB_2U(SCH_1):GND
   A1  GND            GNDA1  @S9S_MB_2U_LIB.S9S_MB_2U(SCH_1):GND
   G5  GND               G5  @S9S_MB_2U_LIB.S9S_MB_2U(SCH_1):GND
   G4  GND               G4  @S9S_MB_2U_LIB.S9S_MB_2U(SCH_1):GND
   G3  GND               G3  @S9S_MB_2U_LIB.S9S_MB_2U(SCH_1):GND
   G2  GND               G2  @S9S_MB_2U_LIB.S9S_MB_2U(SCH_1):GND
   G1  GND               G1  @S9S_MB_2U_LIB.S9S_MB_2U(SCH_1):GND
  B42  FM_PCIE_EDSFF2A_PRSNT_1_N  PRSNT1_N  @S9S_MB_2U_LIB.S9S_MB_2U(SCH_1):FM_PCIE_EDSFF2A_PRSNT_1_N
   B7  FM_EDSFF2A_TYPE_ID    MFG  @S9S_MB_2U_LIB.S9S_MB_2U(SCH_1):FM_EDSFF2A_TYPE_ID
   B8  FM_EDSFF2A_PWRBRK_N  RFUB8  @S9S_MB_2U_LIB.S9S_MB_2U(SCH_1):FM_EDSFF2A_PWRBRK_N
  B15  CLK_100M_EDSFF2A_DP  REFCLKP0  @S9S_MB_2U_LIB.S9S_MB_2U(SCH_1):CLK_100M_EDSFF2A_DP
  B14  CLK_100M_EDSFF2A_DN  REFCLKN0  @S9S_MB_2U_LIB.S9S_MB_2U(SCH_1):CLK_100M_EDSFF2A_DN

SCONN84_123318136  I43  J34    [SCONN84_123318136-SCONN84_1-23A]
   B9  NC             DUALPORTEN_N  NC
  A10  NC             LED_ACTIVITYA10  NC
  A15  NC             REFCLKP1  NC
  A14  NC             REFCLKN1  NC
   A8  SMB_EDSFF2B_3V3AUX_SDA_R  SMBDAT  @S9S_MB_2U_LIB.S9S_MB_2U(SCH_1):SMB_EDSFF2B_3V3AUX_SDA_R
   A7  SMB_EDSFF2B_3V3AUX_SCL_R  SMBCLK  @S9S_MB_2U_LIB.S9S_MB_2U(SCH_1):SMB_EDSFF2B_3V3AUX_SCL_R
   A9  RST_SMB_EDSFF2B_N  SMBRST_N  @S9S_MB_2U_LIB.S9S_MB_2U(SCH_1):RST_SMB_EDSFF2B_N
  B10  RST_PCIE_EDSFF2B_PERST_N  PERST0_N  @S9S_MB_2U_LIB.S9S_MB_2U(SCH_1):RST_PCIE_EDSFF2B_PERST_N
  A11  PU_EDSFF2B_PERST1_CLKREQ_N  PERST1_N_CLKREQ_N  @S9S_MB_2U_LIB.S9S_MB_2U(SCH_1):PU_EDSFF2B_PERST1_CLKREQ_N
  A12  PD_PCIE_EDSFF2B_PRSNT_0_N  PRSNT0_N  @S9S_MB_2U_LIB.S9S_MB_2U(SCH_1):PD_PCIE_EDSFF2B_PRSNT_0_N
  B12  PD_EDSFF2B_PWRDIS  PWRDIS  @S9S_MB_2U_LIB.S9S_MB_2U(SCH_1):PD_EDSFF2B_PWRDIS
  B36  P5E_CPU0_PE4_TX_C_DP<9>  PERN6  @S9S_MB_2U_LIB.S9S_MB_2U(SCH_1):P5E_CPU0_PE4_TX_C_DP<9>
  B39  P5E_CPU0_PE4_TX_C_DP<8>  PERN7  @S9S_MB_2U_LIB.S9S_MB_2U(SCH_1):P5E_CPU0_PE4_TX_C_DP<8>
  B17  P5E_CPU0_PE4_TX_C_DP<15>  PERN0  @S9S_MB_2U_LIB.S9S_MB_2U(SCH_1):P5E_CPU0_PE4_TX_C_DP<15>
  B20  P5E_CPU0_PE4_TX_C_DP<14>  PERN1  @S9S_MB_2U_LIB.S9S_MB_2U(SCH_1):P5E_CPU0_PE4_TX_C_DP<14>
  B23  P5E_CPU0_PE4_TX_C_DP<13>  PERN2  @S9S_MB_2U_LIB.S9S_MB_2U(SCH_1):P5E_CPU0_PE4_TX_C_DP<13>
  B26  P5E_CPU0_PE4_TX_C_DP<12>  PERN3  @S9S_MB_2U_LIB.S9S_MB_2U(SCH_1):P5E_CPU0_PE4_TX_C_DP<12>
  B30  P5E_CPU0_PE4_TX_C_DP<11>  PERN4  @S9S_MB_2U_LIB.S9S_MB_2U(SCH_1):P5E_CPU0_PE4_TX_C_DP<11>
  B33  P5E_CPU0_PE4_TX_C_DP<10>  PERN5  @S9S_MB_2U_LIB.S9S_MB_2U(SCH_1):P5E_CPU0_PE4_TX_C_DP<10>
  B37  P5E_CPU0_PE4_TX_C_DN<9>  PERP6  @S9S_MB_2U_LIB.S9S_MB_2U(SCH_1):P5E_CPU0_PE4_TX_C_DN<9>
  B40  P5E_CPU0_PE4_TX_C_DN<8>  PERP7  @S9S_MB_2U_LIB.S9S_MB_2U(SCH_1):P5E_CPU0_PE4_TX_C_DN<8>
  B18  P5E_CPU0_PE4_TX_C_DN<15>  PERP0  @S9S_MB_2U_LIB.S9S_MB_2U(SCH_1):P5E_CPU0_PE4_TX_C_DN<15>
  B21  P5E_CPU0_PE4_TX_C_DN<14>  PERP1  @S9S_MB_2U_LIB.S9S_MB_2U(SCH_1):P5E_CPU0_PE4_TX_C_DN<14>
  B24  P5E_CPU0_PE4_TX_C_DN<13>  PERP2  @S9S_MB_2U_LIB.S9S_MB_2U(SCH_1):P5E_CPU0_PE4_TX_C_DN<13>
  B27  P5E_CPU0_PE4_TX_C_DN<12>  PERP3  @S9S_MB_2U_LIB.S9S_MB_2U(SCH_1):P5E_CPU0_PE4_TX_C_DN<12>
  B31  P5E_CPU0_PE4_TX_C_DN<11>  PERP4  @S9S_MB_2U_LIB.S9S_MB_2U(SCH_1):P5E_CPU0_PE4_TX_C_DN<11>
  B34  P5E_CPU0_PE4_TX_C_DN<10>  PERP5  @S9S_MB_2U_LIB.S9S_MB_2U(SCH_1):P5E_CPU0_PE4_TX_C_DN<10>
  A37  P5E_CPU0_PE4_RX_DP<9>  PETP6  @S9S_MB_2U_LIB.S9S_MB_2U(SCH_1):P5E_CPU0_PE4_RX_DP<9>
  A40  P5E_CPU0_PE4_RX_DP<8>  PETP7  @S9S_MB_2U_LIB.S9S_MB_2U(SCH_1):P5E_CPU0_PE4_RX_DP<8>
  A18  P5E_CPU0_PE4_RX_DP<15>  PETP0  @S9S_MB_2U_LIB.S9S_MB_2U(SCH_1):P5E_CPU0_PE4_RX_DP<15>
  A21  P5E_CPU0_PE4_RX_DP<14>  PETP1  @S9S_MB_2U_LIB.S9S_MB_2U(SCH_1):P5E_CPU0_PE4_RX_DP<14>
  A24  P5E_CPU0_PE4_RX_DP<13>  PETP2  @S9S_MB_2U_LIB.S9S_MB_2U(SCH_1):P5E_CPU0_PE4_RX_DP<13>
  A27  P5E_CPU0_PE4_RX_DP<12>  PETP3  @S9S_MB_2U_LIB.S9S_MB_2U(SCH_1):P5E_CPU0_PE4_RX_DP<12>
  A31  P5E_CPU0_PE4_RX_DP<11>  PETP4  @S9S_MB_2U_LIB.S9S_MB_2U(SCH_1):P5E_CPU0_PE4_RX_DP<11>
  A34  P5E_CPU0_PE4_RX_DP<10>  PETP5  @S9S_MB_2U_LIB.S9S_MB_2U(SCH_1):P5E_CPU0_PE4_RX_DP<10>
  A36  P5E_CPU0_PE4_RX_DN<9>  PETN6  @S9S_MB_2U_LIB.S9S_MB_2U(SCH_1):P5E_CPU0_PE4_RX_DN<9>
  A39  P5E_CPU0_PE4_RX_DN<8>  PETN7  @S9S_MB_2U_LIB.S9S_MB_2U(SCH_1):P5E_CPU0_PE4_RX_DN<8>
  A17  P5E_CPU0_PE4_RX_DN<15>  PETN0  @S9S_MB_2U_LIB.S9S_MB_2U(SCH_1):P5E_CPU0_PE4_RX_DN<15>
  A20  P5E_CPU0_PE4_RX_DN<14>  PETN1  @S9S_MB_2U_LIB.S9S_MB_2U(SCH_1):P5E_CPU0_PE4_RX_DN<14>
  A23  P5E_CPU0_PE4_RX_DN<13>  PETN2  @S9S_MB_2U_LIB.S9S_MB_2U(SCH_1):P5E_CPU0_PE4_RX_DN<13>
  A26  P5E_CPU0_PE4_RX_DN<12>  PETN3  @S9S_MB_2U_LIB.S9S_MB_2U(SCH_1):P5E_CPU0_PE4_RX_DN<12>
  A30  P5E_CPU0_PE4_RX_DN<11>  PETN4  @S9S_MB_2U_LIB.S9S_MB_2U(SCH_1):P5E_CPU0_PE4_RX_DN<11>
  A33  P5E_CPU0_PE4_RX_DN<10>  PETN5  @S9S_MB_2U_LIB.S9S_MB_2U(SCH_1):P5E_CPU0_PE4_RX_DN<10>
  B11  P3V3_AUX       3_3VAUX  @S9S_MB_2U_LIB.S9S_MB_2U(SCH_1):P3V3_AUX
  A42  P3V3             RFU  @S9S_MB_2U_LIB.S9S_MB_2U(SCH_1):P3V3
   B6  P12V_REAR_CPU  12VB6  @S9S_MB_2U_LIB.S9S_MB_2U(SCH_1):P12V_REAR_CPU
   B5  P12V_REAR_CPU  12VB5  @S9S_MB_2U_LIB.S9S_MB_2U(SCH_1):P12V_REAR_CPU
   B4  P12V_REAR_CPU  12VB4  @S9S_MB_2U_LIB.S9S_MB_2U(SCH_1):P12V_REAR_CPU
   B3  P12V_REAR_CPU  12VB3  @S9S_MB_2U_LIB.S9S_MB_2U(SCH_1):P12V_REAR_CPU
   B2  P12V_REAR_CPU  12VB2  @S9S_MB_2U_LIB.S9S_MB_2U(SCH_1):P12V_REAR_CPU
   B1  P12V_REAR_CPU  12VB1  @S9S_MB_2U_LIB.S9S_MB_2U(SCH_1):P12V_REAR_CPU
  B41  GND            GNDB41  @S9S_MB_2U_LIB.S9S_MB_2U(SCH_1):GND
  B38  GND            GNDB38  @S9S_MB_2U_LIB.S9S_MB_2U(SCH_1):GND
  B35  GND            GNDB35  @S9S_MB_2U_LIB.S9S_MB_2U(SCH_1):GND
  B32  GND            GNDB32  @S9S_MB_2U_LIB.S9S_MB_2U(SCH_1):GND
  B29  GND            GNDB29  @S9S_MB_2U_LIB.S9S_MB_2U(SCH_1):GND
  B28  GND            GNDB28  @S9S_MB_2U_LIB.S9S_MB_2U(SCH_1):GND
  B25  GND            GNDB25  @S9S_MB_2U_LIB.S9S_MB_2U(SCH_1):GND
  B22  GND            GNDB22  @S9S_MB_2U_LIB.S9S_MB_2U(SCH_1):GND
  B19  GND            GNDB19  @S9S_MB_2U_LIB.S9S_MB_2U(SCH_1):GND
  B16  GND            GNDB16  @S9S_MB_2U_LIB.S9S_MB_2U(SCH_1):GND
  B13  GND            GNDB13  @S9S_MB_2U_LIB.S9S_MB_2U(SCH_1):GND
  A41  GND            GNDA41  @S9S_MB_2U_LIB.S9S_MB_2U(SCH_1):GND
  A38  GND            GNDA38  @S9S_MB_2U_LIB.S9S_MB_2U(SCH_1):GND
  A35  GND            GNDA35  @S9S_MB_2U_LIB.S9S_MB_2U(SCH_1):GND
  A32  GND            GNDA32  @S9S_MB_2U_LIB.S9S_MB_2U(SCH_1):GND
  A29  GND            GNDA29  @S9S_MB_2U_LIB.S9S_MB_2U(SCH_1):GND
  A28  GND            GNDA28  @S9S_MB_2U_LIB.S9S_MB_2U(SCH_1):GND
  A25  GND            GNDA25  @S9S_MB_2U_LIB.S9S_MB_2U(SCH_1):GND
  A22  GND            GNDA22  @S9S_MB_2U_LIB.S9S_MB_2U(SCH_1):GND
  A19  GND            GNDA19  @S9S_MB_2U_LIB.S9S_MB_2U(SCH_1):GND
  A16  GND            GNDA16  @S9S_MB_2U_LIB.S9S_MB_2U(SCH_1):GND
  A13  GND            GNDA13  @S9S_MB_2U_LIB.S9S_MB_2U(SCH_1):GND
   A6  GND            GNDA6  @S9S_MB_2U_LIB.S9S_MB_2U(SCH_1):GND
   A5  GND            GNDA5  @S9S_MB_2U_LIB.S9S_MB_2U(SCH_1):GND
   A4  GND            GNDA4  @S9S_MB_2U_LIB.S9S_MB_2U(SCH_1):GND
   A3  GND            GNDA3  @S9S_MB_2U_LIB.S9S_MB_2U(SCH_1):GND
   A2  GND            GNDA2  @S9S_MB_2U_LIB.S9S_MB_2U(SCH_1):GND
   A1  GND            GNDA1  @S9S_MB_2U_LIB.S9S_MB_2U(SCH_1):GND
   G5  GND               G5  @S9S_MB_2U_LIB.S9S_MB_2U(SCH_1):GND
   G4  GND               G4  @S9S_MB_2U_LIB.S9S_MB_2U(SCH_1):GND
   G3  GND               G3  @S9S_MB_2U_LIB.S9S_MB_2U(SCH_1):GND
   G2  GND               G2  @S9S_MB_2U_LIB.S9S_MB_2U(SCH_1):GND
   G1  GND               G1  @S9S_MB_2U_LIB.S9S_MB_2U(SCH_1):GND
  B42  FM_PCIE_EDSFF2B_PRSNT_1_N  PRSNT1_N  @S9S_MB_2U_LIB.S9S_MB_2U(SCH_1):FM_PCIE_EDSFF2B_PRSNT_1_N
   B7  FM_EDSFF2B_TYPE_ID    MFG  @S9S_MB_2U_LIB.S9S_MB_2U(SCH_1):FM_EDSFF2B_TYPE_ID
   B8  FM_EDSFF2B_PWRBRK_N  RFUB8  @S9S_MB_2U_LIB.S9S_MB_2U(SCH_1):FM_EDSFF2B_PWRBRK_N
  B15  CLK_100M_EDSFF2B_DP  REFCLKP0  @S9S_MB_2U_LIB.S9S_MB_2U(SCH_1):CLK_100M_EDSFF2B_DP
  B14  CLK_100M_EDSFF2B_DN  REFCLKN0  @S9S_MB_2U_LIB.S9S_MB_2U(SCH_1):CLK_100M_EDSFF2B_DN

SCONN140_G64V3431BHR  I64  J35    [SCONN140_G64V3431BHR-SCONN140_B]
  A18  NC             SIGNAL_A18  NC
  A12  SMB_EDSFF3_3V3AUX_SDA_R  SIGNAL_A12  @S9S_MB_2U_LIB.S9S_MB_2U(SCH_1):SMB_EDSFF3_3V3AUX_SDA_R
  A11  SMB_EDSFF3_3V3AUX_SCL_R  SIGNAL_A11  @S9S_MB_2U_LIB.S9S_MB_2U(SCH_1):SMB_EDSFF3_3V3AUX_SCL_R
   A9  RST_PCIE_EDSFF3_PERST_N  SIGNAL_A9  @S9S_MB_2U_LIB.S9S_MB_2U(SCH_1):RST_PCIE_EDSFF3_PERST_N
  B50  P5E_CPU1_PE3_TX_C_DP<9>  SIGNAL_B50  @S9S_MB_2U_LIB.S9S_MB_2U(SCH_1):P5E_CPU1_PE3_TX_C_DP<9>
  B47  P5E_CPU1_PE3_TX_C_DP<8>  SIGNAL_B47  @S9S_MB_2U_LIB.S9S_MB_2U(SCH_1):P5E_CPU1_PE3_TX_C_DP<8>
  B44  P5E_CPU1_PE3_TX_C_DP<7>  SIGNAL_B44  @S9S_MB_2U_LIB.S9S_MB_2U(SCH_1):P5E_CPU1_PE3_TX_C_DP<7>
  B39  P5E_CPU1_PE3_TX_C_DP<6>  SIGNAL_B39  @S9S_MB_2U_LIB.S9S_MB_2U(SCH_1):P5E_CPU1_PE3_TX_C_DP<6>
  B36  P5E_CPU1_PE3_TX_C_DP<5>  SIGNAL_B36  @S9S_MB_2U_LIB.S9S_MB_2U(SCH_1):P5E_CPU1_PE3_TX_C_DP<5>
  B33  P5E_CPU1_PE3_TX_C_DP<4>  SIGNAL_B33  @S9S_MB_2U_LIB.S9S_MB_2U(SCH_1):P5E_CPU1_PE3_TX_C_DP<4>
  B30  P5E_CPU1_PE3_TX_C_DP<3>  SIGNAL_B30  @S9S_MB_2U_LIB.S9S_MB_2U(SCH_1):P5E_CPU1_PE3_TX_C_DP<3>
  B26  P5E_CPU1_PE3_TX_C_DP<2>  SIGNAL_B26  @S9S_MB_2U_LIB.S9S_MB_2U(SCH_1):P5E_CPU1_PE3_TX_C_DP<2>
  B23  P5E_CPU1_PE3_TX_C_DP<1>  SIGNAL_B23  @S9S_MB_2U_LIB.S9S_MB_2U(SCH_1):P5E_CPU1_PE3_TX_C_DP<1>
  B68  P5E_CPU1_PE3_TX_C_DP<15>  SIGNAL_B68  @S9S_MB_2U_LIB.S9S_MB_2U(SCH_1):P5E_CPU1_PE3_TX_C_DP<15>
  B65  P5E_CPU1_PE3_TX_C_DP<14>  SIGNAL_B65  @S9S_MB_2U_LIB.S9S_MB_2U(SCH_1):P5E_CPU1_PE3_TX_C_DP<14>
  B62  P5E_CPU1_PE3_TX_C_DP<13>  SIGNAL_B62  @S9S_MB_2U_LIB.S9S_MB_2U(SCH_1):P5E_CPU1_PE3_TX_C_DP<13>
  B59  P5E_CPU1_PE3_TX_C_DP<12>  SIGNAL_B59  @S9S_MB_2U_LIB.S9S_MB_2U(SCH_1):P5E_CPU1_PE3_TX_C_DP<12>
  B56  P5E_CPU1_PE3_TX_C_DP<11>  SIGNAL_B56  @S9S_MB_2U_LIB.S9S_MB_2U(SCH_1):P5E_CPU1_PE3_TX_C_DP<11>
  B53  P5E_CPU1_PE3_TX_C_DP<10>  SIGNAL_B53  @S9S_MB_2U_LIB.S9S_MB_2U(SCH_1):P5E_CPU1_PE3_TX_C_DP<10>
  B21  P5E_CPU1_PE3_TX_C_DP<0>  SIGNAL_B21  @S9S_MB_2U_LIB.S9S_MB_2U(SCH_1):P5E_CPU1_PE3_TX_C_DP<0>
  B51  P5E_CPU1_PE3_TX_C_DN<9>  SIGNAL_B51  @S9S_MB_2U_LIB.S9S_MB_2U(SCH_1):P5E_CPU1_PE3_TX_C_DN<9>
  B48  P5E_CPU1_PE3_TX_C_DN<8>  SIGNAL_B48  @S9S_MB_2U_LIB.S9S_MB_2U(SCH_1):P5E_CPU1_PE3_TX_C_DN<8>
  B45  P5E_CPU1_PE3_TX_C_DN<7>  SIGNAL_B45  @S9S_MB_2U_LIB.S9S_MB_2U(SCH_1):P5E_CPU1_PE3_TX_C_DN<7>
  B40  P5E_CPU1_PE3_TX_C_DN<6>  SIGNAL_B40  @S9S_MB_2U_LIB.S9S_MB_2U(SCH_1):P5E_CPU1_PE3_TX_C_DN<6>
  B37  P5E_CPU1_PE3_TX_C_DN<5>  SIGNAL_B37  @S9S_MB_2U_LIB.S9S_MB_2U(SCH_1):P5E_CPU1_PE3_TX_C_DN<5>
  B34  P5E_CPU1_PE3_TX_C_DN<4>  SIGNAL_B34  @S9S_MB_2U_LIB.S9S_MB_2U(SCH_1):P5E_CPU1_PE3_TX_C_DN<4>
  B31  P5E_CPU1_PE3_TX_C_DN<3>  SIGNAL_B31  @S9S_MB_2U_LIB.S9S_MB_2U(SCH_1):P5E_CPU1_PE3_TX_C_DN<3>
  B27  P5E_CPU1_PE3_TX_C_DN<2>  SIGNAL_B27  @S9S_MB_2U_LIB.S9S_MB_2U(SCH_1):P5E_CPU1_PE3_TX_C_DN<2>
  B24  P5E_CPU1_PE3_TX_C_DN<1>  SIGNAL_B24  @S9S_MB_2U_LIB.S9S_MB_2U(SCH_1):P5E_CPU1_PE3_TX_C_DN<1>
  B69  P5E_CPU1_PE3_TX_C_DN<15>  SIGNAL_B69  @S9S_MB_2U_LIB.S9S_MB_2U(SCH_1):P5E_CPU1_PE3_TX_C_DN<15>
  B66  P5E_CPU1_PE3_TX_C_DN<14>  SIGNAL_B66  @S9S_MB_2U_LIB.S9S_MB_2U(SCH_1):P5E_CPU1_PE3_TX_C_DN<14>
  B63  P5E_CPU1_PE3_TX_C_DN<13>  SIGNAL_B63  @S9S_MB_2U_LIB.S9S_MB_2U(SCH_1):P5E_CPU1_PE3_TX_C_DN<13>
  B60  P5E_CPU1_PE3_TX_C_DN<12>  SIGNAL_B60  @S9S_MB_2U_LIB.S9S_MB_2U(SCH_1):P5E_CPU1_PE3_TX_C_DN<12>
  B57  P5E_CPU1_PE3_TX_C_DN<11>  SIGNAL_B57  @S9S_MB_2U_LIB.S9S_MB_2U(SCH_1):P5E_CPU1_PE3_TX_C_DN<11>
  B54  P5E_CPU1_PE3_TX_C_DN<10>  SIGNAL_B54  @S9S_MB_2U_LIB.S9S_MB_2U(SCH_1):P5E_CPU1_PE3_TX_C_DN<10>
  B20  P5E_CPU1_PE3_TX_C_DN<0>  SIGNAL_B20  @S9S_MB_2U_LIB.S9S_MB_2U(SCH_1):P5E_CPU1_PE3_TX_C_DN<0>
  A50  P5E_CPU1_PE3_RX_DP<9>  SIGNAL_A50  @S9S_MB_2U_LIB.S9S_MB_2U(SCH_1):P5E_CPU1_PE3_RX_DP<9>
  A48  P5E_CPU1_PE3_RX_DP<8>  SIGNAL_A48  @S9S_MB_2U_LIB.S9S_MB_2U(SCH_1):P5E_CPU1_PE3_RX_DP<8>
  A45  P5E_CPU1_PE3_RX_DP<7>  SIGNAL_A45  @S9S_MB_2U_LIB.S9S_MB_2U(SCH_1):P5E_CPU1_PE3_RX_DP<7>
  A39  P5E_CPU1_PE3_RX_DP<6>  SIGNAL_A39  @S9S_MB_2U_LIB.S9S_MB_2U(SCH_1):P5E_CPU1_PE3_RX_DP<6>
  A37  P5E_CPU1_PE3_RX_DP<5>  SIGNAL_A37  @S9S_MB_2U_LIB.S9S_MB_2U(SCH_1):P5E_CPU1_PE3_RX_DP<5>
  A33  P5E_CPU1_PE3_RX_DP<4>  SIGNAL_A33  @S9S_MB_2U_LIB.S9S_MB_2U(SCH_1):P5E_CPU1_PE3_RX_DP<4>
  A30  P5E_CPU1_PE3_RX_DP<3>  SIGNAL_A30  @S9S_MB_2U_LIB.S9S_MB_2U(SCH_1):P5E_CPU1_PE3_RX_DP<3>
  A27  P5E_CPU1_PE3_RX_DP<2>  SIGNAL_A27  @S9S_MB_2U_LIB.S9S_MB_2U(SCH_1):P5E_CPU1_PE3_RX_DP<2>
  A23  P5E_CPU1_PE3_RX_DP<1>  SIGNAL_A23  @S9S_MB_2U_LIB.S9S_MB_2U(SCH_1):P5E_CPU1_PE3_RX_DP<1>
  A69  P5E_CPU1_PE3_RX_DP<15>  SIGNAL_A69  @S9S_MB_2U_LIB.S9S_MB_2U(SCH_1):P5E_CPU1_PE3_RX_DP<15>
  A65  P5E_CPU1_PE3_RX_DP<14>  SIGNAL_A65  @S9S_MB_2U_LIB.S9S_MB_2U(SCH_1):P5E_CPU1_PE3_RX_DP<14>
  A63  P5E_CPU1_PE3_RX_DP<13>  SIGNAL_A63  @S9S_MB_2U_LIB.S9S_MB_2U(SCH_1):P5E_CPU1_PE3_RX_DP<13>
  A59  P5E_CPU1_PE3_RX_DP<12>  SIGNAL_A59  @S9S_MB_2U_LIB.S9S_MB_2U(SCH_1):P5E_CPU1_PE3_RX_DP<12>
  A56  P5E_CPU1_PE3_RX_DP<11>  SIGNAL_A56  @S9S_MB_2U_LIB.S9S_MB_2U(SCH_1):P5E_CPU1_PE3_RX_DP<11>
  A54  P5E_CPU1_PE3_RX_DP<10>  SIGNAL_A54  @S9S_MB_2U_LIB.S9S_MB_2U(SCH_1):P5E_CPU1_PE3_RX_DP<10>
  A20  P5E_CPU1_PE3_RX_DP<0>  SIGNAL_A20  @S9S_MB_2U_LIB.S9S_MB_2U(SCH_1):P5E_CPU1_PE3_RX_DP<0>
  A51  P5E_CPU1_PE3_RX_DN<9>  SIGNAL_A51  @S9S_MB_2U_LIB.S9S_MB_2U(SCH_1):P5E_CPU1_PE3_RX_DN<9>
  A47  P5E_CPU1_PE3_RX_DN<8>  SIGNAL_A47  @S9S_MB_2U_LIB.S9S_MB_2U(SCH_1):P5E_CPU1_PE3_RX_DN<8>
  A44  P5E_CPU1_PE3_RX_DN<7>  SIGNAL_A44  @S9S_MB_2U_LIB.S9S_MB_2U(SCH_1):P5E_CPU1_PE3_RX_DN<7>
  A40  P5E_CPU1_PE3_RX_DN<6>  SIGNAL_A40  @S9S_MB_2U_LIB.S9S_MB_2U(SCH_1):P5E_CPU1_PE3_RX_DN<6>
  A36  P5E_CPU1_PE3_RX_DN<5>  SIGNAL_A36  @S9S_MB_2U_LIB.S9S_MB_2U(SCH_1):P5E_CPU1_PE3_RX_DN<5>
  A34  P5E_CPU1_PE3_RX_DN<4>  SIGNAL_A34  @S9S_MB_2U_LIB.S9S_MB_2U(SCH_1):P5E_CPU1_PE3_RX_DN<4>
  A31  P5E_CPU1_PE3_RX_DN<3>  SIGNAL_A31  @S9S_MB_2U_LIB.S9S_MB_2U(SCH_1):P5E_CPU1_PE3_RX_DN<3>
  A26  P5E_CPU1_PE3_RX_DN<2>  SIGNAL_A26  @S9S_MB_2U_LIB.S9S_MB_2U(SCH_1):P5E_CPU1_PE3_RX_DN<2>
  A24  P5E_CPU1_PE3_RX_DN<1>  SIGNAL_A24  @S9S_MB_2U_LIB.S9S_MB_2U(SCH_1):P5E_CPU1_PE3_RX_DN<1>
  A68  P5E_CPU1_PE3_RX_DN<15>  SIGNAL_A68  @S9S_MB_2U_LIB.S9S_MB_2U(SCH_1):P5E_CPU1_PE3_RX_DN<15>
  A66  P5E_CPU1_PE3_RX_DN<14>  SIGNAL_A66  @S9S_MB_2U_LIB.S9S_MB_2U(SCH_1):P5E_CPU1_PE3_RX_DN<14>
  A62  P5E_CPU1_PE3_RX_DN<13>  SIGNAL_A62  @S9S_MB_2U_LIB.S9S_MB_2U(SCH_1):P5E_CPU1_PE3_RX_DN<13>
  A60  P5E_CPU1_PE3_RX_DN<12>  SIGNAL_A60  @S9S_MB_2U_LIB.S9S_MB_2U(SCH_1):P5E_CPU1_PE3_RX_DN<12>
  A57  P5E_CPU1_PE3_RX_DN<11>  SIGNAL_A57  @S9S_MB_2U_LIB.S9S_MB_2U(SCH_1):P5E_CPU1_PE3_RX_DN<11>
  A53  P5E_CPU1_PE3_RX_DN<10>  SIGNAL_A53  @S9S_MB_2U_LIB.S9S_MB_2U(SCH_1):P5E_CPU1_PE3_RX_DN<10>
  A21  P5E_CPU1_PE3_RX_DN<0>  SIGNAL_A21  @S9S_MB_2U_LIB.S9S_MB_2U(SCH_1):P5E_CPU1_PE3_RX_DN<0>
  B15  P3V3_AUX       SIGNAL_B15  @S9S_MB_2U_LIB.S9S_MB_2U(SCH_1):P3V3_AUX
   A3  P3V3           SIGNAL_A3  @S9S_MB_2U_LIB.S9S_MB_2U(SCH_1):P3V3
   A4  P3V3           GND_A4  @S9S_MB_2U_LIB.S9S_MB_2U(SCH_1):P3V3
  B12  P12V_REAR_CPU  SIGNAL_B12  @S9S_MB_2U_LIB.S9S_MB_2U(SCH_1):P12V_REAR_CPU
  B11  P12V_REAR_CPU  SIGNAL_B11  @S9S_MB_2U_LIB.S9S_MB_2U(SCH_1):P12V_REAR_CPU
   B9  P12V_REAR_CPU  SIGNAL_B9  @S9S_MB_2U_LIB.S9S_MB_2U(SCH_1):P12V_REAR_CPU
   B8  P12V_REAR_CPU  SIGNAL_B8  @S9S_MB_2U_LIB.S9S_MB_2U(SCH_1):P12V_REAR_CPU
   B5  P12V_REAR_CPU  SIGNAL_B5  @S9S_MB_2U_LIB.S9S_MB_2U(SCH_1):P12V_REAR_CPU
   B3  P12V_REAR_CPU  SIGNAL_B3  @S9S_MB_2U_LIB.S9S_MB_2U(SCH_1):P12V_REAR_CPU
   B2  P12V_REAR_CPU  SIGNAL_B2  @S9S_MB_2U_LIB.S9S_MB_2U(SCH_1):P12V_REAR_CPU
  B10  P12V_REAR_CPU  GND_B10  @S9S_MB_2U_LIB.S9S_MB_2U(SCH_1):P12V_REAR_CPU
   B4  P12V_REAR_CPU  GND_B4  @S9S_MB_2U_LIB.S9S_MB_2U(SCH_1):P12V_REAR_CPU
   B1  P12V_REAR_CPU  GND_B1  @S9S_MB_2U_LIB.S9S_MB_2U(SCH_1):P12V_REAR_CPU
  A42  IRQ_LVC3_WAKE_EDSFF3_N  GND_A42  @S9S_MB_2U_LIB.S9S_MB_2U(SCH_1):IRQ_LVC3_WAKE_EDSFF3_N
   B6  GND            SIGNAL_B6  @S9S_MB_2U_LIB.S9S_MB_2U(SCH_1):GND
   A8  GND            SIGNAL_A8  @S9S_MB_2U_LIB.S9S_MB_2U(SCH_1):GND
   A6  GND            SIGNAL_A6  @S9S_MB_2U_LIB.S9S_MB_2U(SCH_1):GND
   A5  GND            SIGNAL_A5  @S9S_MB_2U_LIB.S9S_MB_2U(SCH_1):GND
   A2  GND            SIGNAL_A2  @S9S_MB_2U_LIB.S9S_MB_2U(SCH_1):GND
  B70  GND            GND_B70  @S9S_MB_2U_LIB.S9S_MB_2U(SCH_1):GND
  B67  GND            GND_B67  @S9S_MB_2U_LIB.S9S_MB_2U(SCH_1):GND
  B64  GND            GND_B64  @S9S_MB_2U_LIB.S9S_MB_2U(SCH_1):GND
  B61  GND            GND_B61  @S9S_MB_2U_LIB.S9S_MB_2U(SCH_1):GND
  B58  GND            GND_B58  @S9S_MB_2U_LIB.S9S_MB_2U(SCH_1):GND
  B55  GND            GND_B55  @S9S_MB_2U_LIB.S9S_MB_2U(SCH_1):GND
  B52  GND            GND_B52  @S9S_MB_2U_LIB.S9S_MB_2U(SCH_1):GND
  B49  GND            GND_B49  @S9S_MB_2U_LIB.S9S_MB_2U(SCH_1):GND
  B46  GND            GND_B46  @S9S_MB_2U_LIB.S9S_MB_2U(SCH_1):GND
  B43  GND            GND_B43  @S9S_MB_2U_LIB.S9S_MB_2U(SCH_1):GND
  B41  GND            GND_B41  @S9S_MB_2U_LIB.S9S_MB_2U(SCH_1):GND
  B38  GND            GND_B38  @S9S_MB_2U_LIB.S9S_MB_2U(SCH_1):GND
  B35  GND            GND_B35  @S9S_MB_2U_LIB.S9S_MB_2U(SCH_1):GND
  B32  GND            GND_B32  @S9S_MB_2U_LIB.S9S_MB_2U(SCH_1):GND
  B29  GND            GND_B29  @S9S_MB_2U_LIB.S9S_MB_2U(SCH_1):GND
  B28  GND            GND_B28  @S9S_MB_2U_LIB.S9S_MB_2U(SCH_1):GND
  B25  GND            GND_B25  @S9S_MB_2U_LIB.S9S_MB_2U(SCH_1):GND
  B22  GND            GND_B22  @S9S_MB_2U_LIB.S9S_MB_2U(SCH_1):GND
  B19  GND            GND_B19  @S9S_MB_2U_LIB.S9S_MB_2U(SCH_1):GND
  B16  GND            GND_B16  @S9S_MB_2U_LIB.S9S_MB_2U(SCH_1):GND
  B13  GND            GND_B13  @S9S_MB_2U_LIB.S9S_MB_2U(SCH_1):GND
   B7  GND            GND_B7  @S9S_MB_2U_LIB.S9S_MB_2U(SCH_1):GND
  A70  GND            GND_A70  @S9S_MB_2U_LIB.S9S_MB_2U(SCH_1):GND
  A67  GND            GND_A67  @S9S_MB_2U_LIB.S9S_MB_2U(SCH_1):GND
  A64  GND            GND_A64  @S9S_MB_2U_LIB.S9S_MB_2U(SCH_1):GND
  A61  GND            GND_A61  @S9S_MB_2U_LIB.S9S_MB_2U(SCH_1):GND
  A58  GND            GND_A58  @S9S_MB_2U_LIB.S9S_MB_2U(SCH_1):GND
  A55  GND            GND_A55  @S9S_MB_2U_LIB.S9S_MB_2U(SCH_1):GND
  A52  GND            GND_A52  @S9S_MB_2U_LIB.S9S_MB_2U(SCH_1):GND
  A49  GND            GND_A49  @S9S_MB_2U_LIB.S9S_MB_2U(SCH_1):GND
  A46  GND            GND_A46  @S9S_MB_2U_LIB.S9S_MB_2U(SCH_1):GND
  A43  GND            GND_A43  @S9S_MB_2U_LIB.S9S_MB_2U(SCH_1):GND
  A41  GND            GND_A41  @S9S_MB_2U_LIB.S9S_MB_2U(SCH_1):GND
  A38  GND            GND_A38  @S9S_MB_2U_LIB.S9S_MB_2U(SCH_1):GND
  A35  GND            GND_A35  @S9S_MB_2U_LIB.S9S_MB_2U(SCH_1):GND
  A32  GND            GND_A32  @S9S_MB_2U_LIB.S9S_MB_2U(SCH_1):GND
  A29  GND            GND_A29  @S9S_MB_2U_LIB.S9S_MB_2U(SCH_1):GND
  A28  GND            GND_A28  @S9S_MB_2U_LIB.S9S_MB_2U(SCH_1):GND
  A25  GND            GND_A25  @S9S_MB_2U_LIB.S9S_MB_2U(SCH_1):GND
  A22  GND            GND_A22  @S9S_MB_2U_LIB.S9S_MB_2U(SCH_1):GND
  A19  GND            GND_A19  @S9S_MB_2U_LIB.S9S_MB_2U(SCH_1):GND
  A16  GND            GND_A16  @S9S_MB_2U_LIB.S9S_MB_2U(SCH_1):GND
  A13  GND            GND_A13  @S9S_MB_2U_LIB.S9S_MB_2U(SCH_1):GND
  A10  GND            GND_A10  @S9S_MB_2U_LIB.S9S_MB_2U(SCH_1):GND
   A7  GND            GND_A7  @S9S_MB_2U_LIB.S9S_MB_2U(SCH_1):GND
   G8  GND               G8  @S9S_MB_2U_LIB.S9S_MB_2U(SCH_1):GND
   G7  GND               G7  @S9S_MB_2U_LIB.S9S_MB_2U(SCH_1):GND
   G6  GND               G6  @S9S_MB_2U_LIB.S9S_MB_2U(SCH_1):GND
   G5  GND               G5  @S9S_MB_2U_LIB.S9S_MB_2U(SCH_1):GND
   G4  GND               G4  @S9S_MB_2U_LIB.S9S_MB_2U(SCH_1):GND
   G3  GND               G3  @S9S_MB_2U_LIB.S9S_MB_2U(SCH_1):GND
   G2  GND               G2  @S9S_MB_2U_LIB.S9S_MB_2U(SCH_1):GND
   G1  GND               G1  @S9S_MB_2U_LIB.S9S_MB_2U(SCH_1):GND
  B42  FM_PCIE_EDSFF3_PRSNT_1_N  GND_B42  @S9S_MB_2U_LIB.S9S_MB_2U(SCH_1):FM_PCIE_EDSFF3_PRSNT_1_N
  A17  FM_EDSFF3_TYPE_ID  SIGNAL_A17  @S9S_MB_2U_LIB.S9S_MB_2U(SCH_1):FM_EDSFF3_TYPE_ID
  B14  FM_EDSFF3_PWRBRK_N  SIGNAL_B14  @S9S_MB_2U_LIB.S9S_MB_2U(SCH_1):FM_EDSFF3_PWRBRK_N
  A15  EDSFF3_USB2_5_DP  SIGNAL_A15  @S9S_MB_2U_LIB.S9S_MB_2U(SCH_1):EDSFF3_USB2_5_DP
  A14  EDSFF3_USB2_5_DN  SIGNAL_A14  @S9S_MB_2U_LIB.S9S_MB_2U(SCH_1):EDSFF3_USB2_5_DN
   A1  EDSFF3_PRSNT_0_N  GND_A1  @S9S_MB_2U_LIB.S9S_MB_2U(SCH_1):EDSFF3_PRSNT_0_N
  B18  CLK_100M_EDSFF3_DP  SIGNAL_B18  @S9S_MB_2U_LIB.S9S_MB_2U(SCH_1):CLK_100M_EDSFF3_DP
  B17  CLK_100M_EDSFF3_DN  SIGNAL_B17  @S9S_MB_2U_LIB.S9S_MB_2U(SCH_1):CLK_100M_EDSFF3_DN

SCONN168_623403212  I86  J37    [SCONN168_623403212-SCONN168_6-A]
  B69  NC              RFU2  NC
  B68  NC              RFU1  NC
   A8  SMB_OCP_SFF_3V3AUX_R_SDA  SMDAT  @S9S_MB_2U_LIB.S9S_MB_2U(SCH_1):SMB_OCP_SFF_3V3AUX_R_SDA
   A7  SMB_OCP_SFF_3V3AUX_R_SCL  SMCLK  @S9S_MB_2U_LIB.S9S_MB_2U(SCH_1):SMB_OCP_SFF_3V3AUX_R_SCL
  OCP_B3  SGPIO_OCP_SFF_LD_N    LD#  @S9S_MB_2U_LIB.S9S_MB_2U(SCH_1):SGPIO_OCP_SFF_LD_N
  OCP_B5  SGPIO_OCP_SFF_DATAOUT_N  DATA_OUT  @S9S_MB_2U_LIB.S9S_MB_2U(SCH_1):SGPIO_OCP_SFF_DATAOUT_N
  OCP_B4  SGPIO_OCP_SFF_DATAIN_N  DATA_IN  @S9S_MB_2U_LIB.S9S_MB_2U(SCH_1):SGPIO_OCP_SFF_DATAIN_N
  OCP_B6  SGPIO_OCP_SFF_CLK_N    CLK  @S9S_MB_2U_LIB.S9S_MB_2U(SCH_1):SGPIO_OCP_SFF_CLK_N
  OCP_A2  RST_PERST3_OCP_SFF_N  PERST3#  @S9S_MB_2U_LIB.S9S_MB_2U(SCH_1):RST_PERST3_OCP_SFF_N
  OCP_A1  RST_PERST2_OCP_SFF_N  PERST2#  @S9S_MB_2U_LIB.S9S_MB_2U(SCH_1):RST_PERST2_OCP_SFF_N
  A11  RST_PERST1_OCP_SFF_N  PERST1#  @S9S_MB_2U_LIB.S9S_MB_2U(SCH_1):RST_PERST1_OCP_SFF_N
  B10  RST_PERST0_OCP_SFF_N  PERST0#  @S9S_MB_2U_LIB.S9S_MB_2U(SCH_1):RST_PERST0_OCP_SFF_N
   A9  PU_RST_SMB_OCP_SFF_N  SMRST#  @S9S_MB_2U_LIB.S9S_MB_2U(SCH_1):PU_RST_SMB_OCP_SFF_N
  B47  P5E_CPU0_PE1_TX_C_DP<9>  PETN9  @S9S_MB_2U_LIB.S9S_MB_2U(SCH_1):P5E_CPU0_PE1_TX_C_DP<9>
  B44  P5E_CPU0_PE1_TX_C_DP<8>  PETN8  @S9S_MB_2U_LIB.S9S_MB_2U(SCH_1):P5E_CPU0_PE1_TX_C_DP<8>
  B39  P5E_CPU0_PE1_TX_C_DP<7>  PETN7  @S9S_MB_2U_LIB.S9S_MB_2U(SCH_1):P5E_CPU0_PE1_TX_C_DP<7>
  B36  P5E_CPU0_PE1_TX_C_DP<6>  PETN6  @S9S_MB_2U_LIB.S9S_MB_2U(SCH_1):P5E_CPU0_PE1_TX_C_DP<6>
  B33  P5E_CPU0_PE1_TX_C_DP<5>  PETN5  @S9S_MB_2U_LIB.S9S_MB_2U(SCH_1):P5E_CPU0_PE1_TX_C_DP<5>
  B30  P5E_CPU0_PE1_TX_C_DP<4>  PETN4  @S9S_MB_2U_LIB.S9S_MB_2U(SCH_1):P5E_CPU0_PE1_TX_C_DP<4>
  B26  P5E_CPU0_PE1_TX_C_DP<3>  PETN3  @S9S_MB_2U_LIB.S9S_MB_2U(SCH_1):P5E_CPU0_PE1_TX_C_DP<3>
  B23  P5E_CPU0_PE1_TX_C_DP<2>  PETN2  @S9S_MB_2U_LIB.S9S_MB_2U(SCH_1):P5E_CPU0_PE1_TX_C_DP<2>
  B20  P5E_CPU0_PE1_TX_C_DP<1>  PETN1  @S9S_MB_2U_LIB.S9S_MB_2U(SCH_1):P5E_CPU0_PE1_TX_C_DP<1>
  B65  P5E_CPU0_PE1_TX_C_DP<15>  PETN15  @S9S_MB_2U_LIB.S9S_MB_2U(SCH_1):P5E_CPU0_PE1_TX_C_DP<15>
  B62  P5E_CPU0_PE1_TX_C_DP<14>  PETN14  @S9S_MB_2U_LIB.S9S_MB_2U(SCH_1):P5E_CPU0_PE1_TX_C_DP<14>
  B59  P5E_CPU0_PE1_TX_C_DP<13>  PETN13  @S9S_MB_2U_LIB.S9S_MB_2U(SCH_1):P5E_CPU0_PE1_TX_C_DP<13>
  B56  P5E_CPU0_PE1_TX_C_DP<12>  PETN12  @S9S_MB_2U_LIB.S9S_MB_2U(SCH_1):P5E_CPU0_PE1_TX_C_DP<12>
  B53  P5E_CPU0_PE1_TX_C_DP<11>  PETN11  @S9S_MB_2U_LIB.S9S_MB_2U(SCH_1):P5E_CPU0_PE1_TX_C_DP<11>
  B50  P5E_CPU0_PE1_TX_C_DP<10>  PETN10  @S9S_MB_2U_LIB.S9S_MB_2U(SCH_1):P5E_CPU0_PE1_TX_C_DP<10>
  B17  P5E_CPU0_PE1_TX_C_DP<0>  PETN0  @S9S_MB_2U_LIB.S9S_MB_2U(SCH_1):P5E_CPU0_PE1_TX_C_DP<0>
  B48  P5E_CPU0_PE1_TX_C_DN<9>  PETP9  @S9S_MB_2U_LIB.S9S_MB_2U(SCH_1):P5E_CPU0_PE1_TX_C_DN<9>
  B45  P5E_CPU0_PE1_TX_C_DN<8>  PETP8  @S9S_MB_2U_LIB.S9S_MB_2U(SCH_1):P5E_CPU0_PE1_TX_C_DN<8>
  B40  P5E_CPU0_PE1_TX_C_DN<7>  PETP7  @S9S_MB_2U_LIB.S9S_MB_2U(SCH_1):P5E_CPU0_PE1_TX_C_DN<7>
  B37  P5E_CPU0_PE1_TX_C_DN<6>  PETP6  @S9S_MB_2U_LIB.S9S_MB_2U(SCH_1):P5E_CPU0_PE1_TX_C_DN<6>
  B34  P5E_CPU0_PE1_TX_C_DN<5>  PETP5  @S9S_MB_2U_LIB.S9S_MB_2U(SCH_1):P5E_CPU0_PE1_TX_C_DN<5>
  B31  P5E_CPU0_PE1_TX_C_DN<4>  PETP4  @S9S_MB_2U_LIB.S9S_MB_2U(SCH_1):P5E_CPU0_PE1_TX_C_DN<4>
  B27  P5E_CPU0_PE1_TX_C_DN<3>  PETP3  @S9S_MB_2U_LIB.S9S_MB_2U(SCH_1):P5E_CPU0_PE1_TX_C_DN<3>
  B24  P5E_CPU0_PE1_TX_C_DN<2>  PETP2  @S9S_MB_2U_LIB.S9S_MB_2U(SCH_1):P5E_CPU0_PE1_TX_C_DN<2>
  B21  P5E_CPU0_PE1_TX_C_DN<1>  PETP1  @S9S_MB_2U_LIB.S9S_MB_2U(SCH_1):P5E_CPU0_PE1_TX_C_DN<1>
  B66  P5E_CPU0_PE1_TX_C_DN<15>  PETP15  @S9S_MB_2U_LIB.S9S_MB_2U(SCH_1):P5E_CPU0_PE1_TX_C_DN<15>
  B63  P5E_CPU0_PE1_TX_C_DN<14>  PETP14  @S9S_MB_2U_LIB.S9S_MB_2U(SCH_1):P5E_CPU0_PE1_TX_C_DN<14>
  B60  P5E_CPU0_PE1_TX_C_DN<13>  PETP13  @S9S_MB_2U_LIB.S9S_MB_2U(SCH_1):P5E_CPU0_PE1_TX_C_DN<13>
  B57  P5E_CPU0_PE1_TX_C_DN<12>  PETP12  @S9S_MB_2U_LIB.S9S_MB_2U(SCH_1):P5E_CPU0_PE1_TX_C_DN<12>
  B54  P5E_CPU0_PE1_TX_C_DN<11>  PETP11  @S9S_MB_2U_LIB.S9S_MB_2U(SCH_1):P5E_CPU0_PE1_TX_C_DN<11>
  B51  P5E_CPU0_PE1_TX_C_DN<10>  PETP10  @S9S_MB_2U_LIB.S9S_MB_2U(SCH_1):P5E_CPU0_PE1_TX_C_DN<10>
  B18  P5E_CPU0_PE1_TX_C_DN<0>  PETP0  @S9S_MB_2U_LIB.S9S_MB_2U(SCH_1):P5E_CPU0_PE1_TX_C_DN<0>
  A47  P5E_CPU0_PE1_RX_DP<9>  PERN9  @S9S_MB_2U_LIB.S9S_MB_2U(SCH_1):P5E_CPU0_PE1_RX_DP<9>
  A44  P5E_CPU0_PE1_RX_DP<8>  PERN8  @S9S_MB_2U_LIB.S9S_MB_2U(SCH_1):P5E_CPU0_PE1_RX_DP<8>
  A39  P5E_CPU0_PE1_RX_DP<7>  PERN7  @S9S_MB_2U_LIB.S9S_MB_2U(SCH_1):P5E_CPU0_PE1_RX_DP<7>
  A36  P5E_CPU0_PE1_RX_DP<6>  PERN6  @S9S_MB_2U_LIB.S9S_MB_2U(SCH_1):P5E_CPU0_PE1_RX_DP<6>
  A33  P5E_CPU0_PE1_RX_DP<5>  PERN5  @S9S_MB_2U_LIB.S9S_MB_2U(SCH_1):P5E_CPU0_PE1_RX_DP<5>
  A30  P5E_CPU0_PE1_RX_DP<4>  PERN4  @S9S_MB_2U_LIB.S9S_MB_2U(SCH_1):P5E_CPU0_PE1_RX_DP<4>
  A26  P5E_CPU0_PE1_RX_DP<3>  PERN3  @S9S_MB_2U_LIB.S9S_MB_2U(SCH_1):P5E_CPU0_PE1_RX_DP<3>
  A23  P5E_CPU0_PE1_RX_DP<2>  PERN2  @S9S_MB_2U_LIB.S9S_MB_2U(SCH_1):P5E_CPU0_PE1_RX_DP<2>
  A20  P5E_CPU0_PE1_RX_DP<1>  PERN1  @S9S_MB_2U_LIB.S9S_MB_2U(SCH_1):P5E_CPU0_PE1_RX_DP<1>
  A65  P5E_CPU0_PE1_RX_DP<15>  PERN15  @S9S_MB_2U_LIB.S9S_MB_2U(SCH_1):P5E_CPU0_PE1_RX_DP<15>
  A62  P5E_CPU0_PE1_RX_DP<14>  PERN14  @S9S_MB_2U_LIB.S9S_MB_2U(SCH_1):P5E_CPU0_PE1_RX_DP<14>
  A59  P5E_CPU0_PE1_RX_DP<13>  PERN13  @S9S_MB_2U_LIB.S9S_MB_2U(SCH_1):P5E_CPU0_PE1_RX_DP<13>
  A56  P5E_CPU0_PE1_RX_DP<12>  PERN12  @S9S_MB_2U_LIB.S9S_MB_2U(SCH_1):P5E_CPU0_PE1_RX_DP<12>
  A53  P5E_CPU0_PE1_RX_DP<11>  PERN11  @S9S_MB_2U_LIB.S9S_MB_2U(SCH_1):P5E_CPU0_PE1_RX_DP<11>
  A50  P5E_CPU0_PE1_RX_DP<10>  PERN10  @S9S_MB_2U_LIB.S9S_MB_2U(SCH_1):P5E_CPU0_PE1_RX_DP<10>
  A17  P5E_CPU0_PE1_RX_DP<0>  PERN0  @S9S_MB_2U_LIB.S9S_MB_2U(SCH_1):P5E_CPU0_PE1_RX_DP<0>
  A48  P5E_CPU0_PE1_RX_DN<9>  PERP9  @S9S_MB_2U_LIB.S9S_MB_2U(SCH_1):P5E_CPU0_PE1_RX_DN<9>
  A45  P5E_CPU0_PE1_RX_DN<8>  PERP8  @S9S_MB_2U_LIB.S9S_MB_2U(SCH_1):P5E_CPU0_PE1_RX_DN<8>
  A40  P5E_CPU0_PE1_RX_DN<7>  PERP7  @S9S_MB_2U_LIB.S9S_MB_2U(SCH_1):P5E_CPU0_PE1_RX_DN<7>
  A37  P5E_CPU0_PE1_RX_DN<6>  PERP6  @S9S_MB_2U_LIB.S9S_MB_2U(SCH_1):P5E_CPU0_PE1_RX_DN<6>
  A34  P5E_CPU0_PE1_RX_DN<5>  PERP5  @S9S_MB_2U_LIB.S9S_MB_2U(SCH_1):P5E_CPU0_PE1_RX_DN<5>
  A31  P5E_CPU0_PE1_RX_DN<4>  PERP4  @S9S_MB_2U_LIB.S9S_MB_2U(SCH_1):P5E_CPU0_PE1_RX_DN<4>
  A27  P5E_CPU0_PE1_RX_DN<3>  PERP3  @S9S_MB_2U_LIB.S9S_MB_2U(SCH_1):P5E_CPU0_PE1_RX_DN<3>
  A24  P5E_CPU0_PE1_RX_DN<2>  PERP2  @S9S_MB_2U_LIB.S9S_MB_2U(SCH_1):P5E_CPU0_PE1_RX_DN<2>
  A21  P5E_CPU0_PE1_RX_DN<1>  PERP1  @S9S_MB_2U_LIB.S9S_MB_2U(SCH_1):P5E_CPU0_PE1_RX_DN<1>
  A66  P5E_CPU0_PE1_RX_DN<15>  PERP15  @S9S_MB_2U_LIB.S9S_MB_2U(SCH_1):P5E_CPU0_PE1_RX_DN<15>
  A63  P5E_CPU0_PE1_RX_DN<14>  PERP14  @S9S_MB_2U_LIB.S9S_MB_2U(SCH_1):P5E_CPU0_PE1_RX_DN<14>
  A60  P5E_CPU0_PE1_RX_DN<13>  PERP13  @S9S_MB_2U_LIB.S9S_MB_2U(SCH_1):P5E_CPU0_PE1_RX_DN<13>
  A57  P5E_CPU0_PE1_RX_DN<12>  PERP12  @S9S_MB_2U_LIB.S9S_MB_2U(SCH_1):P5E_CPU0_PE1_RX_DN<12>
  A54  P5E_CPU0_PE1_RX_DN<11>  PERP11  @S9S_MB_2U_LIB.S9S_MB_2U(SCH_1):P5E_CPU0_PE1_RX_DN<11>
  A51  P5E_CPU0_PE1_RX_DN<10>  PERP10  @S9S_MB_2U_LIB.S9S_MB_2U(SCH_1):P5E_CPU0_PE1_RX_DN<10>
  A18  P5E_CPU0_PE1_RX_DN<0>  PERP0  @S9S_MB_2U_LIB.S9S_MB_2U(SCH_1):P5E_CPU0_PE1_RX_DN<0>
  B11  P3V3_OCP_SFF   +3.3V_EDGE  @S9S_MB_2U_LIB.S9S_MB_2U(SCH_1):P3V3_OCP_SFF
   B6  P12V_OCP_SFF   +12V_EDGE_B6  @S9S_MB_2U_LIB.S9S_MB_2U(SCH_1):P12V_OCP_SFF
   B5  P12V_OCP_SFF   +12V_EDGE_B5  @S9S_MB_2U_LIB.S9S_MB_2U(SCH_1):P12V_OCP_SFF
   B4  P12V_OCP_SFF   +12V_EDGE_B4  @S9S_MB_2U_LIB.S9S_MB_2U(SCH_1):P12V_OCP_SFF
   B3  P12V_OCP_SFF   +12V_EDGE_B3  @S9S_MB_2U_LIB.S9S_MB_2U(SCH_1):P12V_OCP_SFF
   B2  P12V_OCP_SFF   +12V_EDGE_B2  @S9S_MB_2U_LIB.S9S_MB_2U(SCH_1):P12V_OCP_SFF
   B1  P12V_OCP_SFF   +12V_EDGE_B1  @S9S_MB_2U_LIB.S9S_MB_2U(SCH_1):P12V_OCP_SFF
  A69  OCP_SFF_USB2_3_DP  USB_DATP  @S9S_MB_2U_LIB.S9S_MB_2U(SCH_1):OCP_SFF_USB2_3_DP
  A68  OCP_SFF_USB2_3_DN  USB_DATN  @S9S_MB_2U_LIB.S9S_MB_2U(SCH_1):OCP_SFF_USB2_3_DN
  OCP_A5  OCP_SFF_RBT_ARB_OUT  RBT_ARB_OUT  @S9S_MB_2U_LIB.S9S_MB_2U(SCH_1):OCP_SFF_RBT_ARB_OUT
  OCP_A4  OCP_SFF_RBT_ARB_IN  RBT_ARB_IN  @S9S_MB_2U_LIB.S9S_MB_2U(SCH_1):OCP_SFF_RBT_ARB_IN
  A70  OCP_SFF_PWRBRK_N  PWRBRK#  @S9S_MB_2U_LIB.S9S_MB_2U(SCH_1):OCP_SFF_PWRBRK_N
  A10  OCP_SFF_PRSNTA_R_N  PRSNTA#  @S9S_MB_2U_LIB.S9S_MB_2U(SCH_1):OCP_SFF_PRSNTA_R_N
  B70  OCP_SFF_PRSNT3_R_N  PRSNTB3#  @S9S_MB_2U_LIB.S9S_MB_2U(SCH_1):OCP_SFF_PRSNT3_R_N
  A12  OCP_SFF_PRSNT2_R_N  PRSNTB2#  @S9S_MB_2U_LIB.S9S_MB_2U(SCH_1):OCP_SFF_PRSNT2_R_N
  A42  OCP_SFF_PRSNT1_R_N  PRSNTB1#  @S9S_MB_2U_LIB.S9S_MB_2U(SCH_1):OCP_SFF_PRSNT1_R_N
  B42  OCP_SFF_PRSNT0_R_N  PRSNTB0#  @S9S_MB_2U_LIB.S9S_MB_2U(SCH_1):OCP_SFF_PRSNT0_R_N
  OCP_B2  OCP_SFF_MAIN_PWR_EN  MAIN_PWR_EN  @S9S_MB_2U_LIB.S9S_MB_2U(SCH_1):OCP_SFF_MAIN_PWR_EN
  OCP_A6  OCP_SFF_ID1    SLOT_ID1  @S9S_MB_2U_LIB.S9S_MB_2U(SCH_1):OCP_SFF_ID1
  OCP_B7  OCP_SFF_ID0    SLOT_ID0  @S9S_MB_2U_LIB.S9S_MB_2U(SCH_1):OCP_SFF_ID0
   B9  OCP_SFF_BIF2_R_N  BIF2#  @S9S_MB_2U_LIB.S9S_MB_2U(SCH_1):OCP_SFF_BIF2_R_N
   B8  OCP_SFF_BIF1_R_N  BIF1#  @S9S_MB_2U_LIB.S9S_MB_2U(SCH_1):OCP_SFF_BIF1_R_N
   B7  OCP_SFF_BIF0_R_N  BIF0#  @S9S_MB_2U_LIB.S9S_MB_2U(SCH_1):OCP_SFF_BIF0_R_N
  B12  OCP_SFF_AUX_PWR_EN_R  AUX_PWR_EN  @S9S_MB_2U_LIB.S9S_MB_2U(SCH_1):OCP_SFF_AUX_PWR_EN_R
  OCP_A7  NCSI_OCP_SFF_TX_EN  RBT_TX_EN  @S9S_MB_2U_LIB.S9S_MB_2U(SCH_1):NCSI_OCP_SFF_TX_EN
  OCP_A8  NCSI_OCP_SFF_TXD1  RBT_TXD1  @S9S_MB_2U_LIB.S9S_MB_2U(SCH_1):NCSI_OCP_SFF_TXD1
  OCP_A9  NCSI_OCP_SFF_TXD0  RBT_TXD0  @S9S_MB_2U_LIB.S9S_MB_2U(SCH_1):NCSI_OCP_SFF_TXD0
  OCP_B8  NCSI_OCP_SFF_RXD1  RBT_RXD1  @S9S_MB_2U_LIB.S9S_MB_2U(SCH_1):NCSI_OCP_SFF_RXD1
  OCP_B9  NCSI_OCP_SFF_RXD0  RBT_RXD0  @S9S_MB_2U_LIB.S9S_MB_2U(SCH_1):NCSI_OCP_SFF_RXD0
  OCP_B14  NCSI_OCP_SFF_CRS_DV  RBT_CRS_DV  @S9S_MB_2U_LIB.S9S_MB_2U(SCH_1):NCSI_OCP_SFF_CRS_DV
  OCP_A3  IRQ_LVC3_OCP_SFF_WAKE_N  WAKE#  @S9S_MB_2U_LIB.S9S_MB_2U(SCH_1):IRQ_LVC3_OCP_SFF_WAKE_N
  OCP_B13  GND            GND_OCP_B13  @S9S_MB_2U_LIB.S9S_MB_2U(SCH_1):GND
  OCP_B10  GND            GND_OCP_B10  @S9S_MB_2U_LIB.S9S_MB_2U(SCH_1):GND
  OCP_A13  GND            GND_OCP_A13  @S9S_MB_2U_LIB.S9S_MB_2U(SCH_1):GND
  OCP_A10  GND            GND_OCP_A10  @S9S_MB_2U_LIB.S9S_MB_2U(SCH_1):GND
  B67  GND            GND_B67  @S9S_MB_2U_LIB.S9S_MB_2U(SCH_1):GND
  B64  GND            GND_B64  @S9S_MB_2U_LIB.S9S_MB_2U(SCH_1):GND
  B61  GND            GND_B61  @S9S_MB_2U_LIB.S9S_MB_2U(SCH_1):GND
  B58  GND            GND_B58  @S9S_MB_2U_LIB.S9S_MB_2U(SCH_1):GND
  B55  GND            GND_B55  @S9S_MB_2U_LIB.S9S_MB_2U(SCH_1):GND
  B52  GND            GND_B52  @S9S_MB_2U_LIB.S9S_MB_2U(SCH_1):GND
  B49  GND            GND_B49  @S9S_MB_2U_LIB.S9S_MB_2U(SCH_1):GND
  B46  GND            GND_B46  @S9S_MB_2U_LIB.S9S_MB_2U(SCH_1):GND
  B43  GND            GND_B43  @S9S_MB_2U_LIB.S9S_MB_2U(SCH_1):GND
  B41  GND            GND_B41  @S9S_MB_2U_LIB.S9S_MB_2U(SCH_1):GND
  B38  GND            GND_B38  @S9S_MB_2U_LIB.S9S_MB_2U(SCH_1):GND
  B35  GND            GND_B35  @S9S_MB_2U_LIB.S9S_MB_2U(SCH_1):GND
  B32  GND            GND_B32  @S9S_MB_2U_LIB.S9S_MB_2U(SCH_1):GND
  B29  GND            GND_B29  @S9S_MB_2U_LIB.S9S_MB_2U(SCH_1):GND
  B28  GND            GND_B28  @S9S_MB_2U_LIB.S9S_MB_2U(SCH_1):GND
  B25  GND            GND_B25  @S9S_MB_2U_LIB.S9S_MB_2U(SCH_1):GND
  B22  GND            GND_B22  @S9S_MB_2U_LIB.S9S_MB_2U(SCH_1):GND
  B19  GND            GND_B19  @S9S_MB_2U_LIB.S9S_MB_2U(SCH_1):GND
  B16  GND            GND_B16  @S9S_MB_2U_LIB.S9S_MB_2U(SCH_1):GND
  B13  GND            GND_B13  @S9S_MB_2U_LIB.S9S_MB_2U(SCH_1):GND
  A67  GND            GND_A67  @S9S_MB_2U_LIB.S9S_MB_2U(SCH_1):GND
  A64  GND            GND_A64  @S9S_MB_2U_LIB.S9S_MB_2U(SCH_1):GND
  A61  GND            GND_A61  @S9S_MB_2U_LIB.S9S_MB_2U(SCH_1):GND
  A58  GND            GND_A58  @S9S_MB_2U_LIB.S9S_MB_2U(SCH_1):GND
  A55  GND            GND_A55  @S9S_MB_2U_LIB.S9S_MB_2U(SCH_1):GND
  A52  GND            GND_A52  @S9S_MB_2U_LIB.S9S_MB_2U(SCH_1):GND
  A49  GND            GND_A49  @S9S_MB_2U_LIB.S9S_MB_2U(SCH_1):GND
  A46  GND            GND_A46  @S9S_MB_2U_LIB.S9S_MB_2U(SCH_1):GND
  A43  GND            GND_A43  @S9S_MB_2U_LIB.S9S_MB_2U(SCH_1):GND
  A41  GND            GND_A41  @S9S_MB_2U_LIB.S9S_MB_2U(SCH_1):GND
  A38  GND            GND_A38  @S9S_MB_2U_LIB.S9S_MB_2U(SCH_1):GND
  A35  GND            GND_A35  @S9S_MB_2U_LIB.S9S_MB_2U(SCH_1):GND
  A32  GND            GND_A32  @S9S_MB_2U_LIB.S9S_MB_2U(SCH_1):GND
  A29  GND            GND_A29  @S9S_MB_2U_LIB.S9S_MB_2U(SCH_1):GND
  A28  GND            GND_A28  @S9S_MB_2U_LIB.S9S_MB_2U(SCH_1):GND
  A25  GND            GND_A25  @S9S_MB_2U_LIB.S9S_MB_2U(SCH_1):GND
  A22  GND            GND_A22  @S9S_MB_2U_LIB.S9S_MB_2U(SCH_1):GND
  A19  GND            GND_A19  @S9S_MB_2U_LIB.S9S_MB_2U(SCH_1):GND
  A16  GND            GND_A16  @S9S_MB_2U_LIB.S9S_MB_2U(SCH_1):GND
  A13  GND            GND_A13  @S9S_MB_2U_LIB.S9S_MB_2U(SCH_1):GND
   A6  GND            GND_A6  @S9S_MB_2U_LIB.S9S_MB_2U(SCH_1):GND
   A5  GND            GND_A5  @S9S_MB_2U_LIB.S9S_MB_2U(SCH_1):GND
   A4  GND            GND_A4  @S9S_MB_2U_LIB.S9S_MB_2U(SCH_1):GND
   A3  GND            GND_A3  @S9S_MB_2U_LIB.S9S_MB_2U(SCH_1):GND
   A2  GND            GND_A2  @S9S_MB_2U_LIB.S9S_MB_2U(SCH_1):GND
   A1  GND            GND_A1  @S9S_MB_2U_LIB.S9S_MB_2U(SCH_1):GND
  OCP_B1  FM_OCP_SFF_PWR_GOOD  NIC_PWR_GOOD  @S9S_MB_2U_LIB.S9S_MB_2U(SCH_1):FM_OCP_SFF_PWR_GOOD
  OCP_A14  CLK_50M_NCSI_OCP_SFF  RBT_CLK_IN  @S9S_MB_2U_LIB.S9S_MB_2U(SCH_1):CLK_50M_NCSI_OCP_SFF
  OCP_A12  CLK_100M_OCP_SFF_3_DP  REFCLKP3  @S9S_MB_2U_LIB.S9S_MB_2U(SCH_1):CLK_100M_OCP_SFF_3_DP
  OCP_A11  CLK_100M_OCP_SFF_3_DN  REFCLKN3  @S9S_MB_2U_LIB.S9S_MB_2U(SCH_1):CLK_100M_OCP_SFF_3_DN
  OCP_B12  CLK_100M_OCP_SFF_2_DP  REFCLKP2  @S9S_MB_2U_LIB.S9S_MB_2U(SCH_1):CLK_100M_OCP_SFF_2_DP
  OCP_B11  CLK_100M_OCP_SFF_2_DN  REFCLKN2  @S9S_MB_2U_LIB.S9S_MB_2U(SCH_1):CLK_100M_OCP_SFF_2_DN
  A15  CLK_100M_OCP_SFF_1_DP  REFCLKP1  @S9S_MB_2U_LIB.S9S_MB_2U(SCH_1):CLK_100M_OCP_SFF_1_DP
  A14  CLK_100M_OCP_SFF_1_DN  REFCLKN1  @S9S_MB_2U_LIB.S9S_MB_2U(SCH_1):CLK_100M_OCP_SFF_1_DN
  B15  CLK_100M_OCP_SFF_0_DP  REFCLKP0  @S9S_MB_2U_LIB.S9S_MB_2U(SCH_1):CLK_100M_OCP_SFF_0_DP
  B14  CLK_100M_OCP_SFF_0_DN  REFCLKN0  @S9S_MB_2U_LIB.S9S_MB_2U(SCH_1):CLK_100M_OCP_SFF_0_DN

SCONN168_623403212  I115  J41    [SCONN168_623403212-SCONN168_6-A]
  OCP_A14  VIRTUAL_RESEAT  RBT_CLK_IN  @S9S_MB_2U_LIB.S9S_MB_2U(SCH_1):VIRTUAL_RESEAT
  B50  USB2_9_DP      PETN10  @S9S_MB_2U_LIB.S9S_MB_2U(SCH_1):USB2_9_DP
  B51  USB2_9_DN      PETP10  @S9S_MB_2U_LIB.S9S_MB_2U(SCH_1):USB2_9_DN
  B53  USB2_8_DP      PETN11  @S9S_MB_2U_LIB.S9S_MB_2U(SCH_1):USB2_8_DP
  B54  USB2_8_DN      PETP11  @S9S_MB_2U_LIB.S9S_MB_2U(SCH_1):USB2_8_DN
  B56  USB2_0_DP      PETN12  @S9S_MB_2U_LIB.S9S_MB_2U(SCH_1):USB2_0_DP
  B57  USB2_0_DN      PETP12  @S9S_MB_2U_LIB.S9S_MB_2U(SCH_1):USB2_0_DN
  OCP_B5  NC             DATA_OUT  NC
  OCP_B6  NC               CLK  NC
  OCP_B13  NC             GND_OCP_B13  NC
  OCP_B14  NC             RBT_CRS_DV  NC
  OCP_B11  NC             REFCLKN2  NC
  B48  NC             PETP9  NC
  B47  NC             PETN9  NC
  B46  NC             GND_B46  NC
  B45  NC             PETP8  NC
  B44  NC             PETN8  NC
  B43  NC             GND_B43  NC
  B68  NC              RFU1  NC
  B65  NC             PETN15  NC
  B62  NC             PETN14  NC
  B69  NC              RFU2  NC
  B66  NC             PETP15  NC
  B63  NC             PETP14  NC
  A68  NC             USB_DATN  NC
  A65  NC             PERN15  NC
  A62  NC             PERN14  NC
  A69  NC             USB_DATP  NC
  A66  NC             PERP15  NC
  A63  NC             PERP14  NC
  OCP_B8  NC             RBT_RXD1  NC
  OCP_B9  NC             RBT_RXD0  NC
  OCP_B12  SPI_TPM_CS_N   REFCLKP2  @S9S_MB_2U_LIB.S9S_MB_2U(SCH_1):SPI_TPM_CS_N
  B15  SPI_SYS_WP_IO2  REFCLKP0  @S9S_MB_2U_LIB.S9S_MB_2U(SCH_1):SPI_SYS_WP_IO2
  B13  SPI_SYS_MOSI   GND_B13  @S9S_MB_2U_LIB.S9S_MB_2U(SCH_1):SPI_SYS_MOSI
  B14  SPI_SYS_MISO   REFCLKN0  @S9S_MB_2U_LIB.S9S_MB_2U(SCH_1):SPI_SYS_MISO
  B16  SPI_SYS_HOLD_IO3  GND_B16  @S9S_MB_2U_LIB.S9S_MB_2U(SCH_1):SPI_SYS_HOLD_IO3
  B12  SPI_SYS_CS0_N  AUX_PWR_EN  @S9S_MB_2U_LIB.S9S_MB_2U(SCH_1):SPI_SYS_CS0_N
  B11  SPI_SYS_CLK    +3.3V_EDGE  @S9S_MB_2U_LIB.S9S_MB_2U(SCH_1):SPI_SYS_CLK
  B42  SPI_PCH_PFR_CS1_N  PRSNTB0#  @S9S_MB_2U_LIB.S9S_MB_2U(SCH_1):SPI_PCH_PFR_CS1_N
   A6  SMB_VR_3V3AUX_SDA  GND_A6  @S9S_MB_2U_LIB.S9S_MB_2U(SCH_1):SMB_VR_3V3AUX_SDA
   A5  SMB_VR_3V3AUX_SCL  GND_A5  @S9S_MB_2U_LIB.S9S_MB_2U(SCH_1):SMB_VR_3V3AUX_SCL
   A8  SMB_SML1_PMBUS_3V3AUX_PCH_SDA  SMDAT  @S9S_MB_2U_LIB.S9S_MB_2U(SCH_1):SMB_SML1_PMBUS_3V3AUX_PCH_SDA
   A7  SMB_SML1_PMBUS_3V3AUX_PCH_SCL  SMCLK  @S9S_MB_2U_LIB.S9S_MB_2U(SCH_1):SMB_SML1_PMBUS_3V3AUX_PCH_SCL
  A26  SMB_SML0_3V3AUX_SDA  PERN3  @S9S_MB_2U_LIB.S9S_MB_2U(SCH_1):SMB_SML0_3V3AUX_SDA
  A25  SMB_SML0_3V3AUX_SCL  GND_A25  @S9S_MB_2U_LIB.S9S_MB_2U(SCH_1):SMB_SML0_3V3AUX_SCL
  A10  SMB_SENSOR_3V3AUX_SDA  PRSNTA#  @S9S_MB_2U_LIB.S9S_MB_2U(SCH_1):SMB_SENSOR_3V3AUX_SDA
   A9  SMB_SENSOR_3V3AUX_SCL  SMRST#  @S9S_MB_2U_LIB.S9S_MB_2U(SCH_1):SMB_SENSOR_3V3AUX_SCL
  A41  SMB_S3M_CPU_3V3AUX_SDA  GND_A41  @S9S_MB_2U_LIB.S9S_MB_2U(SCH_1):SMB_S3M_CPU_3V3AUX_SDA
  A40  SMB_S3M_CPU_3V3AUX_SCL  PERP7  @S9S_MB_2U_LIB.S9S_MB_2U(SCH_1):SMB_S3M_CPU_3V3AUX_SCL
   A2  SMB_PLD_3V3AUX_SDA  GND_A2  @S9S_MB_2U_LIB.S9S_MB_2U(SCH_1):SMB_PLD_3V3AUX_SDA
   A1  SMB_PLD_3V3AUX_SCL  GND_A1  @S9S_MB_2U_LIB.S9S_MB_2U(SCH_1):SMB_PLD_3V3AUX_SCL
  A39  SMB_PCIE3_3V3AUX_SDA  PERN7  @S9S_MB_2U_LIB.S9S_MB_2U(SCH_1):SMB_PCIE3_3V3AUX_SDA
  A38  SMB_PCIE3_3V3AUX_SCL  GND_A38  @S9S_MB_2U_LIB.S9S_MB_2U(SCH_1):SMB_PCIE3_3V3AUX_SCL
  A32  SMB_PCIE2_3V3AUX_SDA  GND_A32  @S9S_MB_2U_LIB.S9S_MB_2U(SCH_1):SMB_PCIE2_3V3AUX_SDA
  A31  SMB_PCIE2_3V3AUX_SCL  PERP4  @S9S_MB_2U_LIB.S9S_MB_2U(SCH_1):SMB_PCIE2_3V3AUX_SCL
  A28  SMB_PCIE1_3V3AUX_SDA  GND_A28  @S9S_MB_2U_LIB.S9S_MB_2U(SCH_1):SMB_PCIE1_3V3AUX_SDA
  A27  SMB_PCIE1_3V3AUX_SCL  PERP3  @S9S_MB_2U_LIB.S9S_MB_2U(SCH_1):SMB_PCIE1_3V3AUX_SCL
  A24  SMB_PCIE0_3V3AUX_SDA  PERP2  @S9S_MB_2U_LIB.S9S_MB_2U(SCH_1):SMB_PCIE0_3V3AUX_SDA
  A23  SMB_PCIE0_3V3AUX_SCL  PERN2  @S9S_MB_2U_LIB.S9S_MB_2U(SCH_1):SMB_PCIE0_3V3AUX_SCL
   A4  SMB_HOST_3V3AUX_SDA  GND_A4  @S9S_MB_2U_LIB.S9S_MB_2U(SCH_1):SMB_HOST_3V3AUX_SDA
   A3  SMB_HOST_3V3AUX_SCL  GND_A3  @S9S_MB_2U_LIB.S9S_MB_2U(SCH_1):SMB_HOST_3V3AUX_SCL
  A30  SMB_FAN_3V3AUX_SDA  PERN4  @S9S_MB_2U_LIB.S9S_MB_2U(SCH_1):SMB_FAN_3V3AUX_SDA
  A29  SMB_FAN_3V3AUX_SCL  GND_A29  @S9S_MB_2U_LIB.S9S_MB_2U(SCH_1):SMB_FAN_3V3AUX_SCL
  A22  SMB_CPU_PIROM_3V3AUX_SDA  GND_A22  @S9S_MB_2U_LIB.S9S_MB_2U(SCH_1):SMB_CPU_PIROM_3V3AUX_SDA
  A21  SMB_CPU_PIROM_3V3AUX_SCL  PERP1  @S9S_MB_2U_LIB.S9S_MB_2U(SCH_1):SMB_CPU_PIROM_3V3AUX_SCL
  B37  SGPIO_LD_1     PETP6  @S9S_MB_2U_LIB.S9S_MB_2U(SCH_1):SGPIO_LD_1
  B32  SGPIO_LD_0     GND_B32  @S9S_MB_2U_LIB.S9S_MB_2U(SCH_1):SGPIO_LD_0
  B34  SGPIO_DO_1     PETP5  @S9S_MB_2U_LIB.S9S_MB_2U(SCH_1):SGPIO_DO_1
  B29  SGPIO_DO_0     GND_B29  @S9S_MB_2U_LIB.S9S_MB_2U(SCH_1):SGPIO_DO_0
  B36  SGPIO_DI_1     PETN6  @S9S_MB_2U_LIB.S9S_MB_2U(SCH_1):SGPIO_DI_1
  B31  SGPIO_DI_0     PETP4  @S9S_MB_2U_LIB.S9S_MB_2U(SCH_1):SGPIO_DI_0
  B35  SGPIO_CLK_1    GND_B35  @S9S_MB_2U_LIB.S9S_MB_2U(SCH_1):SGPIO_CLK_1
  B30  SGPIO_CLK_0    PETN4  @S9S_MB_2U_LIB.S9S_MB_2U(SCH_1):SGPIO_CLK_0
  B39  RST_SGPIO_RESET_N  PETN7  @S9S_MB_2U_LIB.S9S_MB_2U(SCH_1):RST_SGPIO_RESET_N
  A51  RST_PLTRST_B_N  PERP10  @S9S_MB_2U_LIB.S9S_MB_2U(SCH_1):RST_PLTRST_B_N
  A46  RST_MB_STBY_N  GND_A46  @S9S_MB_2U_LIB.S9S_MB_2U(SCH_1):RST_MB_STBY_N
  A53  ROT_P1_RST_IND_N  PERN11  @S9S_MB_2U_LIB.S9S_MB_2U(SCH_1):ROT_P1_RST_IND_N
  B25  RMII_OCP_BMC_RXD_1  GND_B25  @S9S_MB_2U_LIB.S9S_MB_2U(SCH_1):RMII_OCP_BMC_RXD_1
  B24  RMII_OCP_BMC_RXD_0  PETP2  @S9S_MB_2U_LIB.S9S_MB_2U(SCH_1):RMII_OCP_BMC_RXD_0
  B19  RMII_OCP_BMC_CRSDV  GND_B19  @S9S_MB_2U_LIB.S9S_MB_2U(SCH_1):RMII_OCP_BMC_CRSDV
  B20  RMII_BMC_OCP_TX_EN  PETN1  @S9S_MB_2U_LIB.S9S_MB_2U(SCH_1):RMII_BMC_OCP_TX_EN
  B22  RMII_BMC_OCP_TXD_1  GND_B22  @S9S_MB_2U_LIB.S9S_MB_2U(SCH_1):RMII_BMC_OCP_TXD_1
  B21  RMII_BMC_OCP_TXD_0  PETP1  @S9S_MB_2U_LIB.S9S_MB_2U(SCH_1):RMII_BMC_OCP_TXD_0
  B23  RMII_BMC_OCP_RX_ER  PETN2  @S9S_MB_2U_LIB.S9S_MB_2U(SCH_1):RMII_BMC_OCP_RX_ER
  A48  PWRGD_SYS_PWROK  PERP9  @S9S_MB_2U_LIB.S9S_MB_2U(SCH_1):PWRGD_SYS_PWROK
  A44  PWRGD_PS_PWROK_R  PERN8  @S9S_MB_2U_LIB.S9S_MB_2U(SCH_1):PWRGD_PS_PWROK_R
  B28  PVCCIO_PECI_BMC  GND_B28  @S9S_MB_2U_LIB.S9S_MB_2U(SCH_1):PVCCIO_PECI_BMC
  OCP_B3  PRSNT0_N         LD#  @S9S_MB_2U_LIB.S9S_MB_2U(SCH_1):PRSNT0_N
  B27  PECI_BMC       PETP3  @S9S_MB_2U_LIB.S9S_MB_2U(SCH_1):PECI_BMC
  B41  P3V_BAT_R      GND_B41  @S9S_MB_2U_LIB.S9S_MB_2U(SCH_1):P3V_BAT_R
  B59  P3E_PCH_M2_TX_C_DP<4>  PETN13  @S9S_MB_2U_LIB.S9S_MB_2U(SCH_1):P3E_PCH_M2_TX_C_DP<4>
  B60  P3E_PCH_M2_TX_C_DN<4>  PETP13  @S9S_MB_2U_LIB.S9S_MB_2U(SCH_1):P3E_PCH_M2_TX_C_DN<4>
  A59  P3E_PCH_M2_RX_DP<4>  PERN13  @S9S_MB_2U_LIB.S9S_MB_2U(SCH_1):P3E_PCH_M2_RX_DP<4>
  A60  P3E_PCH_M2_RX_DN<4>  PERP13  @S9S_MB_2U_LIB.S9S_MB_2U(SCH_1):P3E_PCH_M2_RX_DN<4>
  A15  P3E_PCH_BMC_TX_C_DP  REFCLKP1  @S9S_MB_2U_LIB.S9S_MB_2U(SCH_1):P3E_PCH_BMC_TX_C_DP
  A16  P3E_PCH_BMC_TX_C_DN  GND_A16  @S9S_MB_2U_LIB.S9S_MB_2U(SCH_1):P3E_PCH_BMC_TX_C_DN
  A18  P3E_PCH_BMC_RX_DP  PERP0  @S9S_MB_2U_LIB.S9S_MB_2U(SCH_1):P3E_PCH_BMC_RX_DP
  A19  P3E_PCH_BMC_RX_DN  GND_A19  @S9S_MB_2U_LIB.S9S_MB_2U(SCH_1):P3E_PCH_BMC_RX_DN
  OCP_A2  P12V_SCM       PERST3#  @S9S_MB_2U_LIB.S9S_MB_2U(SCH_1):P12V_SCM
  OCP_A1  P12V_SCM       PERST2#  @S9S_MB_2U_LIB.S9S_MB_2U(SCH_1):P12V_SCM
  OCP_B1  P12V_SCM       NIC_PWR_GOOD  @S9S_MB_2U_LIB.S9S_MB_2U(SCH_1):P12V_SCM
  OCP_B2  P12V_SCM       MAIN_PWR_EN  @S9S_MB_2U_LIB.S9S_MB_2U(SCH_1):P12V_SCM
  A50  JTAG_DBP_BMC_PRDY_N  PERN10  @S9S_MB_2U_LIB.S9S_MB_2U(SCH_1):JTAG_DBP_BMC_PRDY_N
  A35  JTAG_BMC_TMS   GND_A35  @S9S_MB_2U_LIB.S9S_MB_2U(SCH_1):JTAG_BMC_TMS
  A37  JTAG_BMC_TDO   PERP6  @S9S_MB_2U_LIB.S9S_MB_2U(SCH_1):JTAG_BMC_TDO
  A36  JTAG_BMC_TDI   PERN6  @S9S_MB_2U_LIB.S9S_MB_2U(SCH_1):JTAG_BMC_TDI
  A34  JTAG_BMC_TCK   PERP5  @S9S_MB_2U_LIB.S9S_MB_2U(SCH_1):JTAG_BMC_TCK
  A49  JTAG_BMC_DBP_PREQ_N  GND_A49  @S9S_MB_2U_LIB.S9S_MB_2U(SCH_1):JTAG_BMC_DBP_PREQ_N
  B40  IRQ_SGPIO_INTR_N  PETP7  @S9S_MB_2U_LIB.S9S_MB_2U(SCH_1):IRQ_SGPIO_INTR_N
   B3  IRQ_ESPI_LPC_SERIRQ_ALERT_R_N  +12V_EDGE_B3  @S9S_MB_2U_LIB.S9S_MB_2U(SCH_1):IRQ_ESPI_LPC_SERIRQ_ALERT_R_N
  A56  IRQ0_A57       PERN12  @S9S_MB_2U_LIB.S9S_MB_2U(SCH_1):IRQ0_A57
  OCP_A12  I3C_SPD_DDREFGH_CPU1_BMC_R_SDA  REFCLKP3  @S9S_MB_2U_LIB.S9S_MB_2U(SCH_1):I3C_SPD_DDREFGH_CPU1_BMC_R_SDA
  OCP_A11  I3C_SPD_DDREFGH_CPU1_BMC_R_SCL  REFCLKN3  @S9S_MB_2U_LIB.S9S_MB_2U(SCH_1):I3C_SPD_DDREFGH_CPU1_BMC_R_SCL
  OCP_A8  I3C_SPD_DDREFGH_CPU0_BMC_R_SDA  RBT_TXD1  @S9S_MB_2U_LIB.S9S_MB_2U(SCH_1):I3C_SPD_DDREFGH_CPU0_BMC_R_SDA
  OCP_A7  I3C_SPD_DDREFGH_CPU0_BMC_R_SCL  RBT_TX_EN  @S9S_MB_2U_LIB.S9S_MB_2U(SCH_1):I3C_SPD_DDREFGH_CPU0_BMC_R_SCL
  OCP_A10  I3C_SPD_DDRABCD_CPU1_BMC_R_SDA  GND_OCP_A10  @S9S_MB_2U_LIB.S9S_MB_2U(SCH_1):I3C_SPD_DDRABCD_CPU1_BMC_R_SDA
  OCP_A9  I3C_SPD_DDRABCD_CPU1_BMC_R_SCL  RBT_TXD0  @S9S_MB_2U_LIB.S9S_MB_2U(SCH_1):I3C_SPD_DDRABCD_CPU1_BMC_R_SCL
  OCP_A6  I3C_SPD_DDRABCD_CPU0_BMC_R_SDA  SLOT_ID1  @S9S_MB_2U_LIB.S9S_MB_2U(SCH_1):I3C_SPD_DDRABCD_CPU0_BMC_R_SDA
  OCP_A5  I3C_SPD_DDRABCD_CPU0_BMC_R_SCL  RBT_ARB_OUT  @S9S_MB_2U_LIB.S9S_MB_2U(SCH_1):I3C_SPD_DDRABCD_CPU0_BMC_R_SCL
  OCP_A3  GND            WAKE#  @S9S_MB_2U_LIB.S9S_MB_2U(SCH_1):GND
  OCP_B7  GND            SLOT_ID0  @S9S_MB_2U_LIB.S9S_MB_2U(SCH_1):GND
  A14  GND            REFCLKN1  @S9S_MB_2U_LIB.S9S_MB_2U(SCH_1):GND
  OCP_A4  GND            RBT_ARB_IN  @S9S_MB_2U_LIB.S9S_MB_2U(SCH_1):GND
  A70  GND            PWRBRK#  @S9S_MB_2U_LIB.S9S_MB_2U(SCH_1):GND
  B70  GND            PRSNTB3#  @S9S_MB_2U_LIB.S9S_MB_2U(SCH_1):GND
  A42  GND            PRSNTB1#  @S9S_MB_2U_LIB.S9S_MB_2U(SCH_1):GND
  B33  GND            PETN5  @S9S_MB_2U_LIB.S9S_MB_2U(SCH_1):GND
  B26  GND            PETN3  @S9S_MB_2U_LIB.S9S_MB_2U(SCH_1):GND
  B17  GND            PETN0  @S9S_MB_2U_LIB.S9S_MB_2U(SCH_1):GND
  A11  GND            PERST1#  @S9S_MB_2U_LIB.S9S_MB_2U(SCH_1):GND
  B10  GND            PERST0#  @S9S_MB_2U_LIB.S9S_MB_2U(SCH_1):GND
  A33  GND            PERN5  @S9S_MB_2U_LIB.S9S_MB_2U(SCH_1):GND
  A20  GND            PERN1  @S9S_MB_2U_LIB.S9S_MB_2U(SCH_1):GND
  A17  GND            PERN0  @S9S_MB_2U_LIB.S9S_MB_2U(SCH_1):GND
  OCP_B10  GND            GND_OCP_B10  @S9S_MB_2U_LIB.S9S_MB_2U(SCH_1):GND
  OCP_A13  GND            GND_OCP_A13  @S9S_MB_2U_LIB.S9S_MB_2U(SCH_1):GND
  B67  GND            GND_B67  @S9S_MB_2U_LIB.S9S_MB_2U(SCH_1):GND
  B64  GND            GND_B64  @S9S_MB_2U_LIB.S9S_MB_2U(SCH_1):GND
  B61  GND            GND_B61  @S9S_MB_2U_LIB.S9S_MB_2U(SCH_1):GND
  B58  GND            GND_B58  @S9S_MB_2U_LIB.S9S_MB_2U(SCH_1):GND
  B55  GND            GND_B55  @S9S_MB_2U_LIB.S9S_MB_2U(SCH_1):GND
  B52  GND            GND_B52  @S9S_MB_2U_LIB.S9S_MB_2U(SCH_1):GND
  B49  GND            GND_B49  @S9S_MB_2U_LIB.S9S_MB_2U(SCH_1):GND
  B38  GND            GND_B38  @S9S_MB_2U_LIB.S9S_MB_2U(SCH_1):GND
  A67  GND            GND_A67  @S9S_MB_2U_LIB.S9S_MB_2U(SCH_1):GND
  A64  GND            GND_A64  @S9S_MB_2U_LIB.S9S_MB_2U(SCH_1):GND
  A61  GND            GND_A61  @S9S_MB_2U_LIB.S9S_MB_2U(SCH_1):GND
  A58  GND            GND_A58  @S9S_MB_2U_LIB.S9S_MB_2U(SCH_1):GND
  A55  GND            GND_A55  @S9S_MB_2U_LIB.S9S_MB_2U(SCH_1):GND
  A52  GND            GND_A52  @S9S_MB_2U_LIB.S9S_MB_2U(SCH_1):GND
  A43  GND            GND_A43  @S9S_MB_2U_LIB.S9S_MB_2U(SCH_1):GND
  OCP_B4  GND            DATA_IN  @S9S_MB_2U_LIB.S9S_MB_2U(SCH_1):GND
  A57  FM_SCM_PRSNT1_N  PERP12  @S9S_MB_2U_LIB.S9S_MB_2U(SCH_1):FM_SCM_PRSNT1_N
  A45  NC             PERP8  NC
   B9  FM_LPC_ESPI_SEL  BIF2#  @S9S_MB_2U_LIB.S9S_MB_2U(SCH_1):FM_LPC_ESPI_SEL
  A47  FM_BMC_PWRBTN_OUT_R_N  PERN9  @S9S_MB_2U_LIB.S9S_MB_2U(SCH_1):FM_BMC_PWRBTN_OUT_R_N
  A54  FM_BMC_CPU_FBRK_OUT_R_N  PERP11  @S9S_MB_2U_LIB.S9S_MB_2U(SCH_1):FM_BMC_CPU_FBRK_OUT_R_N
   B8  ESPI_LPC_LAD0_IO3  BIF1#  @S9S_MB_2U_LIB.S9S_MB_2U(SCH_1):ESPI_LPC_LAD0_IO3
   B7  ESPI_LPC_LAD0_IO2  BIF0#  @S9S_MB_2U_LIB.S9S_MB_2U(SCH_1):ESPI_LPC_LAD0_IO2
   B6  ESPI_LPC_LAD0_IO1  +12V_EDGE_B6  @S9S_MB_2U_LIB.S9S_MB_2U(SCH_1):ESPI_LPC_LAD0_IO1
   B5  ESPI_LPC_LAD0_IO0  +12V_EDGE_B5  @S9S_MB_2U_LIB.S9S_MB_2U(SCH_1):ESPI_LPC_LAD0_IO0
   B2  ESPI_HOST_LPC_BMC_LFRAME_N  +12V_EDGE_B2  @S9S_MB_2U_LIB.S9S_MB_2U(SCH_1):ESPI_HOST_LPC_BMC_LFRAME_N
   B1  ESPI_HOST_LPC_BMC_CLK  +12V_EDGE_B1  @S9S_MB_2U_LIB.S9S_MB_2U(SCH_1):ESPI_HOST_LPC_BMC_CLK
   B4  ESPI_BMC_LPC_RST_N  +12V_EDGE_B4  @S9S_MB_2U_LIB.S9S_MB_2U(SCH_1):ESPI_BMC_LPC_RST_N
  B18  CLK_50M_RMII_BMC_OCP  PETP0  @S9S_MB_2U_LIB.S9S_MB_2U(SCH_1):CLK_50M_RMII_BMC_OCP
  A12  CLK_100M_BMC_P3E_DP  PRSNTB2#  @S9S_MB_2U_LIB.S9S_MB_2U(SCH_1):CLK_100M_BMC_P3E_DP
  A13  CLK_100M_BMC_P3E_DN  GND_A13  @S9S_MB_2U_LIB.S9S_MB_2U(SCH_1):CLK_100M_BMC_P3E_DN

SCONN60_QSH03001LDAKTR  I44  J42    [SCONN60_QSH03001LDAKTR-SCONN60A]
   50  SMB_HOST_3V3AUX_SDA     50  @S9S_MB_2U_LIB.S9S_MB_2U(SCH_1):SMB_HOST_3V3AUX_SDA
   48  SMB_HOST_3V3AUX_SCL     48  @S9S_MB_2U_LIB.S9S_MB_2U(SCH_1):SMB_HOST_3V3AUX_SCL
    8  PD_TRST_P3         8  @S9S_MB_2U_LIB.S9S_MB_2U(SCH_1):PD_TRST_P3
   52  P3V3_AUX          52  @S9S_MB_2U_LIB.S9S_MB_2U(SCH_1):P3V3_AUX
   12  P1V8_PCH_AUX      12  @S9S_MB_2U_LIB.S9S_MB_2U(SCH_1):P1V8_PCH_AUX
    1  P1V05_PCH_AUX      1  @S9S_MB_2U_LIB.S9S_MB_2U(SCH_1):P1V05_PCH_AUX
    9  NC                 9  NC
   56  NC                56  NC
   54  NC                54  NC
   46  NC                46  NC
   44  NC                44  NC
   34  NC                34  NC
   32  NC                32  NC
   30  NC                30  NC
   28  NC                28  NC
   26  NC                26  NC
   24  NC                24  NC
   22  NC                22  NC
   20  NC                20  NC
   18  NC                18  NC
   37  JTAG_TRC_PCH_PTI<9>     37  @S9S_MB_2U_LIB.S9S_MB_2U(SCH_1):JTAG_TRC_PCH_PTI<9>
   35  JTAG_TRC_PCH_PTI<8>     35  @S9S_MB_2U_LIB.S9S_MB_2U(SCH_1):JTAG_TRC_PCH_PTI<8>
   33  JTAG_TRC_PCH_PTI<7>     33  @S9S_MB_2U_LIB.S9S_MB_2U(SCH_1):JTAG_TRC_PCH_PTI<7>
   31  JTAG_TRC_PCH_PTI<6>     31  @S9S_MB_2U_LIB.S9S_MB_2U(SCH_1):JTAG_TRC_PCH_PTI<6>
   29  JTAG_TRC_PCH_PTI<5>     29  @S9S_MB_2U_LIB.S9S_MB_2U(SCH_1):JTAG_TRC_PCH_PTI<5>
   27  JTAG_TRC_PCH_PTI<4>     27  @S9S_MB_2U_LIB.S9S_MB_2U(SCH_1):JTAG_TRC_PCH_PTI<4>
   25  JTAG_TRC_PCH_PTI<3>     25  @S9S_MB_2U_LIB.S9S_MB_2U(SCH_1):JTAG_TRC_PCH_PTI<3>
   23  JTAG_TRC_PCH_PTI<2>     23  @S9S_MB_2U_LIB.S9S_MB_2U(SCH_1):JTAG_TRC_PCH_PTI<2>
   21  JTAG_TRC_PCH_PTI<1>     21  @S9S_MB_2U_LIB.S9S_MB_2U(SCH_1):JTAG_TRC_PCH_PTI<1>
   49  JTAG_TRC_PCH_PTI<15>     49  @S9S_MB_2U_LIB.S9S_MB_2U(SCH_1):JTAG_TRC_PCH_PTI<15>
   47  JTAG_TRC_PCH_PTI<14>     47  @S9S_MB_2U_LIB.S9S_MB_2U(SCH_1):JTAG_TRC_PCH_PTI<14>
   45  JTAG_TRC_PCH_PTI<13>     45  @S9S_MB_2U_LIB.S9S_MB_2U(SCH_1):JTAG_TRC_PCH_PTI<13>
   43  JTAG_TRC_PCH_PTI<12>     43  @S9S_MB_2U_LIB.S9S_MB_2U(SCH_1):JTAG_TRC_PCH_PTI<12>
   41  JTAG_TRC_PCH_PTI<11>     41  @S9S_MB_2U_LIB.S9S_MB_2U(SCH_1):JTAG_TRC_PCH_PTI<11>
   39  JTAG_TRC_PCH_PTI<10>     39  @S9S_MB_2U_LIB.S9S_MB_2U(SCH_1):JTAG_TRC_PCH_PTI<10>
   19  JTAG_TRC_PCH_PTI<0>     19  @S9S_MB_2U_LIB.S9S_MB_2U(SCH_1):JTAG_TRC_PCH_PTI<0>
   59  JTAG_TRC_PCH_PTI1_CLK     59  @S9S_MB_2U_LIB.S9S_MB_2U(SCH_1):JTAG_TRC_PCH_PTI1_CLK
   13  JTAG_TRC_PCH_PTI0_CLK     13  @S9S_MB_2U_LIB.S9S_MB_2U(SCH_1):JTAG_TRC_PCH_PTI0_CLK
    6  JTAG_RST_DBP_RST_CO_N      6  @S9S_MB_2U_LIB.S9S_MB_2U(SCH_1):JTAG_RST_DBP_RST_CO_N
   42  JTAG_RST_DBP_RSMRST_N     42  @S9S_MB_2U_LIB.S9S_MB_2U(SCH_1):JTAG_RST_DBP_RSMRST_N
    2  JTAG_DBP_TMS_R      2  @S9S_MB_2U_LIB.S9S_MB_2U(SCH_1):JTAG_DBP_TMS_R
    4  JTAG_DBP_TDO_R      4  @S9S_MB_2U_LIB.S9S_MB_2U(SCH_1):JTAG_DBP_TDO_R
    5  JTAG_DBP_TDI_R      5  @S9S_MB_2U_LIB.S9S_MB_2U(SCH_1):JTAG_DBP_TDI_R
   51  JTAG_DBP_TCK_R_TCK     51  @S9S_MB_2U_LIB.S9S_MB_2U(SCH_1):JTAG_DBP_TCK_R_TCK
   17  JTAG_DBP_PRESENT_R_N     17  @S9S_MB_2U_LIB.S9S_MB_2U(SCH_1):JTAG_DBP_PRESENT_R_N
   10  JTAG_DBP_PREQ_N_R     10  @S9S_MB_2U_LIB.S9S_MB_2U(SCH_1):JTAG_DBP_PREQ_N_R
   11  JTAG_DBP_PRDY_R1_N     11  @S9S_MB_2U_LIB.S9S_MB_2U(SCH_1):JTAG_DBP_PRDY_R1_N
   40  JTAG_DBP_POWER_BTN_N     40  @S9S_MB_2U_LIB.S9S_MB_2U(SCH_1):JTAG_DBP_POWER_BTN_N
    7  JTAG_DBP_PMODE      7  @S9S_MB_2U_LIB.S9S_MB_2U(SCH_1):JTAG_DBP_PMODE
   15  JTAG_DBP_PCH_DEBUG_CONSENT_N     15  @S9S_MB_2U_LIB.S9S_MB_2U(SCH_1):JTAG_DBP_PCH_DEBUG_CONSENT_N
   53  JTAG_DBP_CPU_HOOK9_MBP3_GTL_N     53  @S9S_MB_2U_LIB.S9S_MB_2U(SCH_1):JTAG_DBP_CPU_HOOK9_MBP3_GTL_N
   55  JTAG_DBP_CPU_HOOK8_MBP2_GTL_N     55  @S9S_MB_2U_LIB.S9S_MB_2U(SCH_1):JTAG_DBP_CPU_HOOK8_MBP2_GTL_N
    3  JTAG_DBP_CPU_GTL_TCK_R      3  @S9S_MB_2U_LIB.S9S_MB_2U(SCH_1):JTAG_DBP_CPU_GTL_TCK_R
   36  JTAG_DBP_BOOT_HALT_N     36  @S9S_MB_2U_LIB.S9S_MB_2U(SCH_1):JTAG_DBP_BOOT_HALT_N
   G4  GND               G4  @S9S_MB_2U_LIB.S9S_MB_2U(SCH_1):GND
   G3  GND               G3  @S9S_MB_2U_LIB.S9S_MB_2U(SCH_1):GND
   G2  GND               G2  @S9S_MB_2U_LIB.S9S_MB_2U(SCH_1):GND
   G1  GND               G1  @S9S_MB_2U_LIB.S9S_MB_2U(SCH_1):GND
   60  GND               60  @S9S_MB_2U_LIB.S9S_MB_2U(SCH_1):GND
   58  GND               58  @S9S_MB_2U_LIB.S9S_MB_2U(SCH_1):GND
   57  GND               57  @S9S_MB_2U_LIB.S9S_MB_2U(SCH_1):GND
   16  GND               16  @S9S_MB_2U_LIB.S9S_MB_2U(SCH_1):GND
   14  GND               14  @S9S_MB_2U_LIB.S9S_MB_2U(SCH_1):GND
   38  FM_CPU_FBRK_DEBUG_N     38  @S9S_MB_2U_LIB.S9S_MB_2U(SCH_1):FM_CPU_FBRK_DEBUG_N

CONN10_G2100HT0038071  I42  J43    [CONN10_G2100HT0038071-CONN10_GA]
    7  NC                 7  NC
    6  NC                 6  NC
    4  P3V3_AUX           4  @S9S_MB_2U_LIB.S9S_MB_2U(SCH_1):P3V3_AUX
    8  JTAG_PLD_JTAGEN_R      8  @S9S_MB_2U_LIB.S9S_MB_2U(SCH_1):JTAG_PLD_JTAGEN_R
    5  JTAG_BMC_PLD_TMS      5  @S9S_MB_2U_LIB.S9S_MB_2U(SCH_1):JTAG_BMC_PLD_TMS
    3  JTAG_BMC_PLD_TDO      3  @S9S_MB_2U_LIB.S9S_MB_2U(SCH_1):JTAG_BMC_PLD_TDO
    9  JTAG_BMC_PLD_TDI      9  @S9S_MB_2U_LIB.S9S_MB_2U(SCH_1):JTAG_BMC_PLD_TDI
    1  JTAG_BMC_PLD_TCK      1  @S9S_MB_2U_LIB.S9S_MB_2U(SCH_1):JTAG_BMC_PLD_TCK
   10  GND               10  @S9S_MB_2U_LIB.S9S_MB_2U(SCH_1):GND
    2  GND                2  @S9S_MB_2U_LIB.S9S_MB_2U(SCH_1):GND

CONN24_52SH90245BRD  I125  J44    [CONN24_52SH90245BRD-CONN24_52SA]
   10  SMB_PMBUS_PSU1_SDA_R2     10  @S9S_MB_2U_LIB.S9S_MB_2U(SCH_1):SMB_PMBUS_PSU1_SDA_R2
    6  SMB_PMBUS_PSU1_SCL_R2      6  @S9S_MB_2U_LIB.S9S_MB_2U(SCH_1):SMB_PMBUS_PSU1_SCL_R2
   18  SMB_FAN_3V3AUX_SDA_R1     18  @S9S_MB_2U_LIB.S9S_MB_2U(SCH_1):SMB_FAN_3V3AUX_SDA_R1
   14  SMB_FAN_3V3AUX_SCL_R1     14  @S9S_MB_2U_LIB.S9S_MB_2U(SCH_1):SMB_FAN_3V3AUX_SCL_R1
   17  PWRGD_HSC_P12V_PWROK     17  @S9S_MB_2U_LIB.S9S_MB_2U(SCH_1):PWRGD_HSC_P12V_PWROK
   19  PSU1_THROTTLE_R     19  @S9S_MB_2U_LIB.S9S_MB_2U(SCH_1):PSU1_THROTTLE_R
   23  PD_MB_PRSNT       23  @S9S_MB_2U_LIB.S9S_MB_2U(SCH_1):PD_MB_PRSNT
    3  P3V3_AUX           3  @S9S_MB_2U_LIB.S9S_MB_2U(SCH_1):P3V3_AUX
    1  P3V3_AUX           1  @S9S_MB_2U_LIB.S9S_MB_2U(SCH_1):P3V3_AUX
    7  NC                 7  NC
   24  NC                24  NC
   22  NC                22  NC
   21  NC                21  NC
   15  IRQ_SML1_PMBUS_ALERT_R_N     15  @S9S_MB_2U_LIB.S9S_MB_2U(SCH_1):IRQ_SML1_PMBUS_ALERT_R_N
   13  IRQ_P12V_HSC_FAULT_N     13  @S9S_MB_2U_LIB.S9S_MB_2U(SCH_1):IRQ_P12V_HSC_FAULT_N
   20  GND               20  @S9S_MB_2U_LIB.S9S_MB_2U(SCH_1):GND
   16  GND               16  @S9S_MB_2U_LIB.S9S_MB_2U(SCH_1):GND
   12  GND               12  @S9S_MB_2U_LIB.S9S_MB_2U(SCH_1):GND
    8  GND                8  @S9S_MB_2U_LIB.S9S_MB_2U(SCH_1):GND
    5  GND                5  @S9S_MB_2U_LIB.S9S_MB_2U(SCH_1):GND
    4  GND                4  @S9S_MB_2U_LIB.S9S_MB_2U(SCH_1):GND
   11  FM_UV_ADR_TRIGGER_N     11  @S9S_MB_2U_LIB.S9S_MB_2U(SCH_1):FM_UV_ADR_TRIGGER_N
    9  FM_OV_ADR_TRIGGER_N      9  @S9S_MB_2U_LIB.S9S_MB_2U(SCH_1):FM_OV_ADR_TRIGGER_N
    2  FAN_PDB_PRSNT_N      2  @S9S_MB_2U_LIB.S9S_MB_2U(SCH_1):FAN_PDB_PRSNT_N

CONN9_2UB3903013101F  I39  J48    [CONN9_2UB3903013101F-CONN9_2UBA]
    9  USB3_9_TX_DP_FB  SSTX+  @S9S_MB_2U_LIB.S9S_MB_2U(SCH_1):USB3_9_TX_DP_FB
    8  USB3_9_TX_DN_FB  SSTX-  @S9S_MB_2U_LIB.S9S_MB_2U(SCH_1):USB3_9_TX_DN_FB
    6  USB3_9_RX_DP_FB  SSRX+  @S9S_MB_2U_LIB.S9S_MB_2U(SCH_1):USB3_9_RX_DP_FB
    5  USB3_9_RX_DN_FB  SSRX-  @S9S_MB_2U_LIB.S9S_MB_2U(SCH_1):USB3_9_RX_DN_FB
    3  USB2_1_F_DP       D+  @S9S_MB_2U_LIB.S9S_MB_2U(SCH_1):USB2_1_F_DP
    2  USB2_1_F_DN       D-  @S9S_MB_2U_LIB.S9S_MB_2U(SCH_1):USB2_1_F_DN
    1  P5V_USB_INT     VBUS  @S9S_MB_2U_LIB.S9S_MB_2U(SCH_1):P5V_USB_INT
    7  GND            GND_D  @S9S_MB_2U_LIB.S9S_MB_2U(SCH_1):GND
    4  GND              GND  @S9S_MB_2U_LIB.S9S_MB_2U(SCH_1):GND
   G4  GND               G4  @S9S_MB_2U_LIB.S9S_MB_2U(SCH_1):GND
   G3  GND               G3  @S9S_MB_2U_LIB.S9S_MB_2U(SCH_1):GND
   G2  GND               G2  @S9S_MB_2U_LIB.S9S_MB_2U(SCH_1):GND
   G1  GND               G1  @S9S_MB_2U_LIB.S9S_MB_2U(SCH_1):GND

CONN10_10142708102011LF  I2   J49    [CONN10_10142708102011LF-CONN10A]
   10  P12V_AUX          10  @S9S_MB_2U_LIB.S9S_MB_2U(SCH_1):P12V_AUX
    9  P12V_AUX           9  @S9S_MB_2U_LIB.S9S_MB_2U(SCH_1):P12V_AUX
    8  P12V_AUX           8  @S9S_MB_2U_LIB.S9S_MB_2U(SCH_1):P12V_AUX
    7  P12V_AUX           7  @S9S_MB_2U_LIB.S9S_MB_2U(SCH_1):P12V_AUX
    6  P12V_AUX           6  @S9S_MB_2U_LIB.S9S_MB_2U(SCH_1):P12V_AUX
    5  GND                5  @S9S_MB_2U_LIB.S9S_MB_2U(SCH_1):GND
    4  GND                4  @S9S_MB_2U_LIB.S9S_MB_2U(SCH_1):GND
    3  GND                3  @S9S_MB_2U_LIB.S9S_MB_2U(SCH_1):GND
    2  GND                2  @S9S_MB_2U_LIB.S9S_MB_2U(SCH_1):GND
    1  GND                1  @S9S_MB_2U_LIB.S9S_MB_2U(SCH_1):GND

CONN10_10142708102011LF  I4   J50    [CONN10_10142708102011LF-CONN10A]
   10  P12V_AUX          10  @S9S_MB_2U_LIB.S9S_MB_2U(SCH_1):P12V_AUX
    9  P12V_AUX           9  @S9S_MB_2U_LIB.S9S_MB_2U(SCH_1):P12V_AUX
    8  P12V_AUX           8  @S9S_MB_2U_LIB.S9S_MB_2U(SCH_1):P12V_AUX
    7  P12V_AUX           7  @S9S_MB_2U_LIB.S9S_MB_2U(SCH_1):P12V_AUX
    6  P12V_AUX           6  @S9S_MB_2U_LIB.S9S_MB_2U(SCH_1):P12V_AUX
    5  GND                5  @S9S_MB_2U_LIB.S9S_MB_2U(SCH_1):GND
    4  GND                4  @S9S_MB_2U_LIB.S9S_MB_2U(SCH_1):GND
    3  GND                3  @S9S_MB_2U_LIB.S9S_MB_2U(SCH_1):GND
    2  GND                2  @S9S_MB_2U_LIB.S9S_MB_2U(SCH_1):GND
    1  GND                1  @S9S_MB_2U_LIB.S9S_MB_2U(SCH_1):GND

CONN7_ABASAT054KA1  I8   J54    [CONN7_ABASAT054KA1-CONN7_ABA-SA]
    2  SATA_P11_TX_C_DP      2  @S9S_MB_2U_LIB.S9S_MB_2U(SCH_1):SATA_P11_TX_C_DP
    3  SATA_P11_TX_C_DN      3  @S9S_MB_2U_LIB.S9S_MB_2U(SCH_1):SATA_P11_TX_C_DN
    6  SATA_P11_RX_C_DP      6  @S9S_MB_2U_LIB.S9S_MB_2U(SCH_1):SATA_P11_RX_C_DP
    5  SATA_P11_RX_C_DN      5  @S9S_MB_2U_LIB.S9S_MB_2U(SCH_1):SATA_P11_RX_C_DN
   G2  GND               G2  @S9S_MB_2U_LIB.S9S_MB_2U(SCH_1):GND
   G1  GND               G1  @S9S_MB_2U_LIB.S9S_MB_2U(SCH_1):GND
    7  GND                7  @S9S_MB_2U_LIB.S9S_MB_2U(SCH_1):GND
    4  GND                4  @S9S_MB_2U_LIB.S9S_MB_2U(SCH_1):GND
    1  GND                1  @S9S_MB_2U_LIB.S9S_MB_2U(SCH_1):GND

SCONN140_G64V3431BHR  I150  J55    [SCONN140_G64V3431BHR-SCONN140_A]
   B8  SMB_RISER1_3V3AUX_SDA  SIGNAL_B8  @S9S_MB_2U_LIB.S9S_MB_2U(SCH_1):SMB_RISER1_3V3AUX_SDA
   B7  SMB_RISER1_3V3AUX_SCL  GND_B7  @S9S_MB_2U_LIB.S9S_MB_2U(SCH_1):SMB_RISER1_3V3AUX_SCL
  A10  NC             GND_A10  NC
   A9  RISER1_TYPE_ID  SIGNAL_A9  @S9S_MB_2U_LIB.S9S_MB_2U(SCH_1):RISER1_TYPE_ID
  B12  RISER1_CLK1_EN_N  SIGNAL_B12  @S9S_MB_2U_LIB.S9S_MB_2U(SCH_1):RISER1_CLK1_EN_N
  B11  RISER1_CLK0_EN_N  SIGNAL_B11  @S9S_MB_2U_LIB.S9S_MB_2U(SCH_1):RISER1_CLK0_EN_N
   B1  PD_RISER1_PRSNT1  GND_B1  @S9S_MB_2U_LIB.S9S_MB_2U(SCH_1):PD_RISER1_PRSNT1
  A70  PCIE_RISER1_PRSNT2_N  GND_A70  @S9S_MB_2U_LIB.S9S_MB_2U(SCH_1):PCIE_RISER1_PRSNT2_N
  A36  P5E_CPU0_PE2_TX_C_DP<9>  SIGNAL_A36  @S9S_MB_2U_LIB.S9S_MB_2U(SCH_1):P5E_CPU0_PE2_TX_C_DP<9>
  A39  P5E_CPU0_PE2_TX_C_DP<8>  SIGNAL_A39  @S9S_MB_2U_LIB.S9S_MB_2U(SCH_1):P5E_CPU0_PE2_TX_C_DP<8>
  A44  P5E_CPU0_PE2_TX_C_DP<7>  SIGNAL_A44  @S9S_MB_2U_LIB.S9S_MB_2U(SCH_1):P5E_CPU0_PE2_TX_C_DP<7>
  A47  P5E_CPU0_PE2_TX_C_DP<6>  SIGNAL_A47  @S9S_MB_2U_LIB.S9S_MB_2U(SCH_1):P5E_CPU0_PE2_TX_C_DP<6>
  A50  P5E_CPU0_PE2_TX_C_DP<5>  SIGNAL_A50  @S9S_MB_2U_LIB.S9S_MB_2U(SCH_1):P5E_CPU0_PE2_TX_C_DP<5>
  A53  P5E_CPU0_PE2_TX_C_DP<4>  SIGNAL_A53  @S9S_MB_2U_LIB.S9S_MB_2U(SCH_1):P5E_CPU0_PE2_TX_C_DP<4>
  A56  P5E_CPU0_PE2_TX_C_DP<3>  SIGNAL_A56  @S9S_MB_2U_LIB.S9S_MB_2U(SCH_1):P5E_CPU0_PE2_TX_C_DP<3>
  A59  P5E_CPU0_PE2_TX_C_DP<2>  SIGNAL_A59  @S9S_MB_2U_LIB.S9S_MB_2U(SCH_1):P5E_CPU0_PE2_TX_C_DP<2>
  A62  P5E_CPU0_PE2_TX_C_DP<1>  SIGNAL_A62  @S9S_MB_2U_LIB.S9S_MB_2U(SCH_1):P5E_CPU0_PE2_TX_C_DP<1>
  A17  P5E_CPU0_PE2_TX_C_DP<15>  SIGNAL_A17  @S9S_MB_2U_LIB.S9S_MB_2U(SCH_1):P5E_CPU0_PE2_TX_C_DP<15>
  A20  P5E_CPU0_PE2_TX_C_DP<14>  SIGNAL_A20  @S9S_MB_2U_LIB.S9S_MB_2U(SCH_1):P5E_CPU0_PE2_TX_C_DP<14>
  A23  P5E_CPU0_PE2_TX_C_DP<13>  SIGNAL_A23  @S9S_MB_2U_LIB.S9S_MB_2U(SCH_1):P5E_CPU0_PE2_TX_C_DP<13>
  A26  P5E_CPU0_PE2_TX_C_DP<12>  SIGNAL_A26  @S9S_MB_2U_LIB.S9S_MB_2U(SCH_1):P5E_CPU0_PE2_TX_C_DP<12>
  A30  P5E_CPU0_PE2_TX_C_DP<11>  SIGNAL_A30  @S9S_MB_2U_LIB.S9S_MB_2U(SCH_1):P5E_CPU0_PE2_TX_C_DP<11>
  A33  P5E_CPU0_PE2_TX_C_DP<10>  SIGNAL_A33  @S9S_MB_2U_LIB.S9S_MB_2U(SCH_1):P5E_CPU0_PE2_TX_C_DP<10>
  A65  P5E_CPU0_PE2_TX_C_DP<0>  SIGNAL_A65  @S9S_MB_2U_LIB.S9S_MB_2U(SCH_1):P5E_CPU0_PE2_TX_C_DP<0>
  A37  P5E_CPU0_PE2_TX_C_DN<9>  SIGNAL_A37  @S9S_MB_2U_LIB.S9S_MB_2U(SCH_1):P5E_CPU0_PE2_TX_C_DN<9>
  A40  P5E_CPU0_PE2_TX_C_DN<8>  SIGNAL_A40  @S9S_MB_2U_LIB.S9S_MB_2U(SCH_1):P5E_CPU0_PE2_TX_C_DN<8>
  A45  P5E_CPU0_PE2_TX_C_DN<7>  SIGNAL_A45  @S9S_MB_2U_LIB.S9S_MB_2U(SCH_1):P5E_CPU0_PE2_TX_C_DN<7>
  A48  P5E_CPU0_PE2_TX_C_DN<6>  SIGNAL_A48  @S9S_MB_2U_LIB.S9S_MB_2U(SCH_1):P5E_CPU0_PE2_TX_C_DN<6>
  A51  P5E_CPU0_PE2_TX_C_DN<5>  SIGNAL_A51  @S9S_MB_2U_LIB.S9S_MB_2U(SCH_1):P5E_CPU0_PE2_TX_C_DN<5>
  A54  P5E_CPU0_PE2_TX_C_DN<4>  SIGNAL_A54  @S9S_MB_2U_LIB.S9S_MB_2U(SCH_1):P5E_CPU0_PE2_TX_C_DN<4>
  A57  P5E_CPU0_PE2_TX_C_DN<3>  SIGNAL_A57  @S9S_MB_2U_LIB.S9S_MB_2U(SCH_1):P5E_CPU0_PE2_TX_C_DN<3>
  A60  P5E_CPU0_PE2_TX_C_DN<2>  SIGNAL_A60  @S9S_MB_2U_LIB.S9S_MB_2U(SCH_1):P5E_CPU0_PE2_TX_C_DN<2>
  A63  P5E_CPU0_PE2_TX_C_DN<1>  SIGNAL_A63  @S9S_MB_2U_LIB.S9S_MB_2U(SCH_1):P5E_CPU0_PE2_TX_C_DN<1>
  A18  P5E_CPU0_PE2_TX_C_DN<15>  SIGNAL_A18  @S9S_MB_2U_LIB.S9S_MB_2U(SCH_1):P5E_CPU0_PE2_TX_C_DN<15>
  A21  P5E_CPU0_PE2_TX_C_DN<14>  SIGNAL_A21  @S9S_MB_2U_LIB.S9S_MB_2U(SCH_1):P5E_CPU0_PE2_TX_C_DN<14>
  A24  P5E_CPU0_PE2_TX_C_DN<13>  SIGNAL_A24  @S9S_MB_2U_LIB.S9S_MB_2U(SCH_1):P5E_CPU0_PE2_TX_C_DN<13>
  A27  P5E_CPU0_PE2_TX_C_DN<12>  SIGNAL_A27  @S9S_MB_2U_LIB.S9S_MB_2U(SCH_1):P5E_CPU0_PE2_TX_C_DN<12>
  A31  P5E_CPU0_PE2_TX_C_DN<11>  SIGNAL_A31  @S9S_MB_2U_LIB.S9S_MB_2U(SCH_1):P5E_CPU0_PE2_TX_C_DN<11>
  A34  P5E_CPU0_PE2_TX_C_DN<10>  SIGNAL_A34  @S9S_MB_2U_LIB.S9S_MB_2U(SCH_1):P5E_CPU0_PE2_TX_C_DN<10>
  A66  P5E_CPU0_PE2_TX_C_DN<0>  SIGNAL_A66  @S9S_MB_2U_LIB.S9S_MB_2U(SCH_1):P5E_CPU0_PE2_TX_C_DN<0>
  B36  P5E_CPU0_PE2_RX_DP<9>  SIGNAL_B36  @S9S_MB_2U_LIB.S9S_MB_2U(SCH_1):P5E_CPU0_PE2_RX_DP<9>
  B39  P5E_CPU0_PE2_RX_DP<8>  SIGNAL_B39  @S9S_MB_2U_LIB.S9S_MB_2U(SCH_1):P5E_CPU0_PE2_RX_DP<8>
  B44  P5E_CPU0_PE2_RX_DP<7>  SIGNAL_B44  @S9S_MB_2U_LIB.S9S_MB_2U(SCH_1):P5E_CPU0_PE2_RX_DP<7>
  B47  P5E_CPU0_PE2_RX_DP<6>  SIGNAL_B47  @S9S_MB_2U_LIB.S9S_MB_2U(SCH_1):P5E_CPU0_PE2_RX_DP<6>
  B50  P5E_CPU0_PE2_RX_DP<5>  SIGNAL_B50  @S9S_MB_2U_LIB.S9S_MB_2U(SCH_1):P5E_CPU0_PE2_RX_DP<5>
  B53  P5E_CPU0_PE2_RX_DP<4>  SIGNAL_B53  @S9S_MB_2U_LIB.S9S_MB_2U(SCH_1):P5E_CPU0_PE2_RX_DP<4>
  B56  P5E_CPU0_PE2_RX_DP<3>  SIGNAL_B56  @S9S_MB_2U_LIB.S9S_MB_2U(SCH_1):P5E_CPU0_PE2_RX_DP<3>
  B59  P5E_CPU0_PE2_RX_DP<2>  SIGNAL_B59  @S9S_MB_2U_LIB.S9S_MB_2U(SCH_1):P5E_CPU0_PE2_RX_DP<2>
  B62  P5E_CPU0_PE2_RX_DP<1>  SIGNAL_B62  @S9S_MB_2U_LIB.S9S_MB_2U(SCH_1):P5E_CPU0_PE2_RX_DP<1>
  B17  P5E_CPU0_PE2_RX_DP<15>  SIGNAL_B17  @S9S_MB_2U_LIB.S9S_MB_2U(SCH_1):P5E_CPU0_PE2_RX_DP<15>
  B20  P5E_CPU0_PE2_RX_DP<14>  SIGNAL_B20  @S9S_MB_2U_LIB.S9S_MB_2U(SCH_1):P5E_CPU0_PE2_RX_DP<14>
  B23  P5E_CPU0_PE2_RX_DP<13>  SIGNAL_B23  @S9S_MB_2U_LIB.S9S_MB_2U(SCH_1):P5E_CPU0_PE2_RX_DP<13>
  B26  P5E_CPU0_PE2_RX_DP<12>  SIGNAL_B26  @S9S_MB_2U_LIB.S9S_MB_2U(SCH_1):P5E_CPU0_PE2_RX_DP<12>
  B30  P5E_CPU0_PE2_RX_DP<11>  SIGNAL_B30  @S9S_MB_2U_LIB.S9S_MB_2U(SCH_1):P5E_CPU0_PE2_RX_DP<11>
  B33  P5E_CPU0_PE2_RX_DP<10>  SIGNAL_B33  @S9S_MB_2U_LIB.S9S_MB_2U(SCH_1):P5E_CPU0_PE2_RX_DP<10>
  B65  P5E_CPU0_PE2_RX_DP<0>  SIGNAL_B65  @S9S_MB_2U_LIB.S9S_MB_2U(SCH_1):P5E_CPU0_PE2_RX_DP<0>
  B37  P5E_CPU0_PE2_RX_DN<9>  SIGNAL_B37  @S9S_MB_2U_LIB.S9S_MB_2U(SCH_1):P5E_CPU0_PE2_RX_DN<9>
  B40  P5E_CPU0_PE2_RX_DN<8>  SIGNAL_B40  @S9S_MB_2U_LIB.S9S_MB_2U(SCH_1):P5E_CPU0_PE2_RX_DN<8>
  B45  P5E_CPU0_PE2_RX_DN<7>  SIGNAL_B45  @S9S_MB_2U_LIB.S9S_MB_2U(SCH_1):P5E_CPU0_PE2_RX_DN<7>
  B48  P5E_CPU0_PE2_RX_DN<6>  SIGNAL_B48  @S9S_MB_2U_LIB.S9S_MB_2U(SCH_1):P5E_CPU0_PE2_RX_DN<6>
  B51  P5E_CPU0_PE2_RX_DN<5>  SIGNAL_B51  @S9S_MB_2U_LIB.S9S_MB_2U(SCH_1):P5E_CPU0_PE2_RX_DN<5>
  B54  P5E_CPU0_PE2_RX_DN<4>  SIGNAL_B54  @S9S_MB_2U_LIB.S9S_MB_2U(SCH_1):P5E_CPU0_PE2_RX_DN<4>
  B57  P5E_CPU0_PE2_RX_DN<3>  SIGNAL_B57  @S9S_MB_2U_LIB.S9S_MB_2U(SCH_1):P5E_CPU0_PE2_RX_DN<3>
  B60  P5E_CPU0_PE2_RX_DN<2>  SIGNAL_B60  @S9S_MB_2U_LIB.S9S_MB_2U(SCH_1):P5E_CPU0_PE2_RX_DN<2>
  B63  P5E_CPU0_PE2_RX_DN<1>  SIGNAL_B63  @S9S_MB_2U_LIB.S9S_MB_2U(SCH_1):P5E_CPU0_PE2_RX_DN<1>
  B18  P5E_CPU0_PE2_RX_DN<15>  SIGNAL_B18  @S9S_MB_2U_LIB.S9S_MB_2U(SCH_1):P5E_CPU0_PE2_RX_DN<15>
  B21  P5E_CPU0_PE2_RX_DN<14>  SIGNAL_B21  @S9S_MB_2U_LIB.S9S_MB_2U(SCH_1):P5E_CPU0_PE2_RX_DN<14>
  B24  P5E_CPU0_PE2_RX_DN<13>  SIGNAL_B24  @S9S_MB_2U_LIB.S9S_MB_2U(SCH_1):P5E_CPU0_PE2_RX_DN<13>
  B27  P5E_CPU0_PE2_RX_DN<12>  SIGNAL_B27  @S9S_MB_2U_LIB.S9S_MB_2U(SCH_1):P5E_CPU0_PE2_RX_DN<12>
  B31  P5E_CPU0_PE2_RX_DN<11>  SIGNAL_B31  @S9S_MB_2U_LIB.S9S_MB_2U(SCH_1):P5E_CPU0_PE2_RX_DN<11>
  B34  P5E_CPU0_PE2_RX_DN<10>  SIGNAL_B34  @S9S_MB_2U_LIB.S9S_MB_2U(SCH_1):P5E_CPU0_PE2_RX_DN<10>
  B66  P5E_CPU0_PE2_RX_DN<0>  SIGNAL_B66  @S9S_MB_2U_LIB.S9S_MB_2U(SCH_1):P5E_CPU0_PE2_RX_DN<0>
  A11  P3V3_AUX       SIGNAL_A11  @S9S_MB_2U_LIB.S9S_MB_2U(SCH_1):P3V3_AUX
  B69  P3V3           SIGNAL_B69  @S9S_MB_2U_LIB.S9S_MB_2U(SCH_1):P3V3
  A69  P3V3           SIGNAL_A69  @S9S_MB_2U_LIB.S9S_MB_2U(SCH_1):P3V3
  A68  P3V3           SIGNAL_A68  @S9S_MB_2U_LIB.S9S_MB_2U(SCH_1):P3V3
   A6  P12V_FRONT_CPU1  SIGNAL_A6  @S9S_MB_2U_LIB.S9S_MB_2U(SCH_1):P12V_FRONT_CPU1
   A5  P12V_FRONT_CPU1  SIGNAL_A5  @S9S_MB_2U_LIB.S9S_MB_2U(SCH_1):P12V_FRONT_CPU1
   A3  P12V_FRONT_CPU1  SIGNAL_A3  @S9S_MB_2U_LIB.S9S_MB_2U(SCH_1):P12V_FRONT_CPU1
   A2  P12V_FRONT_CPU1  SIGNAL_A2  @S9S_MB_2U_LIB.S9S_MB_2U(SCH_1):P12V_FRONT_CPU1
   A4  P12V_FRONT_CPU1  GND_A4  @S9S_MB_2U_LIB.S9S_MB_2U(SCH_1):P12V_FRONT_CPU1
   A1  P12V_FRONT_CPU1  GND_A1  @S9S_MB_2U_LIB.S9S_MB_2U(SCH_1):P12V_FRONT_CPU1
  A12  NC             SIGNAL_A12  NC
   B9  NC             SIGNAL_B9  NC
   A7  NC             GND_A7  NC
  B10  NC             GND_B10  NC
  B68  JTAG_RISER1_TRST_N  SIGNAL_B68  @S9S_MB_2U_LIB.S9S_MB_2U(SCH_1):JTAG_RISER1_TRST_N
  B42  JTAG_RISER1_TMS  GND_B42  @S9S_MB_2U_LIB.S9S_MB_2U(SCH_1):JTAG_RISER1_TMS
   B4  JTAG_RISER1_TDO  GND_B4  @S9S_MB_2U_LIB.S9S_MB_2U(SCH_1):JTAG_RISER1_TDO
   B3  JTAG_RISER1_TDI  SIGNAL_B3  @S9S_MB_2U_LIB.S9S_MB_2U(SCH_1):JTAG_RISER1_TDI
   B2  JTAG_RISER1_TCK  SIGNAL_B2  @S9S_MB_2U_LIB.S9S_MB_2U(SCH_1):JTAG_RISER1_TCK
  B70  IRQ_LVC3_WAKE_R1_N  GND_B70  @S9S_MB_2U_LIB.S9S_MB_2U(SCH_1):IRQ_LVC3_WAKE_R1_N
   B6  GND            SIGNAL_B6  @S9S_MB_2U_LIB.S9S_MB_2U(SCH_1):GND
   B5  GND            SIGNAL_B5  @S9S_MB_2U_LIB.S9S_MB_2U(SCH_1):GND
  B67  GND            GND_B67  @S9S_MB_2U_LIB.S9S_MB_2U(SCH_1):GND
  B64  GND            GND_B64  @S9S_MB_2U_LIB.S9S_MB_2U(SCH_1):GND
  B61  GND            GND_B61  @S9S_MB_2U_LIB.S9S_MB_2U(SCH_1):GND
  B58  GND            GND_B58  @S9S_MB_2U_LIB.S9S_MB_2U(SCH_1):GND
  B55  GND            GND_B55  @S9S_MB_2U_LIB.S9S_MB_2U(SCH_1):GND
  B52  GND            GND_B52  @S9S_MB_2U_LIB.S9S_MB_2U(SCH_1):GND
  B49  GND            GND_B49  @S9S_MB_2U_LIB.S9S_MB_2U(SCH_1):GND
  B46  GND            GND_B46  @S9S_MB_2U_LIB.S9S_MB_2U(SCH_1):GND
  B43  GND            GND_B43  @S9S_MB_2U_LIB.S9S_MB_2U(SCH_1):GND
  B41  GND            GND_B41  @S9S_MB_2U_LIB.S9S_MB_2U(SCH_1):GND
  B38  GND            GND_B38  @S9S_MB_2U_LIB.S9S_MB_2U(SCH_1):GND
  B35  GND            GND_B35  @S9S_MB_2U_LIB.S9S_MB_2U(SCH_1):GND
  B32  GND            GND_B32  @S9S_MB_2U_LIB.S9S_MB_2U(SCH_1):GND
  B29  GND            GND_B29  @S9S_MB_2U_LIB.S9S_MB_2U(SCH_1):GND
  B28  GND            GND_B28  @S9S_MB_2U_LIB.S9S_MB_2U(SCH_1):GND
  B25  GND            GND_B25  @S9S_MB_2U_LIB.S9S_MB_2U(SCH_1):GND
  B22  GND            GND_B22  @S9S_MB_2U_LIB.S9S_MB_2U(SCH_1):GND
  B19  GND            GND_B19  @S9S_MB_2U_LIB.S9S_MB_2U(SCH_1):GND
  B16  GND            GND_B16  @S9S_MB_2U_LIB.S9S_MB_2U(SCH_1):GND
  B13  GND            GND_B13  @S9S_MB_2U_LIB.S9S_MB_2U(SCH_1):GND
  A67  GND            GND_A67  @S9S_MB_2U_LIB.S9S_MB_2U(SCH_1):GND
  A64  GND            GND_A64  @S9S_MB_2U_LIB.S9S_MB_2U(SCH_1):GND
  A61  GND            GND_A61  @S9S_MB_2U_LIB.S9S_MB_2U(SCH_1):GND
  A58  GND            GND_A58  @S9S_MB_2U_LIB.S9S_MB_2U(SCH_1):GND
  A55  GND            GND_A55  @S9S_MB_2U_LIB.S9S_MB_2U(SCH_1):GND
  A52  GND            GND_A52  @S9S_MB_2U_LIB.S9S_MB_2U(SCH_1):GND
  A49  GND            GND_A49  @S9S_MB_2U_LIB.S9S_MB_2U(SCH_1):GND
  A46  GND            GND_A46  @S9S_MB_2U_LIB.S9S_MB_2U(SCH_1):GND
  A43  GND            GND_A43  @S9S_MB_2U_LIB.S9S_MB_2U(SCH_1):GND
  A42  GND            GND_A42  @S9S_MB_2U_LIB.S9S_MB_2U(SCH_1):GND
  A41  GND            GND_A41  @S9S_MB_2U_LIB.S9S_MB_2U(SCH_1):GND
  A38  GND            GND_A38  @S9S_MB_2U_LIB.S9S_MB_2U(SCH_1):GND
  A35  GND            GND_A35  @S9S_MB_2U_LIB.S9S_MB_2U(SCH_1):GND
  A32  GND            GND_A32  @S9S_MB_2U_LIB.S9S_MB_2U(SCH_1):GND
  A29  GND            GND_A29  @S9S_MB_2U_LIB.S9S_MB_2U(SCH_1):GND
  A28  GND            GND_A28  @S9S_MB_2U_LIB.S9S_MB_2U(SCH_1):GND
  A25  GND            GND_A25  @S9S_MB_2U_LIB.S9S_MB_2U(SCH_1):GND
  A22  GND            GND_A22  @S9S_MB_2U_LIB.S9S_MB_2U(SCH_1):GND
  A19  GND            GND_A19  @S9S_MB_2U_LIB.S9S_MB_2U(SCH_1):GND
  A16  GND            GND_A16  @S9S_MB_2U_LIB.S9S_MB_2U(SCH_1):GND
  A13  GND            GND_A13  @S9S_MB_2U_LIB.S9S_MB_2U(SCH_1):GND
   G8  GND               G8  @S9S_MB_2U_LIB.S9S_MB_2U(SCH_1):GND
   G7  GND               G7  @S9S_MB_2U_LIB.S9S_MB_2U(SCH_1):GND
   G6  GND               G6  @S9S_MB_2U_LIB.S9S_MB_2U(SCH_1):GND
   G5  GND               G5  @S9S_MB_2U_LIB.S9S_MB_2U(SCH_1):GND
   G4  GND               G4  @S9S_MB_2U_LIB.S9S_MB_2U(SCH_1):GND
   G3  GND               G3  @S9S_MB_2U_LIB.S9S_MB_2U(SCH_1):GND
   G2  GND               G2  @S9S_MB_2U_LIB.S9S_MB_2U(SCH_1):GND
   G1  GND               G1  @S9S_MB_2U_LIB.S9S_MB_2U(SCH_1):GND
   A8  FM_RISER1_PWRBRK_N  SIGNAL_A8  @S9S_MB_2U_LIB.S9S_MB_2U(SCH_1):FM_RISER1_PWRBRK_N
  B15  CLK_100M_PE_1_DP  SIGNAL_B15  @S9S_MB_2U_LIB.S9S_MB_2U(SCH_1):CLK_100M_PE_1_DP
  B14  CLK_100M_PE_1_DN  SIGNAL_B14  @S9S_MB_2U_LIB.S9S_MB_2U(SCH_1):CLK_100M_PE_1_DN
  A15  CLK_100M_PE_0_DP  SIGNAL_A15  @S9S_MB_2U_LIB.S9S_MB_2U(SCH_1):CLK_100M_PE_0_DP
  A14  CLK_100M_PE_0_DN  SIGNAL_A14  @S9S_MB_2U_LIB.S9S_MB_2U(SCH_1):CLK_100M_PE_0_DN

SCONN140_G64V3431BHR  I242  J57    [SCONN140_G64V3431BHR-SCONN140_A]
   B8  SMB_RISER3_3V3AUX_SDA  SIGNAL_B8  @S9S_MB_2U_LIB.S9S_MB_2U(SCH_1):SMB_RISER3_3V3AUX_SDA
   B7  SMB_RISER3_3V3AUX_SCL  GND_B7  @S9S_MB_2U_LIB.S9S_MB_2U(SCH_1):SMB_RISER3_3V3AUX_SCL
  A10  RST_PCIE_RISER3_N  GND_A10  @S9S_MB_2U_LIB.S9S_MB_2U(SCH_1):RST_PCIE_RISER3_N
   A9  RISER3_TYPE_ID  SIGNAL_A9  @S9S_MB_2U_LIB.S9S_MB_2U(SCH_1):RISER3_TYPE_ID
  B12  RISER3_CLK5_EN_N  SIGNAL_B12  @S9S_MB_2U_LIB.S9S_MB_2U(SCH_1):RISER3_CLK5_EN_N
  B11  RISER3_CLK4_EN_N  SIGNAL_B11  @S9S_MB_2U_LIB.S9S_MB_2U(SCH_1):RISER3_CLK4_EN_N
   B1  PD_RISER3_PRSNT1  GND_B1  @S9S_MB_2U_LIB.S9S_MB_2U(SCH_1):PD_RISER3_PRSNT1
  A70  PCIE_RISER3_PRSNT2_N  GND_A70  @S9S_MB_2U_LIB.S9S_MB_2U(SCH_1):PCIE_RISER3_PRSNT2_N
  A36  P5E_CPU1_PE1_TX_C_DP<9>  SIGNAL_A36  @S9S_MB_2U_LIB.S9S_MB_2U(SCH_1):P5E_CPU1_PE1_TX_C_DP<9>
  A39  P5E_CPU1_PE1_TX_C_DP<8>  SIGNAL_A39  @S9S_MB_2U_LIB.S9S_MB_2U(SCH_1):P5E_CPU1_PE1_TX_C_DP<8>
  A44  P5E_CPU1_PE1_TX_C_DP<7>  SIGNAL_A44  @S9S_MB_2U_LIB.S9S_MB_2U(SCH_1):P5E_CPU1_PE1_TX_C_DP<7>
  A47  P5E_CPU1_PE1_TX_C_DP<6>  SIGNAL_A47  @S9S_MB_2U_LIB.S9S_MB_2U(SCH_1):P5E_CPU1_PE1_TX_C_DP<6>
  A50  P5E_CPU1_PE1_TX_C_DP<5>  SIGNAL_A50  @S9S_MB_2U_LIB.S9S_MB_2U(SCH_1):P5E_CPU1_PE1_TX_C_DP<5>
  A53  P5E_CPU1_PE1_TX_C_DP<4>  SIGNAL_A53  @S9S_MB_2U_LIB.S9S_MB_2U(SCH_1):P5E_CPU1_PE1_TX_C_DP<4>
  A56  P5E_CPU1_PE1_TX_C_DP<3>  SIGNAL_A56  @S9S_MB_2U_LIB.S9S_MB_2U(SCH_1):P5E_CPU1_PE1_TX_C_DP<3>
  A59  P5E_CPU1_PE1_TX_C_DP<2>  SIGNAL_A59  @S9S_MB_2U_LIB.S9S_MB_2U(SCH_1):P5E_CPU1_PE1_TX_C_DP<2>
  A62  P5E_CPU1_PE1_TX_C_DP<1>  SIGNAL_A62  @S9S_MB_2U_LIB.S9S_MB_2U(SCH_1):P5E_CPU1_PE1_TX_C_DP<1>
  A17  P5E_CPU1_PE1_TX_C_DP<15>  SIGNAL_A17  @S9S_MB_2U_LIB.S9S_MB_2U(SCH_1):P5E_CPU1_PE1_TX_C_DP<15>
  A20  P5E_CPU1_PE1_TX_C_DP<14>  SIGNAL_A20  @S9S_MB_2U_LIB.S9S_MB_2U(SCH_1):P5E_CPU1_PE1_TX_C_DP<14>
  A23  P5E_CPU1_PE1_TX_C_DP<13>  SIGNAL_A23  @S9S_MB_2U_LIB.S9S_MB_2U(SCH_1):P5E_CPU1_PE1_TX_C_DP<13>
  A26  P5E_CPU1_PE1_TX_C_DP<12>  SIGNAL_A26  @S9S_MB_2U_LIB.S9S_MB_2U(SCH_1):P5E_CPU1_PE1_TX_C_DP<12>
  A30  P5E_CPU1_PE1_TX_C_DP<11>  SIGNAL_A30  @S9S_MB_2U_LIB.S9S_MB_2U(SCH_1):P5E_CPU1_PE1_TX_C_DP<11>
  A33  P5E_CPU1_PE1_TX_C_DP<10>  SIGNAL_A33  @S9S_MB_2U_LIB.S9S_MB_2U(SCH_1):P5E_CPU1_PE1_TX_C_DP<10>
  A65  P5E_CPU1_PE1_TX_C_DP<0>  SIGNAL_A65  @S9S_MB_2U_LIB.S9S_MB_2U(SCH_1):P5E_CPU1_PE1_TX_C_DP<0>
  A37  P5E_CPU1_PE1_TX_C_DN<9>  SIGNAL_A37  @S9S_MB_2U_LIB.S9S_MB_2U(SCH_1):P5E_CPU1_PE1_TX_C_DN<9>
  A40  P5E_CPU1_PE1_TX_C_DN<8>  SIGNAL_A40  @S9S_MB_2U_LIB.S9S_MB_2U(SCH_1):P5E_CPU1_PE1_TX_C_DN<8>
  A45  P5E_CPU1_PE1_TX_C_DN<7>  SIGNAL_A45  @S9S_MB_2U_LIB.S9S_MB_2U(SCH_1):P5E_CPU1_PE1_TX_C_DN<7>
  A48  P5E_CPU1_PE1_TX_C_DN<6>  SIGNAL_A48  @S9S_MB_2U_LIB.S9S_MB_2U(SCH_1):P5E_CPU1_PE1_TX_C_DN<6>
  A51  P5E_CPU1_PE1_TX_C_DN<5>  SIGNAL_A51  @S9S_MB_2U_LIB.S9S_MB_2U(SCH_1):P5E_CPU1_PE1_TX_C_DN<5>
  A54  P5E_CPU1_PE1_TX_C_DN<4>  SIGNAL_A54  @S9S_MB_2U_LIB.S9S_MB_2U(SCH_1):P5E_CPU1_PE1_TX_C_DN<4>
  A57  P5E_CPU1_PE1_TX_C_DN<3>  SIGNAL_A57  @S9S_MB_2U_LIB.S9S_MB_2U(SCH_1):P5E_CPU1_PE1_TX_C_DN<3>
  A60  P5E_CPU1_PE1_TX_C_DN<2>  SIGNAL_A60  @S9S_MB_2U_LIB.S9S_MB_2U(SCH_1):P5E_CPU1_PE1_TX_C_DN<2>
  A63  P5E_CPU1_PE1_TX_C_DN<1>  SIGNAL_A63  @S9S_MB_2U_LIB.S9S_MB_2U(SCH_1):P5E_CPU1_PE1_TX_C_DN<1>
  A18  P5E_CPU1_PE1_TX_C_DN<15>  SIGNAL_A18  @S9S_MB_2U_LIB.S9S_MB_2U(SCH_1):P5E_CPU1_PE1_TX_C_DN<15>
  A21  P5E_CPU1_PE1_TX_C_DN<14>  SIGNAL_A21  @S9S_MB_2U_LIB.S9S_MB_2U(SCH_1):P5E_CPU1_PE1_TX_C_DN<14>
  A24  P5E_CPU1_PE1_TX_C_DN<13>  SIGNAL_A24  @S9S_MB_2U_LIB.S9S_MB_2U(SCH_1):P5E_CPU1_PE1_TX_C_DN<13>
  A27  P5E_CPU1_PE1_TX_C_DN<12>  SIGNAL_A27  @S9S_MB_2U_LIB.S9S_MB_2U(SCH_1):P5E_CPU1_PE1_TX_C_DN<12>
  A31  P5E_CPU1_PE1_TX_C_DN<11>  SIGNAL_A31  @S9S_MB_2U_LIB.S9S_MB_2U(SCH_1):P5E_CPU1_PE1_TX_C_DN<11>
  A34  P5E_CPU1_PE1_TX_C_DN<10>  SIGNAL_A34  @S9S_MB_2U_LIB.S9S_MB_2U(SCH_1):P5E_CPU1_PE1_TX_C_DN<10>
  A66  P5E_CPU1_PE1_TX_C_DN<0>  SIGNAL_A66  @S9S_MB_2U_LIB.S9S_MB_2U(SCH_1):P5E_CPU1_PE1_TX_C_DN<0>
  B36  P5E_CPU1_PE1_RX_DP<9>  SIGNAL_B36  @S9S_MB_2U_LIB.S9S_MB_2U(SCH_1):P5E_CPU1_PE1_RX_DP<9>
  B39  P5E_CPU1_PE1_RX_DP<8>  SIGNAL_B39  @S9S_MB_2U_LIB.S9S_MB_2U(SCH_1):P5E_CPU1_PE1_RX_DP<8>
  B44  P5E_CPU1_PE1_RX_DP<7>  SIGNAL_B44  @S9S_MB_2U_LIB.S9S_MB_2U(SCH_1):P5E_CPU1_PE1_RX_DP<7>
  B47  P5E_CPU1_PE1_RX_DP<6>  SIGNAL_B47  @S9S_MB_2U_LIB.S9S_MB_2U(SCH_1):P5E_CPU1_PE1_RX_DP<6>
  B50  P5E_CPU1_PE1_RX_DP<5>  SIGNAL_B50  @S9S_MB_2U_LIB.S9S_MB_2U(SCH_1):P5E_CPU1_PE1_RX_DP<5>
  B53  P5E_CPU1_PE1_RX_DP<4>  SIGNAL_B53  @S9S_MB_2U_LIB.S9S_MB_2U(SCH_1):P5E_CPU1_PE1_RX_DP<4>
  B56  P5E_CPU1_PE1_RX_DP<3>  SIGNAL_B56  @S9S_MB_2U_LIB.S9S_MB_2U(SCH_1):P5E_CPU1_PE1_RX_DP<3>
  B59  P5E_CPU1_PE1_RX_DP<2>  SIGNAL_B59  @S9S_MB_2U_LIB.S9S_MB_2U(SCH_1):P5E_CPU1_PE1_RX_DP<2>
  B62  P5E_CPU1_PE1_RX_DP<1>  SIGNAL_B62  @S9S_MB_2U_LIB.S9S_MB_2U(SCH_1):P5E_CPU1_PE1_RX_DP<1>
  B17  P5E_CPU1_PE1_RX_DP<15>  SIGNAL_B17  @S9S_MB_2U_LIB.S9S_MB_2U(SCH_1):P5E_CPU1_PE1_RX_DP<15>
  B20  P5E_CPU1_PE1_RX_DP<14>  SIGNAL_B20  @S9S_MB_2U_LIB.S9S_MB_2U(SCH_1):P5E_CPU1_PE1_RX_DP<14>
  B23  P5E_CPU1_PE1_RX_DP<13>  SIGNAL_B23  @S9S_MB_2U_LIB.S9S_MB_2U(SCH_1):P5E_CPU1_PE1_RX_DP<13>
  B26  P5E_CPU1_PE1_RX_DP<12>  SIGNAL_B26  @S9S_MB_2U_LIB.S9S_MB_2U(SCH_1):P5E_CPU1_PE1_RX_DP<12>
  B30  P5E_CPU1_PE1_RX_DP<11>  SIGNAL_B30  @S9S_MB_2U_LIB.S9S_MB_2U(SCH_1):P5E_CPU1_PE1_RX_DP<11>
  B33  P5E_CPU1_PE1_RX_DP<10>  SIGNAL_B33  @S9S_MB_2U_LIB.S9S_MB_2U(SCH_1):P5E_CPU1_PE1_RX_DP<10>
  B65  P5E_CPU1_PE1_RX_DP<0>  SIGNAL_B65  @S9S_MB_2U_LIB.S9S_MB_2U(SCH_1):P5E_CPU1_PE1_RX_DP<0>
  B37  P5E_CPU1_PE1_RX_DN<9>  SIGNAL_B37  @S9S_MB_2U_LIB.S9S_MB_2U(SCH_1):P5E_CPU1_PE1_RX_DN<9>
  B40  P5E_CPU1_PE1_RX_DN<8>  SIGNAL_B40  @S9S_MB_2U_LIB.S9S_MB_2U(SCH_1):P5E_CPU1_PE1_RX_DN<8>
  B45  P5E_CPU1_PE1_RX_DN<7>  SIGNAL_B45  @S9S_MB_2U_LIB.S9S_MB_2U(SCH_1):P5E_CPU1_PE1_RX_DN<7>
  B48  P5E_CPU1_PE1_RX_DN<6>  SIGNAL_B48  @S9S_MB_2U_LIB.S9S_MB_2U(SCH_1):P5E_CPU1_PE1_RX_DN<6>
  B51  P5E_CPU1_PE1_RX_DN<5>  SIGNAL_B51  @S9S_MB_2U_LIB.S9S_MB_2U(SCH_1):P5E_CPU1_PE1_RX_DN<5>
  B54  P5E_CPU1_PE1_RX_DN<4>  SIGNAL_B54  @S9S_MB_2U_LIB.S9S_MB_2U(SCH_1):P5E_CPU1_PE1_RX_DN<4>
  B57  P5E_CPU1_PE1_RX_DN<3>  SIGNAL_B57  @S9S_MB_2U_LIB.S9S_MB_2U(SCH_1):P5E_CPU1_PE1_RX_DN<3>
  B60  P5E_CPU1_PE1_RX_DN<2>  SIGNAL_B60  @S9S_MB_2U_LIB.S9S_MB_2U(SCH_1):P5E_CPU1_PE1_RX_DN<2>
  B63  P5E_CPU1_PE1_RX_DN<1>  SIGNAL_B63  @S9S_MB_2U_LIB.S9S_MB_2U(SCH_1):P5E_CPU1_PE1_RX_DN<1>
  B18  P5E_CPU1_PE1_RX_DN<15>  SIGNAL_B18  @S9S_MB_2U_LIB.S9S_MB_2U(SCH_1):P5E_CPU1_PE1_RX_DN<15>
  B21  P5E_CPU1_PE1_RX_DN<14>  SIGNAL_B21  @S9S_MB_2U_LIB.S9S_MB_2U(SCH_1):P5E_CPU1_PE1_RX_DN<14>
  B24  P5E_CPU1_PE1_RX_DN<13>  SIGNAL_B24  @S9S_MB_2U_LIB.S9S_MB_2U(SCH_1):P5E_CPU1_PE1_RX_DN<13>
  B27  P5E_CPU1_PE1_RX_DN<12>  SIGNAL_B27  @S9S_MB_2U_LIB.S9S_MB_2U(SCH_1):P5E_CPU1_PE1_RX_DN<12>
  B31  P5E_CPU1_PE1_RX_DN<11>  SIGNAL_B31  @S9S_MB_2U_LIB.S9S_MB_2U(SCH_1):P5E_CPU1_PE1_RX_DN<11>
  B34  P5E_CPU1_PE1_RX_DN<10>  SIGNAL_B34  @S9S_MB_2U_LIB.S9S_MB_2U(SCH_1):P5E_CPU1_PE1_RX_DN<10>
  B66  P5E_CPU1_PE1_RX_DN<0>  SIGNAL_B66  @S9S_MB_2U_LIB.S9S_MB_2U(SCH_1):P5E_CPU1_PE1_RX_DN<0>
  A11  P3V3_AUX       SIGNAL_A11  @S9S_MB_2U_LIB.S9S_MB_2U(SCH_1):P3V3_AUX
  B69  P3V3           SIGNAL_B69  @S9S_MB_2U_LIB.S9S_MB_2U(SCH_1):P3V3
  A69  P3V3           SIGNAL_A69  @S9S_MB_2U_LIB.S9S_MB_2U(SCH_1):P3V3
  A68  P3V3           SIGNAL_A68  @S9S_MB_2U_LIB.S9S_MB_2U(SCH_1):P3V3
   A6  P12V_FRONT_CPU1  SIGNAL_A6  @S9S_MB_2U_LIB.S9S_MB_2U(SCH_1):P12V_FRONT_CPU1
   A5  P12V_FRONT_CPU1  SIGNAL_A5  @S9S_MB_2U_LIB.S9S_MB_2U(SCH_1):P12V_FRONT_CPU1
   A3  P12V_FRONT_CPU1  SIGNAL_A3  @S9S_MB_2U_LIB.S9S_MB_2U(SCH_1):P12V_FRONT_CPU1
   A2  P12V_FRONT_CPU1  SIGNAL_A2  @S9S_MB_2U_LIB.S9S_MB_2U(SCH_1):P12V_FRONT_CPU1
   A4  P12V_FRONT_CPU1  GND_A4  @S9S_MB_2U_LIB.S9S_MB_2U(SCH_1):P12V_FRONT_CPU1
   A1  P12V_FRONT_CPU1  GND_A1  @S9S_MB_2U_LIB.S9S_MB_2U(SCH_1):P12V_FRONT_CPU1
  A12  NC             SIGNAL_A12  NC
   B9  NC             SIGNAL_B9  NC
   A7  NC             GND_A7  NC
  B10  NC             GND_B10  NC
  B68  JTAG_RISER3_TRST_N  SIGNAL_B68  @S9S_MB_2U_LIB.S9S_MB_2U(SCH_1):JTAG_RISER3_TRST_N
  B42  JTAG_RISER3_TMS  GND_B42  @S9S_MB_2U_LIB.S9S_MB_2U(SCH_1):JTAG_RISER3_TMS
   B4  JTAG_RISER3_TDO  GND_B4  @S9S_MB_2U_LIB.S9S_MB_2U(SCH_1):JTAG_RISER3_TDO
   B3  JTAG_RISER3_TDI  SIGNAL_B3  @S9S_MB_2U_LIB.S9S_MB_2U(SCH_1):JTAG_RISER3_TDI
   B2  JTAG_RISER3_TCK  SIGNAL_B2  @S9S_MB_2U_LIB.S9S_MB_2U(SCH_1):JTAG_RISER3_TCK
  B70  IRQ_LVC3_WAKE_R3_N  GND_B70  @S9S_MB_2U_LIB.S9S_MB_2U(SCH_1):IRQ_LVC3_WAKE_R3_N
   B6  GND            SIGNAL_B6  @S9S_MB_2U_LIB.S9S_MB_2U(SCH_1):GND
   B5  GND            SIGNAL_B5  @S9S_MB_2U_LIB.S9S_MB_2U(SCH_1):GND
  B67  GND            GND_B67  @S9S_MB_2U_LIB.S9S_MB_2U(SCH_1):GND
  B64  GND            GND_B64  @S9S_MB_2U_LIB.S9S_MB_2U(SCH_1):GND
  B61  GND            GND_B61  @S9S_MB_2U_LIB.S9S_MB_2U(SCH_1):GND
  B58  GND            GND_B58  @S9S_MB_2U_LIB.S9S_MB_2U(SCH_1):GND
  B55  GND            GND_B55  @S9S_MB_2U_LIB.S9S_MB_2U(SCH_1):GND
  B52  GND            GND_B52  @S9S_MB_2U_LIB.S9S_MB_2U(SCH_1):GND
  B49  GND            GND_B49  @S9S_MB_2U_LIB.S9S_MB_2U(SCH_1):GND
  B46  GND            GND_B46  @S9S_MB_2U_LIB.S9S_MB_2U(SCH_1):GND
  B43  GND            GND_B43  @S9S_MB_2U_LIB.S9S_MB_2U(SCH_1):GND
  B41  GND            GND_B41  @S9S_MB_2U_LIB.S9S_MB_2U(SCH_1):GND
  B38  GND            GND_B38  @S9S_MB_2U_LIB.S9S_MB_2U(SCH_1):GND
  B35  GND            GND_B35  @S9S_MB_2U_LIB.S9S_MB_2U(SCH_1):GND
  B32  GND            GND_B32  @S9S_MB_2U_LIB.S9S_MB_2U(SCH_1):GND
  B29  GND            GND_B29  @S9S_MB_2U_LIB.S9S_MB_2U(SCH_1):GND
  B28  GND            GND_B28  @S9S_MB_2U_LIB.S9S_MB_2U(SCH_1):GND
  B25  GND            GND_B25  @S9S_MB_2U_LIB.S9S_MB_2U(SCH_1):GND
  B22  GND            GND_B22  @S9S_MB_2U_LIB.S9S_MB_2U(SCH_1):GND
  B19  GND            GND_B19  @S9S_MB_2U_LIB.S9S_MB_2U(SCH_1):GND
  B16  GND            GND_B16  @S9S_MB_2U_LIB.S9S_MB_2U(SCH_1):GND
  B13  GND            GND_B13  @S9S_MB_2U_LIB.S9S_MB_2U(SCH_1):GND
  A67  GND            GND_A67  @S9S_MB_2U_LIB.S9S_MB_2U(SCH_1):GND
  A64  GND            GND_A64  @S9S_MB_2U_LIB.S9S_MB_2U(SCH_1):GND
  A61  GND            GND_A61  @S9S_MB_2U_LIB.S9S_MB_2U(SCH_1):GND
  A58  GND            GND_A58  @S9S_MB_2U_LIB.S9S_MB_2U(SCH_1):GND
  A55  GND            GND_A55  @S9S_MB_2U_LIB.S9S_MB_2U(SCH_1):GND
  A52  GND            GND_A52  @S9S_MB_2U_LIB.S9S_MB_2U(SCH_1):GND
  A49  GND            GND_A49  @S9S_MB_2U_LIB.S9S_MB_2U(SCH_1):GND
  A46  GND            GND_A46  @S9S_MB_2U_LIB.S9S_MB_2U(SCH_1):GND
  A43  GND            GND_A43  @S9S_MB_2U_LIB.S9S_MB_2U(SCH_1):GND
  A42  GND            GND_A42  @S9S_MB_2U_LIB.S9S_MB_2U(SCH_1):GND
  A41  GND            GND_A41  @S9S_MB_2U_LIB.S9S_MB_2U(SCH_1):GND
  A38  GND            GND_A38  @S9S_MB_2U_LIB.S9S_MB_2U(SCH_1):GND
  A35  GND            GND_A35  @S9S_MB_2U_LIB.S9S_MB_2U(SCH_1):GND
  A32  GND            GND_A32  @S9S_MB_2U_LIB.S9S_MB_2U(SCH_1):GND
  A29  GND            GND_A29  @S9S_MB_2U_LIB.S9S_MB_2U(SCH_1):GND
  A28  GND            GND_A28  @S9S_MB_2U_LIB.S9S_MB_2U(SCH_1):GND
  A25  GND            GND_A25  @S9S_MB_2U_LIB.S9S_MB_2U(SCH_1):GND
  A22  GND            GND_A22  @S9S_MB_2U_LIB.S9S_MB_2U(SCH_1):GND
  A19  GND            GND_A19  @S9S_MB_2U_LIB.S9S_MB_2U(SCH_1):GND
  A16  GND            GND_A16  @S9S_MB_2U_LIB.S9S_MB_2U(SCH_1):GND
  A13  GND            GND_A13  @S9S_MB_2U_LIB.S9S_MB_2U(SCH_1):GND
   G8  GND               G8  @S9S_MB_2U_LIB.S9S_MB_2U(SCH_1):GND
   G7  GND               G7  @S9S_MB_2U_LIB.S9S_MB_2U(SCH_1):GND
   G6  GND               G6  @S9S_MB_2U_LIB.S9S_MB_2U(SCH_1):GND
   G5  GND               G5  @S9S_MB_2U_LIB.S9S_MB_2U(SCH_1):GND
   G4  GND               G4  @S9S_MB_2U_LIB.S9S_MB_2U(SCH_1):GND
   G3  GND               G3  @S9S_MB_2U_LIB.S9S_MB_2U(SCH_1):GND
   G2  GND               G2  @S9S_MB_2U_LIB.S9S_MB_2U(SCH_1):GND
   G1  GND               G1  @S9S_MB_2U_LIB.S9S_MB_2U(SCH_1):GND
   A8  FM_RISER3_PWRBRK_N  SIGNAL_A8  @S9S_MB_2U_LIB.S9S_MB_2U(SCH_1):FM_RISER3_PWRBRK_N
  B15  CLK_100M_PE_5_DP  SIGNAL_B15  @S9S_MB_2U_LIB.S9S_MB_2U(SCH_1):CLK_100M_PE_5_DP
  B14  CLK_100M_PE_5_DN  SIGNAL_B14  @S9S_MB_2U_LIB.S9S_MB_2U(SCH_1):CLK_100M_PE_5_DN
  A15  CLK_100M_PE_4_DP  SIGNAL_A15  @S9S_MB_2U_LIB.S9S_MB_2U(SCH_1):CLK_100M_PE_4_DP
  A14  CLK_100M_PE_4_DN  SIGNAL_A14  @S9S_MB_2U_LIB.S9S_MB_2U(SCH_1):CLK_100M_PE_4_DN

SCONN75K_APCI0155P004A  I178  J59    [SCONN75K_APCI0155P004A-SCONN75A]
   42  SMB_M2_P0_1V8AUX_SDA   NC13  @S9S_MB_2U_LIB.S9S_MB_2U(SCH_1):SMB_M2_P0_1V8AUX_SDA
   40  SMB_M2_P0_1V8AUX_SCL   NC12  @S9S_MB_2U_LIB.S9S_MB_2U(SCH_1):SMB_M2_P0_1V8AUX_SCL
   50  RST_PCIE_PCH_DEV_0_N  PERST#  @S9S_MB_2U_LIB.S9S_MB_2U(SCH_1):RST_PCIE_PCH_DEV_0_N
   10  PU_DAS_DSS_N   DAS_DSS#||LED1#  @S9S_MB_2U_LIB.S9S_MB_2U(SCH_1):PU_DAS_DSS_N
   38  PD_M2_1_DEVSLP  DEVSLP  @S9S_MB_2U_LIB.S9S_MB_2U(SCH_1):PD_M2_1_DEVSLP
    1  PCIE_M2_SSD0_PRSNT_N   GND1  @S9S_MB_2U_LIB.S9S_MB_2U(SCH_1):PCIE_M2_SSD0_PRSNT_N
   74  P3V3           3.3V_9  @S9S_MB_2U_LIB.S9S_MB_2U(SCH_1):P3V3
   72  P3V3           3.3V_8  @S9S_MB_2U_LIB.S9S_MB_2U(SCH_1):P3V3
   70  P3V3           3.3V_7  @S9S_MB_2U_LIB.S9S_MB_2U(SCH_1):P3V3
   18  P3V3           3.3V_6  @S9S_MB_2U_LIB.S9S_MB_2U(SCH_1):P3V3
   16  P3V3           3.3V_5  @S9S_MB_2U_LIB.S9S_MB_2U(SCH_1):P3V3
   14  P3V3           3.3V_4  @S9S_MB_2U_LIB.S9S_MB_2U(SCH_1):P3V3
   12  P3V3           3.3V_3  @S9S_MB_2U_LIB.S9S_MB_2U(SCH_1):P3V3
    4  P3V3           3.3V_2  @S9S_MB_2U_LIB.S9S_MB_2U(SCH_1):P3V3
    2  P3V3           3.3V_1  @S9S_MB_2U_LIB.S9S_MB_2U(SCH_1):P3V3
   49  P3E_PCH_M2_TX_C_DP<3>  PETP0||SATA-A+  @S9S_MB_2U_LIB.S9S_MB_2U(SCH_1):P3E_PCH_M2_TX_C_DP<3>
   35  P3E_PCH_M2_TX_C_DP<2>  PETN1  @S9S_MB_2U_LIB.S9S_MB_2U(SCH_1):P3E_PCH_M2_TX_C_DP<2>
   23  P3E_PCH_M2_TX_C_DP<1>  PETN2  @S9S_MB_2U_LIB.S9S_MB_2U(SCH_1):P3E_PCH_M2_TX_C_DP<1>
   11  P3E_PCH_M2_TX_C_DP<0>  PETN3  @S9S_MB_2U_LIB.S9S_MB_2U(SCH_1):P3E_PCH_M2_TX_C_DP<0>
   47  P3E_PCH_M2_TX_C_DN<3>  PETN0||SATA-A-  @S9S_MB_2U_LIB.S9S_MB_2U(SCH_1):P3E_PCH_M2_TX_C_DN<3>
   37  P3E_PCH_M2_TX_C_DN<2>  PETP1  @S9S_MB_2U_LIB.S9S_MB_2U(SCH_1):P3E_PCH_M2_TX_C_DN<2>
   25  P3E_PCH_M2_TX_C_DN<1>  PETP2  @S9S_MB_2U_LIB.S9S_MB_2U(SCH_1):P3E_PCH_M2_TX_C_DN<1>
   13  P3E_PCH_M2_TX_C_DN<0>  PETP3  @S9S_MB_2U_LIB.S9S_MB_2U(SCH_1):P3E_PCH_M2_TX_C_DN<0>
   31  P3E_PCH_M2_RX_DP<2>  PERP1  @S9S_MB_2U_LIB.S9S_MB_2U(SCH_1):P3E_PCH_M2_RX_DP<2>
   19  P3E_PCH_M2_RX_DP<1>  PERP2  @S9S_MB_2U_LIB.S9S_MB_2U(SCH_1):P3E_PCH_M2_RX_DP<1>
    7  P3E_PCH_M2_RX_DP<0>  PERP3  @S9S_MB_2U_LIB.S9S_MB_2U(SCH_1):P3E_PCH_M2_RX_DP<0>
   29  P3E_PCH_M2_RX_DN<2>  PERN1  @S9S_MB_2U_LIB.S9S_MB_2U(SCH_1):P3E_PCH_M2_RX_DN<2>
   17  P3E_PCH_M2_RX_DN<1>  PERN2  @S9S_MB_2U_LIB.S9S_MB_2U(SCH_1):P3E_PCH_M2_RX_DN<1>
    5  P3E_PCH_M2_RX_DN<0>  PERN3  @S9S_MB_2U_LIB.S9S_MB_2U(SCH_1):P3E_PCH_M2_RX_DN<0>
   41  P3E_PCH_M2_RX_C_DP<3>  PERN0||SATA-B+  @S9S_MB_2U_LIB.S9S_MB_2U(SCH_1):P3E_PCH_M2_RX_C_DP<3>
   43  P3E_PCH_M2_RX_C_DN<3>  PERP0||SATA-B-  @S9S_MB_2U_LIB.S9S_MB_2U(SCH_1):P3E_PCH_M2_RX_C_DN<3>
   68  NC             SUSCLK  NC
   54  NC             PEWAKE#  NC
   32  NC               NC9  NC
   30  NC               NC8  NC
   28  NC               NC7  NC
   26  NC               NC6  NC
   24  NC               NC5  NC
   22  NC               NC4  NC
   20  NC               NC3  NC
    8  NC               NC2  NC
   67  NC              NC19  NC
   58  NC              NC18  NC
   56  NC              NC17  NC
   48  NC              NC16  NC
   46  NC              NC15  NC
   44  NC              NC14  NC
   36  NC              NC11  NC
   34  NC              NC10  NC
    6  NC               NC1  NC
   52  M2_SSD0_CLKREQ_EN_N_BUF  CLKREQ#  @S9S_MB_2U_LIB.S9S_MB_2U(SCH_1):M2_SSD0_CLKREQ_EN_N_BUF
   75  GND            GND14  @S9S_MB_2U_LIB.S9S_MB_2U(SCH_1):GND
   73  GND            GND13  @S9S_MB_2U_LIB.S9S_MB_2U(SCH_1):GND
   71  GND            GND12  @S9S_MB_2U_LIB.S9S_MB_2U(SCH_1):GND
   57  GND            GND11  @S9S_MB_2U_LIB.S9S_MB_2U(SCH_1):GND
   51  GND            GND10  @S9S_MB_2U_LIB.S9S_MB_2U(SCH_1):GND
   45  GND             GND9  @S9S_MB_2U_LIB.S9S_MB_2U(SCH_1):GND
   39  GND             GND8  @S9S_MB_2U_LIB.S9S_MB_2U(SCH_1):GND
   33  GND             GND7  @S9S_MB_2U_LIB.S9S_MB_2U(SCH_1):GND
   27  GND             GND6  @S9S_MB_2U_LIB.S9S_MB_2U(SCH_1):GND
   21  GND             GND5  @S9S_MB_2U_LIB.S9S_MB_2U(SCH_1):GND
   15  GND             GND4  @S9S_MB_2U_LIB.S9S_MB_2U(SCH_1):GND
    9  GND             GND3  @S9S_MB_2U_LIB.S9S_MB_2U(SCH_1):GND
    3  GND             GND2  @S9S_MB_2U_LIB.S9S_MB_2U(SCH_1):GND
   G2  GND               G2  @S9S_MB_2U_LIB.S9S_MB_2U(SCH_1):GND
   G1  GND               G1  @S9S_MB_2U_LIB.S9S_MB_2U(SCH_1):GND
   69  FM_M2_SSD_1_PEDET  PEDET  @S9S_MB_2U_LIB.S9S_MB_2U(SCH_1):FM_M2_SSD_1_PEDET
   55  CLK_100M_PE_M2_0_DP  REFCLKP  @S9S_MB_2U_LIB.S9S_MB_2U(SCH_1):CLK_100M_PE_M2_0_DP
   53  CLK_100M_PE_M2_0_DN  REFCLKN  @S9S_MB_2U_LIB.S9S_MB_2U(SCH_1):CLK_100M_PE_M2_0_DN

SCONN84_123318136  I49  J61    [SCONN84_123318136-SCONN84_1-23A]
  B10  RST_PCIE_EDSFF4B_PERST_N  PERST0_N  @S9S_MB_2U_LIB.S9S_MB_2U(SCH_1):RST_PCIE_EDSFF4B_PERST_N
  A12  PD_PCIE_EDSFF4B_PRSNT_0_N  PRSNT0_N  @S9S_MB_2U_LIB.S9S_MB_2U(SCH_1):PD_PCIE_EDSFF4B_PRSNT_0_N
  B12  PD_EDSFF4B_PWRDIS  PWRDIS  @S9S_MB_2U_LIB.S9S_MB_2U(SCH_1):PD_EDSFF4B_PWRDIS
  B20  P5E_CPU1_PE4_TX_C_DP<9>  PERN1  @S9S_MB_2U_LIB.S9S_MB_2U(SCH_1):P5E_CPU1_PE4_TX_C_DP<9>
  B17  P5E_CPU1_PE4_TX_C_DP<8>  PERN0  @S9S_MB_2U_LIB.S9S_MB_2U(SCH_1):P5E_CPU1_PE4_TX_C_DP<8>
  B39  P5E_CPU1_PE4_TX_C_DP<15>  PERN7  @S9S_MB_2U_LIB.S9S_MB_2U(SCH_1):P5E_CPU1_PE4_TX_C_DP<15>
  B36  P5E_CPU1_PE4_TX_C_DP<14>  PERN6  @S9S_MB_2U_LIB.S9S_MB_2U(SCH_1):P5E_CPU1_PE4_TX_C_DP<14>
  B33  P5E_CPU1_PE4_TX_C_DP<13>  PERN5  @S9S_MB_2U_LIB.S9S_MB_2U(SCH_1):P5E_CPU1_PE4_TX_C_DP<13>
  B30  P5E_CPU1_PE4_TX_C_DP<12>  PERN4  @S9S_MB_2U_LIB.S9S_MB_2U(SCH_1):P5E_CPU1_PE4_TX_C_DP<12>
  B26  P5E_CPU1_PE4_TX_C_DP<11>  PERN3  @S9S_MB_2U_LIB.S9S_MB_2U(SCH_1):P5E_CPU1_PE4_TX_C_DP<11>
  B23  P5E_CPU1_PE4_TX_C_DP<10>  PERN2  @S9S_MB_2U_LIB.S9S_MB_2U(SCH_1):P5E_CPU1_PE4_TX_C_DP<10>
  B21  P5E_CPU1_PE4_TX_C_DN<9>  PERP1  @S9S_MB_2U_LIB.S9S_MB_2U(SCH_1):P5E_CPU1_PE4_TX_C_DN<9>
  B18  P5E_CPU1_PE4_TX_C_DN<8>  PERP0  @S9S_MB_2U_LIB.S9S_MB_2U(SCH_1):P5E_CPU1_PE4_TX_C_DN<8>
  B40  P5E_CPU1_PE4_TX_C_DN<15>  PERP7  @S9S_MB_2U_LIB.S9S_MB_2U(SCH_1):P5E_CPU1_PE4_TX_C_DN<15>
  B37  P5E_CPU1_PE4_TX_C_DN<14>  PERP6  @S9S_MB_2U_LIB.S9S_MB_2U(SCH_1):P5E_CPU1_PE4_TX_C_DN<14>
  B34  P5E_CPU1_PE4_TX_C_DN<13>  PERP5  @S9S_MB_2U_LIB.S9S_MB_2U(SCH_1):P5E_CPU1_PE4_TX_C_DN<13>
  B31  P5E_CPU1_PE4_TX_C_DN<12>  PERP4  @S9S_MB_2U_LIB.S9S_MB_2U(SCH_1):P5E_CPU1_PE4_TX_C_DN<12>
  B27  P5E_CPU1_PE4_TX_C_DN<11>  PERP3  @S9S_MB_2U_LIB.S9S_MB_2U(SCH_1):P5E_CPU1_PE4_TX_C_DN<11>
  B24  P5E_CPU1_PE4_TX_C_DN<10>  PERP2  @S9S_MB_2U_LIB.S9S_MB_2U(SCH_1):P5E_CPU1_PE4_TX_C_DN<10>
  A20  P5E_CPU1_PE4_RX_DP<9>  PETN1  @S9S_MB_2U_LIB.S9S_MB_2U(SCH_1):P5E_CPU1_PE4_RX_DP<9>
  A18  P5E_CPU1_PE4_RX_DP<8>  PETP0  @S9S_MB_2U_LIB.S9S_MB_2U(SCH_1):P5E_CPU1_PE4_RX_DP<8>
  A40  P5E_CPU1_PE4_RX_DP<15>  PETP7  @S9S_MB_2U_LIB.S9S_MB_2U(SCH_1):P5E_CPU1_PE4_RX_DP<15>
  A36  P5E_CPU1_PE4_RX_DP<14>  PETN6  @S9S_MB_2U_LIB.S9S_MB_2U(SCH_1):P5E_CPU1_PE4_RX_DP<14>
  A34  P5E_CPU1_PE4_RX_DP<13>  PETP5  @S9S_MB_2U_LIB.S9S_MB_2U(SCH_1):P5E_CPU1_PE4_RX_DP<13>
  A30  P5E_CPU1_PE4_RX_DP<12>  PETN4  @S9S_MB_2U_LIB.S9S_MB_2U(SCH_1):P5E_CPU1_PE4_RX_DP<12>
  A26  P5E_CPU1_PE4_RX_DP<11>  PETN3  @S9S_MB_2U_LIB.S9S_MB_2U(SCH_1):P5E_CPU1_PE4_RX_DP<11>
  A24  P5E_CPU1_PE4_RX_DP<10>  PETP2  @S9S_MB_2U_LIB.S9S_MB_2U(SCH_1):P5E_CPU1_PE4_RX_DP<10>
  A21  P5E_CPU1_PE4_RX_DN<9>  PETP1  @S9S_MB_2U_LIB.S9S_MB_2U(SCH_1):P5E_CPU1_PE4_RX_DN<9>
  A17  P5E_CPU1_PE4_RX_DN<8>  PETN0  @S9S_MB_2U_LIB.S9S_MB_2U(SCH_1):P5E_CPU1_PE4_RX_DN<8>
  A39  P5E_CPU1_PE4_RX_DN<15>  PETN7  @S9S_MB_2U_LIB.S9S_MB_2U(SCH_1):P5E_CPU1_PE4_RX_DN<15>
  A37  P5E_CPU1_PE4_RX_DN<14>  PETP6  @S9S_MB_2U_LIB.S9S_MB_2U(SCH_1):P5E_CPU1_PE4_RX_DN<14>
  A33  P5E_CPU1_PE4_RX_DN<13>  PETN5  @S9S_MB_2U_LIB.S9S_MB_2U(SCH_1):P5E_CPU1_PE4_RX_DN<13>
  A31  P5E_CPU1_PE4_RX_DN<12>  PETP4  @S9S_MB_2U_LIB.S9S_MB_2U(SCH_1):P5E_CPU1_PE4_RX_DN<12>
  A27  P5E_CPU1_PE4_RX_DN<11>  PETP3  @S9S_MB_2U_LIB.S9S_MB_2U(SCH_1):P5E_CPU1_PE4_RX_DN<11>
  A23  P5E_CPU1_PE4_RX_DN<10>  PETN2  @S9S_MB_2U_LIB.S9S_MB_2U(SCH_1):P5E_CPU1_PE4_RX_DN<10>
  B11  P3V3_AUX       3_3VAUX  @S9S_MB_2U_LIB.S9S_MB_2U(SCH_1):P3V3_AUX
   A9  P3V3           SMBRST_N  @S9S_MB_2U_LIB.S9S_MB_2U(SCH_1):P3V3
   A8  P3V3           SMBDAT  @S9S_MB_2U_LIB.S9S_MB_2U(SCH_1):P3V3
   A7  P3V3           SMBCLK  @S9S_MB_2U_LIB.S9S_MB_2U(SCH_1):P3V3
   B6  P12V_REAR_CPU  12VB6  @S9S_MB_2U_LIB.S9S_MB_2U(SCH_1):P12V_REAR_CPU
   B5  P12V_REAR_CPU  12VB5  @S9S_MB_2U_LIB.S9S_MB_2U(SCH_1):P12V_REAR_CPU
   B4  P12V_REAR_CPU  12VB4  @S9S_MB_2U_LIB.S9S_MB_2U(SCH_1):P12V_REAR_CPU
   B3  P12V_REAR_CPU  12VB3  @S9S_MB_2U_LIB.S9S_MB_2U(SCH_1):P12V_REAR_CPU
   B2  P12V_REAR_CPU  12VB2  @S9S_MB_2U_LIB.S9S_MB_2U(SCH_1):P12V_REAR_CPU
   B1  P12V_REAR_CPU  12VB1  @S9S_MB_2U_LIB.S9S_MB_2U(SCH_1):P12V_REAR_CPU
  A42  JTAG_EDSFF4_TRST_N    RFU  @S9S_MB_2U_LIB.S9S_MB_2U(SCH_1):JTAG_EDSFF4_TRST_N
  A15  JTAG_EDSFF4_TMS  REFCLKP1  @S9S_MB_2U_LIB.S9S_MB_2U(SCH_1):JTAG_EDSFF4_TMS
   B8  JTAG_EDSFF4_TDO  RFUB8  @S9S_MB_2U_LIB.S9S_MB_2U(SCH_1):JTAG_EDSFF4_TDO
   B9  JTAG_EDSFF4_TDI  DUALPORTEN_N  @S9S_MB_2U_LIB.S9S_MB_2U(SCH_1):JTAG_EDSFF4_TDI
  A14  JTAG_EDSFF4_TCK  REFCLKN1  @S9S_MB_2U_LIB.S9S_MB_2U(SCH_1):JTAG_EDSFF4_TCK
  B41  GND            GNDB41  @S9S_MB_2U_LIB.S9S_MB_2U(SCH_1):GND
  B38  GND            GNDB38  @S9S_MB_2U_LIB.S9S_MB_2U(SCH_1):GND
  B35  GND            GNDB35  @S9S_MB_2U_LIB.S9S_MB_2U(SCH_1):GND
  B32  GND            GNDB32  @S9S_MB_2U_LIB.S9S_MB_2U(SCH_1):GND
  B29  GND            GNDB29  @S9S_MB_2U_LIB.S9S_MB_2U(SCH_1):GND
  B28  GND            GNDB28  @S9S_MB_2U_LIB.S9S_MB_2U(SCH_1):GND
  B25  GND            GNDB25  @S9S_MB_2U_LIB.S9S_MB_2U(SCH_1):GND
  B22  GND            GNDB22  @S9S_MB_2U_LIB.S9S_MB_2U(SCH_1):GND
  B19  GND            GNDB19  @S9S_MB_2U_LIB.S9S_MB_2U(SCH_1):GND
  B16  GND            GNDB16  @S9S_MB_2U_LIB.S9S_MB_2U(SCH_1):GND
  B13  GND            GNDB13  @S9S_MB_2U_LIB.S9S_MB_2U(SCH_1):GND
  A41  GND            GNDA41  @S9S_MB_2U_LIB.S9S_MB_2U(SCH_1):GND
  A38  GND            GNDA38  @S9S_MB_2U_LIB.S9S_MB_2U(SCH_1):GND
  A35  GND            GNDA35  @S9S_MB_2U_LIB.S9S_MB_2U(SCH_1):GND
  A32  GND            GNDA32  @S9S_MB_2U_LIB.S9S_MB_2U(SCH_1):GND
  A29  GND            GNDA29  @S9S_MB_2U_LIB.S9S_MB_2U(SCH_1):GND
  A28  GND            GNDA28  @S9S_MB_2U_LIB.S9S_MB_2U(SCH_1):GND
  A25  GND            GNDA25  @S9S_MB_2U_LIB.S9S_MB_2U(SCH_1):GND
  A22  GND            GNDA22  @S9S_MB_2U_LIB.S9S_MB_2U(SCH_1):GND
  A19  GND            GNDA19  @S9S_MB_2U_LIB.S9S_MB_2U(SCH_1):GND
  A16  GND            GNDA16  @S9S_MB_2U_LIB.S9S_MB_2U(SCH_1):GND
  A13  GND            GNDA13  @S9S_MB_2U_LIB.S9S_MB_2U(SCH_1):GND
   A6  GND            GNDA6  @S9S_MB_2U_LIB.S9S_MB_2U(SCH_1):GND
   A5  GND            GNDA5  @S9S_MB_2U_LIB.S9S_MB_2U(SCH_1):GND
   A4  GND            GNDA4  @S9S_MB_2U_LIB.S9S_MB_2U(SCH_1):GND
   A3  GND            GNDA3  @S9S_MB_2U_LIB.S9S_MB_2U(SCH_1):GND
   A2  GND            GNDA2  @S9S_MB_2U_LIB.S9S_MB_2U(SCH_1):GND
   A1  GND            GNDA1  @S9S_MB_2U_LIB.S9S_MB_2U(SCH_1):GND
   G5  GND               G5  @S9S_MB_2U_LIB.S9S_MB_2U(SCH_1):GND
   G4  GND               G4  @S9S_MB_2U_LIB.S9S_MB_2U(SCH_1):GND
   G3  GND               G3  @S9S_MB_2U_LIB.S9S_MB_2U(SCH_1):GND
   G2  GND               G2  @S9S_MB_2U_LIB.S9S_MB_2U(SCH_1):GND
   G1  GND               G1  @S9S_MB_2U_LIB.S9S_MB_2U(SCH_1):GND
  B42  FM_PCIE_EDSFF4B_PRSNT_1_N  PRSNT1_N  @S9S_MB_2U_LIB.S9S_MB_2U(SCH_1):FM_PCIE_EDSFF4B_PRSNT_1_N
  A10  FM_JTAG_EDSFF4_SEL  LED_ACTIVITYA10  @S9S_MB_2U_LIB.S9S_MB_2U(SCH_1):FM_JTAG_EDSFF4_SEL
   B7  FM_EDSFF4A_TYPE_ID    MFG  @S9S_MB_2U_LIB.S9S_MB_2U(SCH_1):FM_EDSFF4A_TYPE_ID
  A11  EDSFF4B_PERST1_CLKREQ_N  PERST1_N_CLKREQ_N  @S9S_MB_2U_LIB.S9S_MB_2U(SCH_1):EDSFF4B_PERST1_CLKREQ_N
  B15  CLK_100M_EDSFF4B_DP  REFCLKP0  @S9S_MB_2U_LIB.S9S_MB_2U(SCH_1):CLK_100M_EDSFF4B_DP
  B14  CLK_100M_EDSFF4B_DN  REFCLKN0  @S9S_MB_2U_LIB.S9S_MB_2U(SCH_1):CLK_100M_EDSFF4B_DN

SCONN84_123318136  I33  J62    [SCONN84_123318136-SCONN84_1-23A]
  A10  SMB_PEHPCPU0_EDSFF1A_LVC3_R_SCL  LED_ACTIVITYA10  @S9S_MB_2U_LIB.S9S_MB_2U(SCH_1):SMB_PEHPCPU0_EDSFF1A_LVC3_R_SCL
   B9  SMB_PEHPCPU0_EDSFF1ALVC3_R_SDA  DUALPORTEN_N  @S9S_MB_2U_LIB.S9S_MB_2U(SCH_1):SMB_PEHPCPU0_EDSFF1ALVC3_R_SDA
   A8  SMB_EDSFF1A_3V3AUX_SDA_R  SMBDAT  @S9S_MB_2U_LIB.S9S_MB_2U(SCH_1):SMB_EDSFF1A_3V3AUX_SDA_R
   A7  SMB_EDSFF1A_3V3AUX_SCL_R  SMBCLK  @S9S_MB_2U_LIB.S9S_MB_2U(SCH_1):SMB_EDSFF1A_3V3AUX_SCL_R
   A9  RST_SMB_EDSFF1A_N  SMBRST_N  @S9S_MB_2U_LIB.S9S_MB_2U(SCH_1):RST_SMB_EDSFF1A_N
  B10  RST_PCIE_EDSFF1A_PERST_N  PERST0_N  @S9S_MB_2U_LIB.S9S_MB_2U(SCH_1):RST_PCIE_EDSFF1A_PERST_N
  A12  PD_PCIE_EDSFF1A_PRSNT_0_N  PRSNT0_N  @S9S_MB_2U_LIB.S9S_MB_2U(SCH_1):PD_PCIE_EDSFF1A_PRSNT_0_N
  B12  PD_EDSFF1A_PWRDIS  PWRDIS  @S9S_MB_2U_LIB.S9S_MB_2U(SCH_1):PD_EDSFF1A_PWRDIS
  B40  P5E_CPU0_PE3_TX_C_DP<7>  PERP7  @S9S_MB_2U_LIB.S9S_MB_2U(SCH_1):P5E_CPU0_PE3_TX_C_DP<7>
  B37  P5E_CPU0_PE3_TX_C_DP<6>  PERP6  @S9S_MB_2U_LIB.S9S_MB_2U(SCH_1):P5E_CPU0_PE3_TX_C_DP<6>
  B34  P5E_CPU0_PE3_TX_C_DP<5>  PERP5  @S9S_MB_2U_LIB.S9S_MB_2U(SCH_1):P5E_CPU0_PE3_TX_C_DP<5>
  B31  P5E_CPU0_PE3_TX_C_DP<4>  PERP4  @S9S_MB_2U_LIB.S9S_MB_2U(SCH_1):P5E_CPU0_PE3_TX_C_DP<4>
  B27  P5E_CPU0_PE3_TX_C_DP<3>  PERP3  @S9S_MB_2U_LIB.S9S_MB_2U(SCH_1):P5E_CPU0_PE3_TX_C_DP<3>
  B24  P5E_CPU0_PE3_TX_C_DP<2>  PERP2  @S9S_MB_2U_LIB.S9S_MB_2U(SCH_1):P5E_CPU0_PE3_TX_C_DP<2>
  B21  P5E_CPU0_PE3_TX_C_DP<1>  PERP1  @S9S_MB_2U_LIB.S9S_MB_2U(SCH_1):P5E_CPU0_PE3_TX_C_DP<1>
  B18  P5E_CPU0_PE3_TX_C_DP<0>  PERP0  @S9S_MB_2U_LIB.S9S_MB_2U(SCH_1):P5E_CPU0_PE3_TX_C_DP<0>
  B39  P5E_CPU0_PE3_TX_C_DN<7>  PERN7  @S9S_MB_2U_LIB.S9S_MB_2U(SCH_1):P5E_CPU0_PE3_TX_C_DN<7>
  B36  P5E_CPU0_PE3_TX_C_DN<6>  PERN6  @S9S_MB_2U_LIB.S9S_MB_2U(SCH_1):P5E_CPU0_PE3_TX_C_DN<6>
  B33  P5E_CPU0_PE3_TX_C_DN<5>  PERN5  @S9S_MB_2U_LIB.S9S_MB_2U(SCH_1):P5E_CPU0_PE3_TX_C_DN<5>
  B30  P5E_CPU0_PE3_TX_C_DN<4>  PERN4  @S9S_MB_2U_LIB.S9S_MB_2U(SCH_1):P5E_CPU0_PE3_TX_C_DN<4>
  B26  P5E_CPU0_PE3_TX_C_DN<3>  PERN3  @S9S_MB_2U_LIB.S9S_MB_2U(SCH_1):P5E_CPU0_PE3_TX_C_DN<3>
  B23  P5E_CPU0_PE3_TX_C_DN<2>  PERN2  @S9S_MB_2U_LIB.S9S_MB_2U(SCH_1):P5E_CPU0_PE3_TX_C_DN<2>
  B20  P5E_CPU0_PE3_TX_C_DN<1>  PERN1  @S9S_MB_2U_LIB.S9S_MB_2U(SCH_1):P5E_CPU0_PE3_TX_C_DN<1>
  B17  P5E_CPU0_PE3_TX_C_DN<0>  PERN0  @S9S_MB_2U_LIB.S9S_MB_2U(SCH_1):P5E_CPU0_PE3_TX_C_DN<0>
  A40  P5E_CPU0_PE3_RX_DP<7>  PETP7  @S9S_MB_2U_LIB.S9S_MB_2U(SCH_1):P5E_CPU0_PE3_RX_DP<7>
  A37  P5E_CPU0_PE3_RX_DP<6>  PETP6  @S9S_MB_2U_LIB.S9S_MB_2U(SCH_1):P5E_CPU0_PE3_RX_DP<6>
  A34  P5E_CPU0_PE3_RX_DP<5>  PETP5  @S9S_MB_2U_LIB.S9S_MB_2U(SCH_1):P5E_CPU0_PE3_RX_DP<5>
  A31  P5E_CPU0_PE3_RX_DP<4>  PETP4  @S9S_MB_2U_LIB.S9S_MB_2U(SCH_1):P5E_CPU0_PE3_RX_DP<4>
  A27  P5E_CPU0_PE3_RX_DP<3>  PETP3  @S9S_MB_2U_LIB.S9S_MB_2U(SCH_1):P5E_CPU0_PE3_RX_DP<3>
  A24  P5E_CPU0_PE3_RX_DP<2>  PETP2  @S9S_MB_2U_LIB.S9S_MB_2U(SCH_1):P5E_CPU0_PE3_RX_DP<2>
  A21  P5E_CPU0_PE3_RX_DP<1>  PETP1  @S9S_MB_2U_LIB.S9S_MB_2U(SCH_1):P5E_CPU0_PE3_RX_DP<1>
  A18  P5E_CPU0_PE3_RX_DP<0>  PETP0  @S9S_MB_2U_LIB.S9S_MB_2U(SCH_1):P5E_CPU0_PE3_RX_DP<0>
  A39  P5E_CPU0_PE3_RX_DN<7>  PETN7  @S9S_MB_2U_LIB.S9S_MB_2U(SCH_1):P5E_CPU0_PE3_RX_DN<7>
  A36  P5E_CPU0_PE3_RX_DN<6>  PETN6  @S9S_MB_2U_LIB.S9S_MB_2U(SCH_1):P5E_CPU0_PE3_RX_DN<6>
  A33  P5E_CPU0_PE3_RX_DN<5>  PETN5  @S9S_MB_2U_LIB.S9S_MB_2U(SCH_1):P5E_CPU0_PE3_RX_DN<5>
  A30  P5E_CPU0_PE3_RX_DN<4>  PETN4  @S9S_MB_2U_LIB.S9S_MB_2U(SCH_1):P5E_CPU0_PE3_RX_DN<4>
  A26  P5E_CPU0_PE3_RX_DN<3>  PETN3  @S9S_MB_2U_LIB.S9S_MB_2U(SCH_1):P5E_CPU0_PE3_RX_DN<3>
  A23  P5E_CPU0_PE3_RX_DN<2>  PETN2  @S9S_MB_2U_LIB.S9S_MB_2U(SCH_1):P5E_CPU0_PE3_RX_DN<2>
  A20  P5E_CPU0_PE3_RX_DN<1>  PETN1  @S9S_MB_2U_LIB.S9S_MB_2U(SCH_1):P5E_CPU0_PE3_RX_DN<1>
  A17  P5E_CPU0_PE3_RX_DN<0>  PETN0  @S9S_MB_2U_LIB.S9S_MB_2U(SCH_1):P5E_CPU0_PE3_RX_DN<0>
  B11  P3V3_AUX       3_3VAUX  @S9S_MB_2U_LIB.S9S_MB_2U(SCH_1):P3V3_AUX
   B6  P12V_REAR_CPU  12VB6  @S9S_MB_2U_LIB.S9S_MB_2U(SCH_1):P12V_REAR_CPU
   B5  P12V_REAR_CPU  12VB5  @S9S_MB_2U_LIB.S9S_MB_2U(SCH_1):P12V_REAR_CPU
   B4  P12V_REAR_CPU  12VB4  @S9S_MB_2U_LIB.S9S_MB_2U(SCH_1):P12V_REAR_CPU
   B3  P12V_REAR_CPU  12VB3  @S9S_MB_2U_LIB.S9S_MB_2U(SCH_1):P12V_REAR_CPU
   B2  P12V_REAR_CPU  12VB2  @S9S_MB_2U_LIB.S9S_MB_2U(SCH_1):P12V_REAR_CPU
   B1  P12V_REAR_CPU  12VB1  @S9S_MB_2U_LIB.S9S_MB_2U(SCH_1):P12V_REAR_CPU
  A42  NC               RFU  NC
  B41  GND            GNDB41  @S9S_MB_2U_LIB.S9S_MB_2U(SCH_1):GND
  B38  GND            GNDB38  @S9S_MB_2U_LIB.S9S_MB_2U(SCH_1):GND
  B35  GND            GNDB35  @S9S_MB_2U_LIB.S9S_MB_2U(SCH_1):GND
  B32  GND            GNDB32  @S9S_MB_2U_LIB.S9S_MB_2U(SCH_1):GND
  B29  GND            GNDB29  @S9S_MB_2U_LIB.S9S_MB_2U(SCH_1):GND
  B28  GND            GNDB28  @S9S_MB_2U_LIB.S9S_MB_2U(SCH_1):GND
  B25  GND            GNDB25  @S9S_MB_2U_LIB.S9S_MB_2U(SCH_1):GND
  B22  GND            GNDB22  @S9S_MB_2U_LIB.S9S_MB_2U(SCH_1):GND
  B19  GND            GNDB19  @S9S_MB_2U_LIB.S9S_MB_2U(SCH_1):GND
  B16  GND            GNDB16  @S9S_MB_2U_LIB.S9S_MB_2U(SCH_1):GND
  B13  GND            GNDB13  @S9S_MB_2U_LIB.S9S_MB_2U(SCH_1):GND
  A41  GND            GNDA41  @S9S_MB_2U_LIB.S9S_MB_2U(SCH_1):GND
  A38  GND            GNDA38  @S9S_MB_2U_LIB.S9S_MB_2U(SCH_1):GND
  A35  GND            GNDA35  @S9S_MB_2U_LIB.S9S_MB_2U(SCH_1):GND
  A32  GND            GNDA32  @S9S_MB_2U_LIB.S9S_MB_2U(SCH_1):GND
  A29  GND            GNDA29  @S9S_MB_2U_LIB.S9S_MB_2U(SCH_1):GND
  A28  GND            GNDA28  @S9S_MB_2U_LIB.S9S_MB_2U(SCH_1):GND
  A25  GND            GNDA25  @S9S_MB_2U_LIB.S9S_MB_2U(SCH_1):GND
  A22  GND            GNDA22  @S9S_MB_2U_LIB.S9S_MB_2U(SCH_1):GND
  A19  GND            GNDA19  @S9S_MB_2U_LIB.S9S_MB_2U(SCH_1):GND
  A16  GND            GNDA16  @S9S_MB_2U_LIB.S9S_MB_2U(SCH_1):GND
  A13  GND            GNDA13  @S9S_MB_2U_LIB.S9S_MB_2U(SCH_1):GND
   A6  GND            GNDA6  @S9S_MB_2U_LIB.S9S_MB_2U(SCH_1):GND
   A5  GND            GNDA5  @S9S_MB_2U_LIB.S9S_MB_2U(SCH_1):GND
   A4  GND            GNDA4  @S9S_MB_2U_LIB.S9S_MB_2U(SCH_1):GND
   A3  GND            GNDA3  @S9S_MB_2U_LIB.S9S_MB_2U(SCH_1):GND
   A2  GND            GNDA2  @S9S_MB_2U_LIB.S9S_MB_2U(SCH_1):GND
   A1  GND            GNDA1  @S9S_MB_2U_LIB.S9S_MB_2U(SCH_1):GND
   G5  GND               G5  @S9S_MB_2U_LIB.S9S_MB_2U(SCH_1):GND
   G4  GND               G4  @S9S_MB_2U_LIB.S9S_MB_2U(SCH_1):GND
   G3  GND               G3  @S9S_MB_2U_LIB.S9S_MB_2U(SCH_1):GND
   G2  GND               G2  @S9S_MB_2U_LIB.S9S_MB_2U(SCH_1):GND
   G1  GND               G1  @S9S_MB_2U_LIB.S9S_MB_2U(SCH_1):GND
  B42  FM_PCIE_EDSFF1A_PRSNT_1_N  PRSNT1_N  @S9S_MB_2U_LIB.S9S_MB_2U(SCH_1):FM_PCIE_EDSFF1A_PRSNT_1_N
   B7  FM_EDSFF1A_TYPE_ID    MFG  @S9S_MB_2U_LIB.S9S_MB_2U(SCH_1):FM_EDSFF1A_TYPE_ID
   B8  FM_EDSFF1A_PWRBRK_N  RFUB8  @S9S_MB_2U_LIB.S9S_MB_2U(SCH_1):FM_EDSFF1A_PWRBRK_N
  A11  EDSFF1A_PERST1_CLKREQ_N  PERST1_N_CLKREQ_N  @S9S_MB_2U_LIB.S9S_MB_2U(SCH_1):EDSFF1A_PERST1_CLKREQ_N
  B15  CLK_100M_EDSFF1A_DP  REFCLKP0  @S9S_MB_2U_LIB.S9S_MB_2U(SCH_1):CLK_100M_EDSFF1A_DP
  B14  CLK_100M_EDSFF1A_DN  REFCLKN0  @S9S_MB_2U_LIB.S9S_MB_2U(SCH_1):CLK_100M_EDSFF1A_DN
  A15  CLK_100M_EDSFF1A_1_DP  REFCLKP1  @S9S_MB_2U_LIB.S9S_MB_2U(SCH_1):CLK_100M_EDSFF1A_1_DP
  A14  CLK_100M_EDSFF1A_1_DN  REFCLKN1  @S9S_MB_2U_LIB.S9S_MB_2U(SCH_1):CLK_100M_EDSFF1A_1_DN

DELTA_L  I1   J63    [DELTA_L-DELTA-L,THLF,EMPTY,TP24]
    3  DELTA_R_GND        3  @S9S_MB_2U_LIB.S9S_MB_2U(SCH_1):DELTA_R_GND
    1  DELTA_L_85_5INCH_TOP_DP      1  @S9S_MB_2U_LIB.S9S_MB_2U(SCH_1):DELTA_L_85_5INCH_TOP_DP
    2  DELTA_L_85_5INCH_TOP_DN      2  @S9S_MB_2U_LIB.S9S_MB_2U(SCH_1):DELTA_L_85_5INCH_TOP_DN

DELTA_L  I5   J64    [DELTA_L-DELTA-L,THLF,EMPTY,TP24]
    3  DELTA_R_GND        3  @S9S_MB_2U_LIB.S9S_MB_2U(SCH_1):DELTA_R_GND
    1  DELTA_L_85_5INCH_BOT_DP      1  @S9S_MB_2U_LIB.S9S_MB_2U(SCH_1):DELTA_L_85_5INCH_BOT_DP
    2  DELTA_L_85_5INCH_BOT_DN      2  @S9S_MB_2U_LIB.S9S_MB_2U(SCH_1):DELTA_L_85_5INCH_BOT_DN

DELTA_L  I10  J65    [DELTA_L-DELTA-L,THLF,EMPTY,TP24]
    3  DELTA_L_GND        3  @S9S_MB_2U_LIB.S9S_MB_2U(SCH_1):DELTA_L_GND
    1  DELTA_L_85_5INCH_IN1_DP      1  @S9S_MB_2U_LIB.S9S_MB_2U(SCH_1):DELTA_L_85_5INCH_IN1_DP
    2  DELTA_L_85_5INCH_IN1_DN      2  @S9S_MB_2U_LIB.S9S_MB_2U(SCH_1):DELTA_L_85_5INCH_IN1_DN

DELTA_L  I9   J66    [DELTA_L-DELTA-L,THLF,EMPTY,TP24]
    3  DELTA_L_GND        3  @S9S_MB_2U_LIB.S9S_MB_2U(SCH_1):DELTA_L_GND
    1  DELTA_L_85_5INCH_IN2_DP      1  @S9S_MB_2U_LIB.S9S_MB_2U(SCH_1):DELTA_L_85_5INCH_IN2_DP
    2  DELTA_L_85_5INCH_IN2_DN      2  @S9S_MB_2U_LIB.S9S_MB_2U(SCH_1):DELTA_L_85_5INCH_IN2_DN

DELTA_L  I24  J67    [DELTA_L-DELTA-L,THLF,EMPTY,TP24]
    3  DELTA_L_GND        3  @S9S_MB_2U_LIB.S9S_MB_2U(SCH_1):DELTA_L_GND
    1  DELTA_L_85_5INCH_IN3_DP      1  @S9S_MB_2U_LIB.S9S_MB_2U(SCH_1):DELTA_L_85_5INCH_IN3_DP
    2  DELTA_L_85_5INCH_IN3_DN      2  @S9S_MB_2U_LIB.S9S_MB_2U(SCH_1):DELTA_L_85_5INCH_IN3_DN

DELTA_L  I31  J68    [DELTA_L-DELTA-L,THLF,EMPTY,TP24]
    3  DELTA_R_GND        3  @S9S_MB_2U_LIB.S9S_MB_2U(SCH_1):DELTA_R_GND
    1  DELTA_L_85_5INCH_IN4_DP      1  @S9S_MB_2U_LIB.S9S_MB_2U(SCH_1):DELTA_L_85_5INCH_IN4_DP
    2  DELTA_L_85_5INCH_IN4_DN      2  @S9S_MB_2U_LIB.S9S_MB_2U(SCH_1):DELTA_L_85_5INCH_IN4_DN

DELTA_L  I60  J69    [DELTA_L-DELTA-L,THLF,EMPTY,TP24]
    3  DELTA_R_GND        3  @S9S_MB_2U_LIB.S9S_MB_2U(SCH_1):DELTA_R_GND
    2  DELTA_L_85_5INCH_TOP_DP      2  @S9S_MB_2U_LIB.S9S_MB_2U(SCH_1):DELTA_L_85_5INCH_TOP_DP
    1  DELTA_L_85_5INCH_TOP_DN      1  @S9S_MB_2U_LIB.S9S_MB_2U(SCH_1):DELTA_L_85_5INCH_TOP_DN

DELTA_L  I61  J70    [DELTA_L-DELTA-L,THLF,EMPTY,TP24]
    3  DELTA_R_GND        3  @S9S_MB_2U_LIB.S9S_MB_2U(SCH_1):DELTA_R_GND
    2  DELTA_L_85_5INCH_BOT_DP      2  @S9S_MB_2U_LIB.S9S_MB_2U(SCH_1):DELTA_L_85_5INCH_BOT_DP
    1  DELTA_L_85_5INCH_BOT_DN      1  @S9S_MB_2U_LIB.S9S_MB_2U(SCH_1):DELTA_L_85_5INCH_BOT_DN

DELTA_L  I62  J71    [DELTA_L-DELTA-L,THLF,EMPTY,TP24]
    3  DELTA_L_GND        3  @S9S_MB_2U_LIB.S9S_MB_2U(SCH_1):DELTA_L_GND
    2  DELTA_L_85_5INCH_IN1_DP      2  @S9S_MB_2U_LIB.S9S_MB_2U(SCH_1):DELTA_L_85_5INCH_IN1_DP
    1  DELTA_L_85_5INCH_IN1_DN      1  @S9S_MB_2U_LIB.S9S_MB_2U(SCH_1):DELTA_L_85_5INCH_IN1_DN

DELTA_L  I63  J72    [DELTA_L-DELTA-L,THLF,EMPTY,TP24]
    3  DELTA_L_GND        3  @S9S_MB_2U_LIB.S9S_MB_2U(SCH_1):DELTA_L_GND
    2  DELTA_L_85_5INCH_IN2_DP      2  @S9S_MB_2U_LIB.S9S_MB_2U(SCH_1):DELTA_L_85_5INCH_IN2_DP
    1  DELTA_L_85_5INCH_IN2_DN      1  @S9S_MB_2U_LIB.S9S_MB_2U(SCH_1):DELTA_L_85_5INCH_IN2_DN

DELTA_L  I64  J73    [DELTA_L-DELTA-L,THLF,EMPTY,TP24]
    3  DELTA_L_GND        3  @S9S_MB_2U_LIB.S9S_MB_2U(SCH_1):DELTA_L_GND
    2  DELTA_L_85_5INCH_IN3_DP      2  @S9S_MB_2U_LIB.S9S_MB_2U(SCH_1):DELTA_L_85_5INCH_IN3_DP
    1  DELTA_L_85_5INCH_IN3_DN      1  @S9S_MB_2U_LIB.S9S_MB_2U(SCH_1):DELTA_L_85_5INCH_IN3_DN

DELTA_L  I65  J74    [DELTA_L-DELTA-L,THLF,EMPTY,TP24]
    3  DELTA_R_GND        3  @S9S_MB_2U_LIB.S9S_MB_2U(SCH_1):DELTA_R_GND
    2  DELTA_L_85_5INCH_IN4_DP      2  @S9S_MB_2U_LIB.S9S_MB_2U(SCH_1):DELTA_L_85_5INCH_IN4_DP
    1  DELTA_L_85_5INCH_IN4_DN      1  @S9S_MB_2U_LIB.S9S_MB_2U(SCH_1):DELTA_L_85_5INCH_IN4_DN

DELTA_L  I34  J75    [DELTA_L-DELTA-L,THLF,EMPTY,TP24]
    3  DELTA_R_GND        3  @S9S_MB_2U_LIB.S9S_MB_2U(SCH_1):DELTA_R_GND
    1  DELTA_L_85_10INCH_TOP_DP      1  @S9S_MB_2U_LIB.S9S_MB_2U(SCH_1):DELTA_L_85_10INCH_TOP_DP
    2  DELTA_L_85_10INCH_TOP_DN      2  @S9S_MB_2U_LIB.S9S_MB_2U(SCH_1):DELTA_L_85_10INCH_TOP_DN

DELTA_L  I33  J76    [DELTA_L-DELTA-L,THLF,EMPTY,TP24]
    3  DELTA_R_GND        3  @S9S_MB_2U_LIB.S9S_MB_2U(SCH_1):DELTA_R_GND
    1  DELTA_L_85_10INCH_BOT_DP      1  @S9S_MB_2U_LIB.S9S_MB_2U(SCH_1):DELTA_L_85_10INCH_BOT_DP
    2  DELTA_L_85_10INCH_BOT_DN      2  @S9S_MB_2U_LIB.S9S_MB_2U(SCH_1):DELTA_L_85_10INCH_BOT_DN

DELTA_L  I50  J77    [DELTA_L-DELTA-L,THLF,EMPTY,TP24]
    3  DELTA_L_GND        3  @S9S_MB_2U_LIB.S9S_MB_2U(SCH_1):DELTA_L_GND
    1  DELTA_L_85_10INCH_IN1_DP      1  @S9S_MB_2U_LIB.S9S_MB_2U(SCH_1):DELTA_L_85_10INCH_IN1_DP
    2  DELTA_L_85_10INCH_IN1_DN      2  @S9S_MB_2U_LIB.S9S_MB_2U(SCH_1):DELTA_L_85_10INCH_IN1_DN

DELTA_L  I52  J78    [DELTA_L-DELTA-L,THLF,EMPTY,TP24]
    3  DELTA_R_GND        3  @S9S_MB_2U_LIB.S9S_MB_2U(SCH_1):DELTA_R_GND
    1  DELTA_L_85_10INCH_IN2_DP      1  @S9S_MB_2U_LIB.S9S_MB_2U(SCH_1):DELTA_L_85_10INCH_IN2_DP
    2  DELTA_L_85_10INCH_IN2_DN      2  @S9S_MB_2U_LIB.S9S_MB_2U(SCH_1):DELTA_L_85_10INCH_IN2_DN

DELTA_L  I56  J79    [DELTA_L-DELTA-L,THLF,EMPTY,TP24]
    3  DELTA_R_GND        3  @S9S_MB_2U_LIB.S9S_MB_2U(SCH_1):DELTA_R_GND
    1  DELTA_L_85_10INCH_IN3_DP      1  @S9S_MB_2U_LIB.S9S_MB_2U(SCH_1):DELTA_L_85_10INCH_IN3_DP
    2  DELTA_L_85_10INCH_IN3_DN      2  @S9S_MB_2U_LIB.S9S_MB_2U(SCH_1):DELTA_L_85_10INCH_IN3_DN

DELTA_L  I32  J80    [DELTA_L-DELTA-L,THLF,EMPTY,TP24]
    3  DELTA_L_GND        3  @S9S_MB_2U_LIB.S9S_MB_2U(SCH_1):DELTA_L_GND
    1  DELTA_L_85_10INCH_IN4_DP      1  @S9S_MB_2U_LIB.S9S_MB_2U(SCH_1):DELTA_L_85_10INCH_IN4_DP
    2  DELTA_L_85_10INCH_IN4_DN      2  @S9S_MB_2U_LIB.S9S_MB_2U(SCH_1):DELTA_L_85_10INCH_IN4_DN

DELTA_L  I71  J81    [DELTA_L-DELTA-L,THLF,EMPTY,TP24]
    3  DELTA_R_GND        3  @S9S_MB_2U_LIB.S9S_MB_2U(SCH_1):DELTA_R_GND
    2  DELTA_L_85_10INCH_TOP_DP      2  @S9S_MB_2U_LIB.S9S_MB_2U(SCH_1):DELTA_L_85_10INCH_TOP_DP
    1  DELTA_L_85_10INCH_TOP_DN      1  @S9S_MB_2U_LIB.S9S_MB_2U(SCH_1):DELTA_L_85_10INCH_TOP_DN

DELTA_L  I70  J82    [DELTA_L-DELTA-L,THLF,EMPTY,TP24]
    3  DELTA_R_GND        3  @S9S_MB_2U_LIB.S9S_MB_2U(SCH_1):DELTA_R_GND
    2  DELTA_L_85_10INCH_BOT_DP      2  @S9S_MB_2U_LIB.S9S_MB_2U(SCH_1):DELTA_L_85_10INCH_BOT_DP
    1  DELTA_L_85_10INCH_BOT_DN      1  @S9S_MB_2U_LIB.S9S_MB_2U(SCH_1):DELTA_L_85_10INCH_BOT_DN

DELTA_L  I69  J83    [DELTA_L-DELTA-L,THLF,EMPTY,TP24]
    3  DELTA_L_GND        3  @S9S_MB_2U_LIB.S9S_MB_2U(SCH_1):DELTA_L_GND
    2  DELTA_L_85_10INCH_IN1_DP      2  @S9S_MB_2U_LIB.S9S_MB_2U(SCH_1):DELTA_L_85_10INCH_IN1_DP
    1  DELTA_L_85_10INCH_IN1_DN      1  @S9S_MB_2U_LIB.S9S_MB_2U(SCH_1):DELTA_L_85_10INCH_IN1_DN

DELTA_L  I68  J84    [DELTA_L-DELTA-L,THLF,EMPTY,TP24]
    3  DELTA_R_GND        3  @S9S_MB_2U_LIB.S9S_MB_2U(SCH_1):DELTA_R_GND
    2  DELTA_L_85_10INCH_IN2_DP      2  @S9S_MB_2U_LIB.S9S_MB_2U(SCH_1):DELTA_L_85_10INCH_IN2_DP
    1  DELTA_L_85_10INCH_IN2_DN      1  @S9S_MB_2U_LIB.S9S_MB_2U(SCH_1):DELTA_L_85_10INCH_IN2_DN

DELTA_L  I67  J85    [DELTA_L-DELTA-L,THLF,EMPTY,TP24]
    3  DELTA_R_GND        3  @S9S_MB_2U_LIB.S9S_MB_2U(SCH_1):DELTA_R_GND
    2  DELTA_L_85_10INCH_IN3_DP      2  @S9S_MB_2U_LIB.S9S_MB_2U(SCH_1):DELTA_L_85_10INCH_IN3_DP
    1  DELTA_L_85_10INCH_IN3_DN      1  @S9S_MB_2U_LIB.S9S_MB_2U(SCH_1):DELTA_L_85_10INCH_IN3_DN

DELTA_L  I66  J86    [DELTA_L-DELTA-L,THLF,EMPTY,TP24]
    3  DELTA_L_GND        3  @S9S_MB_2U_LIB.S9S_MB_2U(SCH_1):DELTA_L_GND
    2  DELTA_L_85_10INCH_IN4_DP      2  @S9S_MB_2U_LIB.S9S_MB_2U(SCH_1):DELTA_L_85_10INCH_IN4_DP
    1  DELTA_L_85_10INCH_IN4_DN      1  @S9S_MB_2U_LIB.S9S_MB_2U(SCH_1):DELTA_L_85_10INCH_IN4_DN

SCONN84_123318136  I43  J87    [SCONN84_123318136-SCONN84_1-23A]
   B9  SMB_PEHPCPU0_EDSFF1B_LVC3_R_SDA  DUALPORTEN_N  @S9S_MB_2U_LIB.S9S_MB_2U(SCH_1):SMB_PEHPCPU0_EDSFF1B_LVC3_R_SDA
  A10  SMB_PEHPCPU0_EDSFF1B_LVC3_R_SCL  LED_ACTIVITYA10  @S9S_MB_2U_LIB.S9S_MB_2U(SCH_1):SMB_PEHPCPU0_EDSFF1B_LVC3_R_SCL
   A8  SMB_EDSFF1B_3V3AUX_SDA_R  SMBDAT  @S9S_MB_2U_LIB.S9S_MB_2U(SCH_1):SMB_EDSFF1B_3V3AUX_SDA_R
   A7  SMB_EDSFF1B_3V3AUX_SCL_R  SMBCLK  @S9S_MB_2U_LIB.S9S_MB_2U(SCH_1):SMB_EDSFF1B_3V3AUX_SCL_R
   A9  RST_SMB_EDSFF1B_N  SMBRST_N  @S9S_MB_2U_LIB.S9S_MB_2U(SCH_1):RST_SMB_EDSFF1B_N
  B10  RST_PCIE_EDSFF1B_PERST_N  PERST0_N  @S9S_MB_2U_LIB.S9S_MB_2U(SCH_1):RST_PCIE_EDSFF1B_PERST_N
  A11  PU_EDSFF1B_PERST1_CLKREQ_N  PERST1_N_CLKREQ_N  @S9S_MB_2U_LIB.S9S_MB_2U(SCH_1):PU_EDSFF1B_PERST1_CLKREQ_N
  A12  PD_PCIE_EDSFF1B_PRSNT_0_N  PRSNT0_N  @S9S_MB_2U_LIB.S9S_MB_2U(SCH_1):PD_PCIE_EDSFF1B_PRSNT_0_N
  B12  PD_EDSFF1B_PWRDIS  PWRDIS  @S9S_MB_2U_LIB.S9S_MB_2U(SCH_1):PD_EDSFF1B_PWRDIS
  B21  P5E_CPU0_PE3_TX_C_DP<9>  PERP1  @S9S_MB_2U_LIB.S9S_MB_2U(SCH_1):P5E_CPU0_PE3_TX_C_DP<9>
  B18  P5E_CPU0_PE3_TX_C_DP<8>  PERP0  @S9S_MB_2U_LIB.S9S_MB_2U(SCH_1):P5E_CPU0_PE3_TX_C_DP<8>
  B40  P5E_CPU0_PE3_TX_C_DP<15>  PERP7  @S9S_MB_2U_LIB.S9S_MB_2U(SCH_1):P5E_CPU0_PE3_TX_C_DP<15>
  B37  P5E_CPU0_PE3_TX_C_DP<14>  PERP6  @S9S_MB_2U_LIB.S9S_MB_2U(SCH_1):P5E_CPU0_PE3_TX_C_DP<14>
  B34  P5E_CPU0_PE3_TX_C_DP<13>  PERP5  @S9S_MB_2U_LIB.S9S_MB_2U(SCH_1):P5E_CPU0_PE3_TX_C_DP<13>
  B31  P5E_CPU0_PE3_TX_C_DP<12>  PERP4  @S9S_MB_2U_LIB.S9S_MB_2U(SCH_1):P5E_CPU0_PE3_TX_C_DP<12>
  B27  P5E_CPU0_PE3_TX_C_DP<11>  PERP3  @S9S_MB_2U_LIB.S9S_MB_2U(SCH_1):P5E_CPU0_PE3_TX_C_DP<11>
  B24  P5E_CPU0_PE3_TX_C_DP<10>  PERP2  @S9S_MB_2U_LIB.S9S_MB_2U(SCH_1):P5E_CPU0_PE3_TX_C_DP<10>
  B20  P5E_CPU0_PE3_TX_C_DN<9>  PERN1  @S9S_MB_2U_LIB.S9S_MB_2U(SCH_1):P5E_CPU0_PE3_TX_C_DN<9>
  B17  P5E_CPU0_PE3_TX_C_DN<8>  PERN0  @S9S_MB_2U_LIB.S9S_MB_2U(SCH_1):P5E_CPU0_PE3_TX_C_DN<8>
  B39  P5E_CPU0_PE3_TX_C_DN<15>  PERN7  @S9S_MB_2U_LIB.S9S_MB_2U(SCH_1):P5E_CPU0_PE3_TX_C_DN<15>
  B36  P5E_CPU0_PE3_TX_C_DN<14>  PERN6  @S9S_MB_2U_LIB.S9S_MB_2U(SCH_1):P5E_CPU0_PE3_TX_C_DN<14>
  B33  P5E_CPU0_PE3_TX_C_DN<13>  PERN5  @S9S_MB_2U_LIB.S9S_MB_2U(SCH_1):P5E_CPU0_PE3_TX_C_DN<13>
  B30  P5E_CPU0_PE3_TX_C_DN<12>  PERN4  @S9S_MB_2U_LIB.S9S_MB_2U(SCH_1):P5E_CPU0_PE3_TX_C_DN<12>
  B26  P5E_CPU0_PE3_TX_C_DN<11>  PERN3  @S9S_MB_2U_LIB.S9S_MB_2U(SCH_1):P5E_CPU0_PE3_TX_C_DN<11>
  B23  P5E_CPU0_PE3_TX_C_DN<10>  PERN2  @S9S_MB_2U_LIB.S9S_MB_2U(SCH_1):P5E_CPU0_PE3_TX_C_DN<10>
  A21  P5E_CPU0_PE3_RX_DP<9>  PETP1  @S9S_MB_2U_LIB.S9S_MB_2U(SCH_1):P5E_CPU0_PE3_RX_DP<9>
  A18  P5E_CPU0_PE3_RX_DP<8>  PETP0  @S9S_MB_2U_LIB.S9S_MB_2U(SCH_1):P5E_CPU0_PE3_RX_DP<8>
  A40  P5E_CPU0_PE3_RX_DP<15>  PETP7  @S9S_MB_2U_LIB.S9S_MB_2U(SCH_1):P5E_CPU0_PE3_RX_DP<15>
  A37  P5E_CPU0_PE3_RX_DP<14>  PETP6  @S9S_MB_2U_LIB.S9S_MB_2U(SCH_1):P5E_CPU0_PE3_RX_DP<14>
  A34  P5E_CPU0_PE3_RX_DP<13>  PETP5  @S9S_MB_2U_LIB.S9S_MB_2U(SCH_1):P5E_CPU0_PE3_RX_DP<13>
  A31  P5E_CPU0_PE3_RX_DP<12>  PETP4  @S9S_MB_2U_LIB.S9S_MB_2U(SCH_1):P5E_CPU0_PE3_RX_DP<12>
  A27  P5E_CPU0_PE3_RX_DP<11>  PETP3  @S9S_MB_2U_LIB.S9S_MB_2U(SCH_1):P5E_CPU0_PE3_RX_DP<11>
  A24  P5E_CPU0_PE3_RX_DP<10>  PETP2  @S9S_MB_2U_LIB.S9S_MB_2U(SCH_1):P5E_CPU0_PE3_RX_DP<10>
  A20  P5E_CPU0_PE3_RX_DN<9>  PETN1  @S9S_MB_2U_LIB.S9S_MB_2U(SCH_1):P5E_CPU0_PE3_RX_DN<9>
  A17  P5E_CPU0_PE3_RX_DN<8>  PETN0  @S9S_MB_2U_LIB.S9S_MB_2U(SCH_1):P5E_CPU0_PE3_RX_DN<8>
  A39  P5E_CPU0_PE3_RX_DN<15>  PETN7  @S9S_MB_2U_LIB.S9S_MB_2U(SCH_1):P5E_CPU0_PE3_RX_DN<15>
  A36  P5E_CPU0_PE3_RX_DN<14>  PETN6  @S9S_MB_2U_LIB.S9S_MB_2U(SCH_1):P5E_CPU0_PE3_RX_DN<14>
  A33  P5E_CPU0_PE3_RX_DN<13>  PETN5  @S9S_MB_2U_LIB.S9S_MB_2U(SCH_1):P5E_CPU0_PE3_RX_DN<13>
  A30  P5E_CPU0_PE3_RX_DN<12>  PETN4  @S9S_MB_2U_LIB.S9S_MB_2U(SCH_1):P5E_CPU0_PE3_RX_DN<12>
  A26  P5E_CPU0_PE3_RX_DN<11>  PETN3  @S9S_MB_2U_LIB.S9S_MB_2U(SCH_1):P5E_CPU0_PE3_RX_DN<11>
  A23  P5E_CPU0_PE3_RX_DN<10>  PETN2  @S9S_MB_2U_LIB.S9S_MB_2U(SCH_1):P5E_CPU0_PE3_RX_DN<10>
  B11  P3V3_AUX       3_3VAUX  @S9S_MB_2U_LIB.S9S_MB_2U(SCH_1):P3V3_AUX
   B6  P12V_REAR_CPU  12VB6  @S9S_MB_2U_LIB.S9S_MB_2U(SCH_1):P12V_REAR_CPU
   B5  P12V_REAR_CPU  12VB5  @S9S_MB_2U_LIB.S9S_MB_2U(SCH_1):P12V_REAR_CPU
   B4  P12V_REAR_CPU  12VB4  @S9S_MB_2U_LIB.S9S_MB_2U(SCH_1):P12V_REAR_CPU
   B3  P12V_REAR_CPU  12VB3  @S9S_MB_2U_LIB.S9S_MB_2U(SCH_1):P12V_REAR_CPU
   B2  P12V_REAR_CPU  12VB2  @S9S_MB_2U_LIB.S9S_MB_2U(SCH_1):P12V_REAR_CPU
   B1  P12V_REAR_CPU  12VB1  @S9S_MB_2U_LIB.S9S_MB_2U(SCH_1):P12V_REAR_CPU
  A42  NC               RFU  NC
  B41  GND            GNDB41  @S9S_MB_2U_LIB.S9S_MB_2U(SCH_1):GND
  B38  GND            GNDB38  @S9S_MB_2U_LIB.S9S_MB_2U(SCH_1):GND
  B35  GND            GNDB35  @S9S_MB_2U_LIB.S9S_MB_2U(SCH_1):GND
  B32  GND            GNDB32  @S9S_MB_2U_LIB.S9S_MB_2U(SCH_1):GND
  B29  GND            GNDB29  @S9S_MB_2U_LIB.S9S_MB_2U(SCH_1):GND
  B28  GND            GNDB28  @S9S_MB_2U_LIB.S9S_MB_2U(SCH_1):GND
  B25  GND            GNDB25  @S9S_MB_2U_LIB.S9S_MB_2U(SCH_1):GND
  B22  GND            GNDB22  @S9S_MB_2U_LIB.S9S_MB_2U(SCH_1):GND
  B19  GND            GNDB19  @S9S_MB_2U_LIB.S9S_MB_2U(SCH_1):GND
  B16  GND            GNDB16  @S9S_MB_2U_LIB.S9S_MB_2U(SCH_1):GND
  B13  GND            GNDB13  @S9S_MB_2U_LIB.S9S_MB_2U(SCH_1):GND
  A41  GND            GNDA41  @S9S_MB_2U_LIB.S9S_MB_2U(SCH_1):GND
  A38  GND            GNDA38  @S9S_MB_2U_LIB.S9S_MB_2U(SCH_1):GND
  A35  GND            GNDA35  @S9S_MB_2U_LIB.S9S_MB_2U(SCH_1):GND
  A32  GND            GNDA32  @S9S_MB_2U_LIB.S9S_MB_2U(SCH_1):GND
  A29  GND            GNDA29  @S9S_MB_2U_LIB.S9S_MB_2U(SCH_1):GND
  A28  GND            GNDA28  @S9S_MB_2U_LIB.S9S_MB_2U(SCH_1):GND
  A25  GND            GNDA25  @S9S_MB_2U_LIB.S9S_MB_2U(SCH_1):GND
  A22  GND            GNDA22  @S9S_MB_2U_LIB.S9S_MB_2U(SCH_1):GND
  A19  GND            GNDA19  @S9S_MB_2U_LIB.S9S_MB_2U(SCH_1):GND
  A16  GND            GNDA16  @S9S_MB_2U_LIB.S9S_MB_2U(SCH_1):GND
  A13  GND            GNDA13  @S9S_MB_2U_LIB.S9S_MB_2U(SCH_1):GND
   A6  GND            GNDA6  @S9S_MB_2U_LIB.S9S_MB_2U(SCH_1):GND
   A5  GND            GNDA5  @S9S_MB_2U_LIB.S9S_MB_2U(SCH_1):GND
   A4  GND            GNDA4  @S9S_MB_2U_LIB.S9S_MB_2U(SCH_1):GND
   A3  GND            GNDA3  @S9S_MB_2U_LIB.S9S_MB_2U(SCH_1):GND
   A2  GND            GNDA2  @S9S_MB_2U_LIB.S9S_MB_2U(SCH_1):GND
   A1  GND            GNDA1  @S9S_MB_2U_LIB.S9S_MB_2U(SCH_1):GND
   G5  GND               G5  @S9S_MB_2U_LIB.S9S_MB_2U(SCH_1):GND
   G4  GND               G4  @S9S_MB_2U_LIB.S9S_MB_2U(SCH_1):GND
   G3  GND               G3  @S9S_MB_2U_LIB.S9S_MB_2U(SCH_1):GND
   G2  GND               G2  @S9S_MB_2U_LIB.S9S_MB_2U(SCH_1):GND
   G1  GND               G1  @S9S_MB_2U_LIB.S9S_MB_2U(SCH_1):GND
  B42  FM_PCIE_EDSFF1B_PRSNT_1_N  PRSNT1_N  @S9S_MB_2U_LIB.S9S_MB_2U(SCH_1):FM_PCIE_EDSFF1B_PRSNT_1_N
   B7  FM_EDSFF1B_TYPE_ID    MFG  @S9S_MB_2U_LIB.S9S_MB_2U(SCH_1):FM_EDSFF1B_TYPE_ID
   B8  FM_EDSFF1B_PWRBRK_N  RFUB8  @S9S_MB_2U_LIB.S9S_MB_2U(SCH_1):FM_EDSFF1B_PWRBRK_N
  B15  CLK_100M_EDSFF1B_DP  REFCLKP0  @S9S_MB_2U_LIB.S9S_MB_2U(SCH_1):CLK_100M_EDSFF1B_DP
  B14  CLK_100M_EDSFF1B_DN  REFCLKN0  @S9S_MB_2U_LIB.S9S_MB_2U(SCH_1):CLK_100M_EDSFF1B_DN
  A15  CLK_100M_EDSFF1B_1_DP  REFCLKP1  @S9S_MB_2U_LIB.S9S_MB_2U(SCH_1):CLK_100M_EDSFF1B_1_DP
  A14  CLK_100M_EDSFF1B_1_DN  REFCLKN1  @S9S_MB_2U_LIB.S9S_MB_2U(SCH_1):CLK_100M_EDSFF1B_1_DN

SCONN84_123318136  I16  J88    [SCONN84_123318136-SCONN84_1-23A]
  A15  NC             REFCLKP1  NC
  A14  NC             REFCLKN1  NC
   B9  SMB_PEHPCPU1_EDSFF4A_LVC3_R_SDA  DUALPORTEN_N  @S9S_MB_2U_LIB.S9S_MB_2U(SCH_1):SMB_PEHPCPU1_EDSFF4A_LVC3_R_SDA
  A10  SMB_PEHPCPU1_EDSFF4A_LVC3_R_SCL  LED_ACTIVITYA10  @S9S_MB_2U_LIB.S9S_MB_2U(SCH_1):SMB_PEHPCPU1_EDSFF4A_LVC3_R_SCL
   A8  SMB_EDSFF4A_3V3AUX_SDA_R  SMBDAT  @S9S_MB_2U_LIB.S9S_MB_2U(SCH_1):SMB_EDSFF4A_3V3AUX_SDA_R
   A7  SMB_EDSFF4A_3V3AUX_SCL_R  SMBCLK  @S9S_MB_2U_LIB.S9S_MB_2U(SCH_1):SMB_EDSFF4A_3V3AUX_SCL_R
   A9  RST_SMB_EDSFF4A_N  SMBRST_N  @S9S_MB_2U_LIB.S9S_MB_2U(SCH_1):RST_SMB_EDSFF4A_N
  B10  RST_PCIE_EDSFF4A_PERST_N  PERST0_N  @S9S_MB_2U_LIB.S9S_MB_2U(SCH_1):RST_PCIE_EDSFF4A_PERST_N
  A12  PD_PCIE_EDSFF4A_PRSNT_0_N  PRSNT0_N  @S9S_MB_2U_LIB.S9S_MB_2U(SCH_1):PD_PCIE_EDSFF4A_PRSNT_0_N
  B12  PD_EDSFF4A_PWRDIS  PWRDIS  @S9S_MB_2U_LIB.S9S_MB_2U(SCH_1):PD_EDSFF4A_PWRDIS
  B39  P5E_CPU1_PE4_TX_C_DP<7>  PERN7  @S9S_MB_2U_LIB.S9S_MB_2U(SCH_1):P5E_CPU1_PE4_TX_C_DP<7>
  B36  P5E_CPU1_PE4_TX_C_DP<6>  PERN6  @S9S_MB_2U_LIB.S9S_MB_2U(SCH_1):P5E_CPU1_PE4_TX_C_DP<6>
  B33  P5E_CPU1_PE4_TX_C_DP<5>  PERN5  @S9S_MB_2U_LIB.S9S_MB_2U(SCH_1):P5E_CPU1_PE4_TX_C_DP<5>
  B30  P5E_CPU1_PE4_TX_C_DP<4>  PERN4  @S9S_MB_2U_LIB.S9S_MB_2U(SCH_1):P5E_CPU1_PE4_TX_C_DP<4>
  B26  P5E_CPU1_PE4_TX_C_DP<3>  PERN3  @S9S_MB_2U_LIB.S9S_MB_2U(SCH_1):P5E_CPU1_PE4_TX_C_DP<3>
  B23  P5E_CPU1_PE4_TX_C_DP<2>  PERN2  @S9S_MB_2U_LIB.S9S_MB_2U(SCH_1):P5E_CPU1_PE4_TX_C_DP<2>
  B20  P5E_CPU1_PE4_TX_C_DP<1>  PERN1  @S9S_MB_2U_LIB.S9S_MB_2U(SCH_1):P5E_CPU1_PE4_TX_C_DP<1>
  B18  P5E_CPU1_PE4_TX_C_DP<0>  PERP0  @S9S_MB_2U_LIB.S9S_MB_2U(SCH_1):P5E_CPU1_PE4_TX_C_DP<0>
  B40  P5E_CPU1_PE4_TX_C_DN<7>  PERP7  @S9S_MB_2U_LIB.S9S_MB_2U(SCH_1):P5E_CPU1_PE4_TX_C_DN<7>
  B37  P5E_CPU1_PE4_TX_C_DN<6>  PERP6  @S9S_MB_2U_LIB.S9S_MB_2U(SCH_1):P5E_CPU1_PE4_TX_C_DN<6>
  B34  P5E_CPU1_PE4_TX_C_DN<5>  PERP5  @S9S_MB_2U_LIB.S9S_MB_2U(SCH_1):P5E_CPU1_PE4_TX_C_DN<5>
  B31  P5E_CPU1_PE4_TX_C_DN<4>  PERP4  @S9S_MB_2U_LIB.S9S_MB_2U(SCH_1):P5E_CPU1_PE4_TX_C_DN<4>
  B27  P5E_CPU1_PE4_TX_C_DN<3>  PERP3  @S9S_MB_2U_LIB.S9S_MB_2U(SCH_1):P5E_CPU1_PE4_TX_C_DN<3>
  B24  P5E_CPU1_PE4_TX_C_DN<2>  PERP2  @S9S_MB_2U_LIB.S9S_MB_2U(SCH_1):P5E_CPU1_PE4_TX_C_DN<2>
  B21  P5E_CPU1_PE4_TX_C_DN<1>  PERP1  @S9S_MB_2U_LIB.S9S_MB_2U(SCH_1):P5E_CPU1_PE4_TX_C_DN<1>
  B17  P5E_CPU1_PE4_TX_C_DN<0>  PERN0  @S9S_MB_2U_LIB.S9S_MB_2U(SCH_1):P5E_CPU1_PE4_TX_C_DN<0>
  A40  P5E_CPU1_PE4_RX_DP<7>  PETP7  @S9S_MB_2U_LIB.S9S_MB_2U(SCH_1):P5E_CPU1_PE4_RX_DP<7>
  A36  P5E_CPU1_PE4_RX_DP<6>  PETN6  @S9S_MB_2U_LIB.S9S_MB_2U(SCH_1):P5E_CPU1_PE4_RX_DP<6>
  A34  P5E_CPU1_PE4_RX_DP<5>  PETP5  @S9S_MB_2U_LIB.S9S_MB_2U(SCH_1):P5E_CPU1_PE4_RX_DP<5>
  A30  P5E_CPU1_PE4_RX_DP<4>  PETN4  @S9S_MB_2U_LIB.S9S_MB_2U(SCH_1):P5E_CPU1_PE4_RX_DP<4>
  A26  P5E_CPU1_PE4_RX_DP<3>  PETN3  @S9S_MB_2U_LIB.S9S_MB_2U(SCH_1):P5E_CPU1_PE4_RX_DP<3>
  A24  P5E_CPU1_PE4_RX_DP<2>  PETP2  @S9S_MB_2U_LIB.S9S_MB_2U(SCH_1):P5E_CPU1_PE4_RX_DP<2>
  A20  P5E_CPU1_PE4_RX_DP<1>  PETN1  @S9S_MB_2U_LIB.S9S_MB_2U(SCH_1):P5E_CPU1_PE4_RX_DP<1>
  A17  P5E_CPU1_PE4_RX_DP<0>  PETN0  @S9S_MB_2U_LIB.S9S_MB_2U(SCH_1):P5E_CPU1_PE4_RX_DP<0>
  A39  P5E_CPU1_PE4_RX_DN<7>  PETN7  @S9S_MB_2U_LIB.S9S_MB_2U(SCH_1):P5E_CPU1_PE4_RX_DN<7>
  A37  P5E_CPU1_PE4_RX_DN<6>  PETP6  @S9S_MB_2U_LIB.S9S_MB_2U(SCH_1):P5E_CPU1_PE4_RX_DN<6>
  A33  P5E_CPU1_PE4_RX_DN<5>  PETN5  @S9S_MB_2U_LIB.S9S_MB_2U(SCH_1):P5E_CPU1_PE4_RX_DN<5>
  A31  P5E_CPU1_PE4_RX_DN<4>  PETP4  @S9S_MB_2U_LIB.S9S_MB_2U(SCH_1):P5E_CPU1_PE4_RX_DN<4>
  A27  P5E_CPU1_PE4_RX_DN<3>  PETP3  @S9S_MB_2U_LIB.S9S_MB_2U(SCH_1):P5E_CPU1_PE4_RX_DN<3>
  A23  P5E_CPU1_PE4_RX_DN<2>  PETN2  @S9S_MB_2U_LIB.S9S_MB_2U(SCH_1):P5E_CPU1_PE4_RX_DN<2>
  A21  P5E_CPU1_PE4_RX_DN<1>  PETP1  @S9S_MB_2U_LIB.S9S_MB_2U(SCH_1):P5E_CPU1_PE4_RX_DN<1>
  A18  P5E_CPU1_PE4_RX_DN<0>  PETP0  @S9S_MB_2U_LIB.S9S_MB_2U(SCH_1):P5E_CPU1_PE4_RX_DN<0>
  B11  P3V3_AUX       3_3VAUX  @S9S_MB_2U_LIB.S9S_MB_2U(SCH_1):P3V3_AUX
   B6  P12V_REAR_CPU  12VB6  @S9S_MB_2U_LIB.S9S_MB_2U(SCH_1):P12V_REAR_CPU
   B5  P12V_REAR_CPU  12VB5  @S9S_MB_2U_LIB.S9S_MB_2U(SCH_1):P12V_REAR_CPU
   B4  P12V_REAR_CPU  12VB4  @S9S_MB_2U_LIB.S9S_MB_2U(SCH_1):P12V_REAR_CPU
   B3  P12V_REAR_CPU  12VB3  @S9S_MB_2U_LIB.S9S_MB_2U(SCH_1):P12V_REAR_CPU
   B2  P12V_REAR_CPU  12VB2  @S9S_MB_2U_LIB.S9S_MB_2U(SCH_1):P12V_REAR_CPU
   B1  P12V_REAR_CPU  12VB1  @S9S_MB_2U_LIB.S9S_MB_2U(SCH_1):P12V_REAR_CPU
  A42  IRQ_LVC3_WAKE_EDSFF4_N    RFU  @S9S_MB_2U_LIB.S9S_MB_2U(SCH_1):IRQ_LVC3_WAKE_EDSFF4_N
  B41  GND            GNDB41  @S9S_MB_2U_LIB.S9S_MB_2U(SCH_1):GND
  B38  GND            GNDB38  @S9S_MB_2U_LIB.S9S_MB_2U(SCH_1):GND
  B35  GND            GNDB35  @S9S_MB_2U_LIB.S9S_MB_2U(SCH_1):GND
  B32  GND            GNDB32  @S9S_MB_2U_LIB.S9S_MB_2U(SCH_1):GND
  B29  GND            GNDB29  @S9S_MB_2U_LIB.S9S_MB_2U(SCH_1):GND
  B28  GND            GNDB28  @S9S_MB_2U_LIB.S9S_MB_2U(SCH_1):GND
  B25  GND            GNDB25  @S9S_MB_2U_LIB.S9S_MB_2U(SCH_1):GND
  B22  GND            GNDB22  @S9S_MB_2U_LIB.S9S_MB_2U(SCH_1):GND
  B19  GND            GNDB19  @S9S_MB_2U_LIB.S9S_MB_2U(SCH_1):GND
  B16  GND            GNDB16  @S9S_MB_2U_LIB.S9S_MB_2U(SCH_1):GND
  B13  GND            GNDB13  @S9S_MB_2U_LIB.S9S_MB_2U(SCH_1):GND
  A41  GND            GNDA41  @S9S_MB_2U_LIB.S9S_MB_2U(SCH_1):GND
  A38  GND            GNDA38  @S9S_MB_2U_LIB.S9S_MB_2U(SCH_1):GND
  A35  GND            GNDA35  @S9S_MB_2U_LIB.S9S_MB_2U(SCH_1):GND
  A32  GND            GNDA32  @S9S_MB_2U_LIB.S9S_MB_2U(SCH_1):GND
  A29  GND            GNDA29  @S9S_MB_2U_LIB.S9S_MB_2U(SCH_1):GND
  A28  GND            GNDA28  @S9S_MB_2U_LIB.S9S_MB_2U(SCH_1):GND
  A25  GND            GNDA25  @S9S_MB_2U_LIB.S9S_MB_2U(SCH_1):GND
  A22  GND            GNDA22  @S9S_MB_2U_LIB.S9S_MB_2U(SCH_1):GND
  A19  GND            GNDA19  @S9S_MB_2U_LIB.S9S_MB_2U(SCH_1):GND
  A16  GND            GNDA16  @S9S_MB_2U_LIB.S9S_MB_2U(SCH_1):GND
  A13  GND            GNDA13  @S9S_MB_2U_LIB.S9S_MB_2U(SCH_1):GND
   A6  GND            GNDA6  @S9S_MB_2U_LIB.S9S_MB_2U(SCH_1):GND
   A5  GND            GNDA5  @S9S_MB_2U_LIB.S9S_MB_2U(SCH_1):GND
   A4  GND            GNDA4  @S9S_MB_2U_LIB.S9S_MB_2U(SCH_1):GND
   A3  GND            GNDA3  @S9S_MB_2U_LIB.S9S_MB_2U(SCH_1):GND
   A2  GND            GNDA2  @S9S_MB_2U_LIB.S9S_MB_2U(SCH_1):GND
   A1  GND            GNDA1  @S9S_MB_2U_LIB.S9S_MB_2U(SCH_1):GND
   G5  GND               G5  @S9S_MB_2U_LIB.S9S_MB_2U(SCH_1):GND
   G4  GND               G4  @S9S_MB_2U_LIB.S9S_MB_2U(SCH_1):GND
   G3  GND               G3  @S9S_MB_2U_LIB.S9S_MB_2U(SCH_1):GND
   G2  GND               G2  @S9S_MB_2U_LIB.S9S_MB_2U(SCH_1):GND
   G1  GND               G1  @S9S_MB_2U_LIB.S9S_MB_2U(SCH_1):GND
  B42  FM_PCIE_EDSFF4A_PRSNT_1_N  PRSNT1_N  @S9S_MB_2U_LIB.S9S_MB_2U(SCH_1):FM_PCIE_EDSFF4A_PRSNT_1_N
   B7  FM_EDSFF4A_TYPE_ID    MFG  @S9S_MB_2U_LIB.S9S_MB_2U(SCH_1):FM_EDSFF4A_TYPE_ID
   B8  FM_EDSFF4A_PWRBRK_N  RFUB8  @S9S_MB_2U_LIB.S9S_MB_2U(SCH_1):FM_EDSFF4A_PWRBRK_N
  A11  EDSFF4A_PERST1_CLKREQ_N  PERST1_N_CLKREQ_N  @S9S_MB_2U_LIB.S9S_MB_2U(SCH_1):EDSFF4A_PERST1_CLKREQ_N
  B15  CLK_100M_EDSFF4A_DP  REFCLKP0  @S9S_MB_2U_LIB.S9S_MB_2U(SCH_1):CLK_100M_EDSFF4A_DP
  B14  CLK_100M_EDSFF4A_DN  REFCLKN0  @S9S_MB_2U_LIB.S9S_MB_2U(SCH_1):CLK_100M_EDSFF4A_DN

SCONN280_ME1028040102011  I282  J89    [SCONN280_ME1028040102011-SCONNA]
  A140  PCIE_RISER2_PRSNT_N   A140  @S9S_MB_2U_LIB.S9S_MB_2U(SCH_1):PCIE_RISER2_PRSNT_N
  B104  P5E_CPU1_PE2_TX_C_DP<9>   B104  @S9S_MB_2U_LIB.S9S_MB_2U(SCH_1):P5E_CPU1_PE2_TX_C_DP<9>
  B107  P5E_CPU1_PE2_TX_C_DP<8>   B107  @S9S_MB_2U_LIB.S9S_MB_2U(SCH_1):P5E_CPU1_PE2_TX_C_DP<8>
  B110  P5E_CPU1_PE2_TX_C_DP<7>   B110  @S9S_MB_2U_LIB.S9S_MB_2U(SCH_1):P5E_CPU1_PE2_TX_C_DP<7>
  B114  P5E_CPU1_PE2_TX_C_DP<6>   B114  @S9S_MB_2U_LIB.S9S_MB_2U(SCH_1):P5E_CPU1_PE2_TX_C_DP<6>
  B117  P5E_CPU1_PE2_TX_C_DP<5>   B117  @S9S_MB_2U_LIB.S9S_MB_2U(SCH_1):P5E_CPU1_PE2_TX_C_DP<5>
  B120  P5E_CPU1_PE2_TX_C_DP<4>   B120  @S9S_MB_2U_LIB.S9S_MB_2U(SCH_1):P5E_CPU1_PE2_TX_C_DP<4>
  B123  P5E_CPU1_PE2_TX_C_DP<3>   B123  @S9S_MB_2U_LIB.S9S_MB_2U(SCH_1):P5E_CPU1_PE2_TX_C_DP<3>
  B126  P5E_CPU1_PE2_TX_C_DP<2>   B126  @S9S_MB_2U_LIB.S9S_MB_2U(SCH_1):P5E_CPU1_PE2_TX_C_DP<2>
  B129  P5E_CPU1_PE2_TX_C_DP<1>   B129  @S9S_MB_2U_LIB.S9S_MB_2U(SCH_1):P5E_CPU1_PE2_TX_C_DP<1>
  B86  P5E_CPU1_PE2_TX_C_DP<15>    B86  @S9S_MB_2U_LIB.S9S_MB_2U(SCH_1):P5E_CPU1_PE2_TX_C_DP<15>
  B89  P5E_CPU1_PE2_TX_C_DP<14>    B89  @S9S_MB_2U_LIB.S9S_MB_2U(SCH_1):P5E_CPU1_PE2_TX_C_DP<14>
  B92  P5E_CPU1_PE2_TX_C_DP<13>    B92  @S9S_MB_2U_LIB.S9S_MB_2U(SCH_1):P5E_CPU1_PE2_TX_C_DP<13>
  B95  P5E_CPU1_PE2_TX_C_DP<12>    B95  @S9S_MB_2U_LIB.S9S_MB_2U(SCH_1):P5E_CPU1_PE2_TX_C_DP<12>
  B98  P5E_CPU1_PE2_TX_C_DP<11>    B98  @S9S_MB_2U_LIB.S9S_MB_2U(SCH_1):P5E_CPU1_PE2_TX_C_DP<11>
  B101  P5E_CPU1_PE2_TX_C_DP<10>   B101  @S9S_MB_2U_LIB.S9S_MB_2U(SCH_1):P5E_CPU1_PE2_TX_C_DP<10>
  B132  P5E_CPU1_PE2_TX_C_DP<0>   B132  @S9S_MB_2U_LIB.S9S_MB_2U(SCH_1):P5E_CPU1_PE2_TX_C_DP<0>
  B105  P5E_CPU1_PE2_TX_C_DN<9>   B105  @S9S_MB_2U_LIB.S9S_MB_2U(SCH_1):P5E_CPU1_PE2_TX_C_DN<9>
  B108  P5E_CPU1_PE2_TX_C_DN<8>   B108  @S9S_MB_2U_LIB.S9S_MB_2U(SCH_1):P5E_CPU1_PE2_TX_C_DN<8>
  B111  P5E_CPU1_PE2_TX_C_DN<7>   B111  @S9S_MB_2U_LIB.S9S_MB_2U(SCH_1):P5E_CPU1_PE2_TX_C_DN<7>
  B115  P5E_CPU1_PE2_TX_C_DN<6>   B115  @S9S_MB_2U_LIB.S9S_MB_2U(SCH_1):P5E_CPU1_PE2_TX_C_DN<6>
  B118  P5E_CPU1_PE2_TX_C_DN<5>   B118  @S9S_MB_2U_LIB.S9S_MB_2U(SCH_1):P5E_CPU1_PE2_TX_C_DN<5>
  B121  P5E_CPU1_PE2_TX_C_DN<4>   B121  @S9S_MB_2U_LIB.S9S_MB_2U(SCH_1):P5E_CPU1_PE2_TX_C_DN<4>
  B124  P5E_CPU1_PE2_TX_C_DN<3>   B124  @S9S_MB_2U_LIB.S9S_MB_2U(SCH_1):P5E_CPU1_PE2_TX_C_DN<3>
  B127  P5E_CPU1_PE2_TX_C_DN<2>   B127  @S9S_MB_2U_LIB.S9S_MB_2U(SCH_1):P5E_CPU1_PE2_TX_C_DN<2>
  B130  P5E_CPU1_PE2_TX_C_DN<1>   B130  @S9S_MB_2U_LIB.S9S_MB_2U(SCH_1):P5E_CPU1_PE2_TX_C_DN<1>
  B87  P5E_CPU1_PE2_TX_C_DN<15>    B87  @S9S_MB_2U_LIB.S9S_MB_2U(SCH_1):P5E_CPU1_PE2_TX_C_DN<15>
  B90  P5E_CPU1_PE2_TX_C_DN<14>    B90  @S9S_MB_2U_LIB.S9S_MB_2U(SCH_1):P5E_CPU1_PE2_TX_C_DN<14>
  B93  P5E_CPU1_PE2_TX_C_DN<13>    B93  @S9S_MB_2U_LIB.S9S_MB_2U(SCH_1):P5E_CPU1_PE2_TX_C_DN<13>
  B96  P5E_CPU1_PE2_TX_C_DN<12>    B96  @S9S_MB_2U_LIB.S9S_MB_2U(SCH_1):P5E_CPU1_PE2_TX_C_DN<12>
  B99  P5E_CPU1_PE2_TX_C_DN<11>    B99  @S9S_MB_2U_LIB.S9S_MB_2U(SCH_1):P5E_CPU1_PE2_TX_C_DN<11>
  B102  P5E_CPU1_PE2_TX_C_DN<10>   B102  @S9S_MB_2U_LIB.S9S_MB_2U(SCH_1):P5E_CPU1_PE2_TX_C_DN<10>
  B133  P5E_CPU1_PE2_TX_C_DN<0>   B133  @S9S_MB_2U_LIB.S9S_MB_2U(SCH_1):P5E_CPU1_PE2_TX_C_DN<0>
  A104  P5E_CPU1_PE2_RX_DP<9>   A104  @S9S_MB_2U_LIB.S9S_MB_2U(SCH_1):P5E_CPU1_PE2_RX_DP<9>
  A107  P5E_CPU1_PE2_RX_DP<8>   A107  @S9S_MB_2U_LIB.S9S_MB_2U(SCH_1):P5E_CPU1_PE2_RX_DP<8>
  A110  P5E_CPU1_PE2_RX_DP<7>   A110  @S9S_MB_2U_LIB.S9S_MB_2U(SCH_1):P5E_CPU1_PE2_RX_DP<7>
  A114  P5E_CPU1_PE2_RX_DP<6>   A114  @S9S_MB_2U_LIB.S9S_MB_2U(SCH_1):P5E_CPU1_PE2_RX_DP<6>
  A117  P5E_CPU1_PE2_RX_DP<5>   A117  @S9S_MB_2U_LIB.S9S_MB_2U(SCH_1):P5E_CPU1_PE2_RX_DP<5>
  A120  P5E_CPU1_PE2_RX_DP<4>   A120  @S9S_MB_2U_LIB.S9S_MB_2U(SCH_1):P5E_CPU1_PE2_RX_DP<4>
  A123  P5E_CPU1_PE2_RX_DP<3>   A123  @S9S_MB_2U_LIB.S9S_MB_2U(SCH_1):P5E_CPU1_PE2_RX_DP<3>
  A126  P5E_CPU1_PE2_RX_DP<2>   A126  @S9S_MB_2U_LIB.S9S_MB_2U(SCH_1):P5E_CPU1_PE2_RX_DP<2>
  A129  P5E_CPU1_PE2_RX_DP<1>   A129  @S9S_MB_2U_LIB.S9S_MB_2U(SCH_1):P5E_CPU1_PE2_RX_DP<1>
  A86  P5E_CPU1_PE2_RX_DP<15>    A86  @S9S_MB_2U_LIB.S9S_MB_2U(SCH_1):P5E_CPU1_PE2_RX_DP<15>
  A89  P5E_CPU1_PE2_RX_DP<14>    A89  @S9S_MB_2U_LIB.S9S_MB_2U(SCH_1):P5E_CPU1_PE2_RX_DP<14>
  A92  P5E_CPU1_PE2_RX_DP<13>    A92  @S9S_MB_2U_LIB.S9S_MB_2U(SCH_1):P5E_CPU1_PE2_RX_DP<13>
  A95  P5E_CPU1_PE2_RX_DP<12>    A95  @S9S_MB_2U_LIB.S9S_MB_2U(SCH_1):P5E_CPU1_PE2_RX_DP<12>
  A98  P5E_CPU1_PE2_RX_DP<11>    A98  @S9S_MB_2U_LIB.S9S_MB_2U(SCH_1):P5E_CPU1_PE2_RX_DP<11>
  A101  P5E_CPU1_PE2_RX_DP<10>   A101  @S9S_MB_2U_LIB.S9S_MB_2U(SCH_1):P5E_CPU1_PE2_RX_DP<10>
  A132  P5E_CPU1_PE2_RX_DP<0>   A132  @S9S_MB_2U_LIB.S9S_MB_2U(SCH_1):P5E_CPU1_PE2_RX_DP<0>
  A105  P5E_CPU1_PE2_RX_DN<9>   A105  @S9S_MB_2U_LIB.S9S_MB_2U(SCH_1):P5E_CPU1_PE2_RX_DN<9>
  A108  P5E_CPU1_PE2_RX_DN<8>   A108  @S9S_MB_2U_LIB.S9S_MB_2U(SCH_1):P5E_CPU1_PE2_RX_DN<8>
  A111  P5E_CPU1_PE2_RX_DN<7>   A111  @S9S_MB_2U_LIB.S9S_MB_2U(SCH_1):P5E_CPU1_PE2_RX_DN<7>
  A115  P5E_CPU1_PE2_RX_DN<6>   A115  @S9S_MB_2U_LIB.S9S_MB_2U(SCH_1):P5E_CPU1_PE2_RX_DN<6>
  A118  P5E_CPU1_PE2_RX_DN<5>   A118  @S9S_MB_2U_LIB.S9S_MB_2U(SCH_1):P5E_CPU1_PE2_RX_DN<5>
  A121  P5E_CPU1_PE2_RX_DN<4>   A121  @S9S_MB_2U_LIB.S9S_MB_2U(SCH_1):P5E_CPU1_PE2_RX_DN<4>
  A124  P5E_CPU1_PE2_RX_DN<3>   A124  @S9S_MB_2U_LIB.S9S_MB_2U(SCH_1):P5E_CPU1_PE2_RX_DN<3>
  A127  P5E_CPU1_PE2_RX_DN<2>   A127  @S9S_MB_2U_LIB.S9S_MB_2U(SCH_1):P5E_CPU1_PE2_RX_DN<2>
  A130  P5E_CPU1_PE2_RX_DN<1>   A130  @S9S_MB_2U_LIB.S9S_MB_2U(SCH_1):P5E_CPU1_PE2_RX_DN<1>
  A87  P5E_CPU1_PE2_RX_DN<15>    A87  @S9S_MB_2U_LIB.S9S_MB_2U(SCH_1):P5E_CPU1_PE2_RX_DN<15>
  A90  P5E_CPU1_PE2_RX_DN<14>    A90  @S9S_MB_2U_LIB.S9S_MB_2U(SCH_1):P5E_CPU1_PE2_RX_DN<14>
  A93  P5E_CPU1_PE2_RX_DN<13>    A93  @S9S_MB_2U_LIB.S9S_MB_2U(SCH_1):P5E_CPU1_PE2_RX_DN<13>
  A96  P5E_CPU1_PE2_RX_DN<12>    A96  @S9S_MB_2U_LIB.S9S_MB_2U(SCH_1):P5E_CPU1_PE2_RX_DN<12>
  A99  P5E_CPU1_PE2_RX_DN<11>    A99  @S9S_MB_2U_LIB.S9S_MB_2U(SCH_1):P5E_CPU1_PE2_RX_DN<11>
  A102  P5E_CPU1_PE2_RX_DN<10>   A102  @S9S_MB_2U_LIB.S9S_MB_2U(SCH_1):P5E_CPU1_PE2_RX_DN<10>
  A133  P5E_CPU1_PE2_RX_DN<0>   A133  @S9S_MB_2U_LIB.S9S_MB_2U(SCH_1):P5E_CPU1_PE2_RX_DN<0>
  B140  P3V3            B140  @S9S_MB_2U_LIB.S9S_MB_2U(SCH_1):P3V3
  B139  P3V3            B139  @S9S_MB_2U_LIB.S9S_MB_2U(SCH_1):P3V3
  B138  P3V3            B138  @S9S_MB_2U_LIB.S9S_MB_2U(SCH_1):P3V3
  B137  P3V3            B137  @S9S_MB_2U_LIB.S9S_MB_2U(SCH_1):P3V3
  B136  P3V3            B136  @S9S_MB_2U_LIB.S9S_MB_2U(SCH_1):P3V3
  B135  P3V3            B135  @S9S_MB_2U_LIB.S9S_MB_2U(SCH_1):P3V3
   G4  GND               G4  @S9S_MB_2U_LIB.S9S_MB_2U(SCH_1):GND
   G3  GND               G3  @S9S_MB_2U_LIB.S9S_MB_2U(SCH_1):GND
   G2  GND               G2  @S9S_MB_2U_LIB.S9S_MB_2U(SCH_1):GND
   G1  GND               G1  @S9S_MB_2U_LIB.S9S_MB_2U(SCH_1):GND
  B134  GND             B134  @S9S_MB_2U_LIB.S9S_MB_2U(SCH_1):GND
  B131  GND             B131  @S9S_MB_2U_LIB.S9S_MB_2U(SCH_1):GND
  B128  GND             B128  @S9S_MB_2U_LIB.S9S_MB_2U(SCH_1):GND
  B125  GND             B125  @S9S_MB_2U_LIB.S9S_MB_2U(SCH_1):GND
  B122  GND             B122  @S9S_MB_2U_LIB.S9S_MB_2U(SCH_1):GND
  B119  GND             B119  @S9S_MB_2U_LIB.S9S_MB_2U(SCH_1):GND
  B116  GND             B116  @S9S_MB_2U_LIB.S9S_MB_2U(SCH_1):GND
  B113  GND             B113  @S9S_MB_2U_LIB.S9S_MB_2U(SCH_1):GND
  B112  GND             B112  @S9S_MB_2U_LIB.S9S_MB_2U(SCH_1):GND
  B109  GND             B109  @S9S_MB_2U_LIB.S9S_MB_2U(SCH_1):GND
  B106  GND             B106  @S9S_MB_2U_LIB.S9S_MB_2U(SCH_1):GND
  B103  GND             B103  @S9S_MB_2U_LIB.S9S_MB_2U(SCH_1):GND
  B100  GND             B100  @S9S_MB_2U_LIB.S9S_MB_2U(SCH_1):GND
  B97  GND              B97  @S9S_MB_2U_LIB.S9S_MB_2U(SCH_1):GND
  B94  GND              B94  @S9S_MB_2U_LIB.S9S_MB_2U(SCH_1):GND
  B91  GND              B91  @S9S_MB_2U_LIB.S9S_MB_2U(SCH_1):GND
  B88  GND              B88  @S9S_MB_2U_LIB.S9S_MB_2U(SCH_1):GND
  B85  GND              B85  @S9S_MB_2U_LIB.S9S_MB_2U(SCH_1):GND
  A139  GND             A139  @S9S_MB_2U_LIB.S9S_MB_2U(SCH_1):GND
  A138  GND             A138  @S9S_MB_2U_LIB.S9S_MB_2U(SCH_1):GND
  A137  GND             A137  @S9S_MB_2U_LIB.S9S_MB_2U(SCH_1):GND
  A136  GND             A136  @S9S_MB_2U_LIB.S9S_MB_2U(SCH_1):GND
  A135  GND             A135  @S9S_MB_2U_LIB.S9S_MB_2U(SCH_1):GND
  A134  GND             A134  @S9S_MB_2U_LIB.S9S_MB_2U(SCH_1):GND
  A131  GND             A131  @S9S_MB_2U_LIB.S9S_MB_2U(SCH_1):GND
  A128  GND             A128  @S9S_MB_2U_LIB.S9S_MB_2U(SCH_1):GND
  A125  GND             A125  @S9S_MB_2U_LIB.S9S_MB_2U(SCH_1):GND
  A122  GND             A122  @S9S_MB_2U_LIB.S9S_MB_2U(SCH_1):GND
  A119  GND             A119  @S9S_MB_2U_LIB.S9S_MB_2U(SCH_1):GND
  A116  GND             A116  @S9S_MB_2U_LIB.S9S_MB_2U(SCH_1):GND
  A113  GND             A113  @S9S_MB_2U_LIB.S9S_MB_2U(SCH_1):GND
  A112  GND             A112  @S9S_MB_2U_LIB.S9S_MB_2U(SCH_1):GND
  A109  GND             A109  @S9S_MB_2U_LIB.S9S_MB_2U(SCH_1):GND
  A106  GND             A106  @S9S_MB_2U_LIB.S9S_MB_2U(SCH_1):GND
  A103  GND             A103  @S9S_MB_2U_LIB.S9S_MB_2U(SCH_1):GND
  A100  GND             A100  @S9S_MB_2U_LIB.S9S_MB_2U(SCH_1):GND
  A97  GND              A97  @S9S_MB_2U_LIB.S9S_MB_2U(SCH_1):GND
  A94  GND              A94  @S9S_MB_2U_LIB.S9S_MB_2U(SCH_1):GND
  A91  GND              A91  @S9S_MB_2U_LIB.S9S_MB_2U(SCH_1):GND
  A88  GND              A88  @S9S_MB_2U_LIB.S9S_MB_2U(SCH_1):GND
  A85  GND              A85  @S9S_MB_2U_LIB.S9S_MB_2U(SCH_1):GND

SCONN280_ME1028040102011  I239  J89    [SCONN280_ME1028040102011-SCONNA]
  B25  SMB_RISER2_1_3V3AUX_SDA    B25  @S9S_MB_2U_LIB.S9S_MB_2U(SCH_1):SMB_RISER2_1_3V3AUX_SDA
  B24  SMB_RISER2_1_3V3AUX_SCL    B24  @S9S_MB_2U_LIB.S9S_MB_2U(SCH_1):SMB_RISER2_1_3V3AUX_SCL
  A21  SMB_RISER2_0_3V3AUX_SDA    A21  @S9S_MB_2U_LIB.S9S_MB_2U(SCH_1):SMB_RISER2_0_3V3AUX_SDA
  A20  SMB_RISER2_0_3V3AUX_SCL    A20  @S9S_MB_2U_LIB.S9S_MB_2U(SCH_1):SMB_RISER2_0_3V3AUX_SCL
  A30  RST_PCIE_RISER2_N    A30  @S9S_MB_2U_LIB.S9S_MB_2U(SCH_1):RST_PCIE_RISER2_N
  B21  RISER2_USB2_4_DP    B21  @S9S_MB_2U_LIB.S9S_MB_2U(SCH_1):RISER2_USB2_4_DP
  B20  RISER2_USB2_4_DN    B20  @S9S_MB_2U_LIB.S9S_MB_2U(SCH_1):RISER2_USB2_4_DN
  B31  RISER2_TYPE_ID    B31  @S9S_MB_2U_LIB.S9S_MB_2U(SCH_1):RISER2_TYPE_ID
  B27  RISER2_CLK3_EN_N    B27  @S9S_MB_2U_LIB.S9S_MB_2U(SCH_1):RISER2_CLK3_EN_N
  A31  RISER2_CLK2_EN_N    A31  @S9S_MB_2U_LIB.S9S_MB_2U(SCH_1):RISER2_CLK2_EN_N
   A1  PD_RISER2_PRSNT1     A1  @S9S_MB_2U_LIB.S9S_MB_2U(SCH_1):PD_RISER2_PRSNT1
  B54  P5E_CPU1_PE0_TX_C_DP<9>    B54  @S9S_MB_2U_LIB.S9S_MB_2U(SCH_1):P5E_CPU1_PE0_TX_C_DP<9>
  B58  P5E_CPU1_PE0_TX_C_DP<8>    B58  @S9S_MB_2U_LIB.S9S_MB_2U(SCH_1):P5E_CPU1_PE0_TX_C_DP<8>
  B61  P5E_CPU1_PE0_TX_C_DP<7>    B61  @S9S_MB_2U_LIB.S9S_MB_2U(SCH_1):P5E_CPU1_PE0_TX_C_DP<7>
  B64  P5E_CPU1_PE0_TX_C_DP<6>    B64  @S9S_MB_2U_LIB.S9S_MB_2U(SCH_1):P5E_CPU1_PE0_TX_C_DP<6>
  B67  P5E_CPU1_PE0_TX_C_DP<5>    B67  @S9S_MB_2U_LIB.S9S_MB_2U(SCH_1):P5E_CPU1_PE0_TX_C_DP<5>
  B70  P5E_CPU1_PE0_TX_C_DP<4>    B70  @S9S_MB_2U_LIB.S9S_MB_2U(SCH_1):P5E_CPU1_PE0_TX_C_DP<4>
  B73  P5E_CPU1_PE0_TX_C_DP<3>    B73  @S9S_MB_2U_LIB.S9S_MB_2U(SCH_1):P5E_CPU1_PE0_TX_C_DP<3>
  B76  P5E_CPU1_PE0_TX_C_DP<2>    B76  @S9S_MB_2U_LIB.S9S_MB_2U(SCH_1):P5E_CPU1_PE0_TX_C_DP<2>
  B79  P5E_CPU1_PE0_TX_C_DP<1>    B79  @S9S_MB_2U_LIB.S9S_MB_2U(SCH_1):P5E_CPU1_PE0_TX_C_DP<1>
  B36  P5E_CPU1_PE0_TX_C_DP<15>    B36  @S9S_MB_2U_LIB.S9S_MB_2U(SCH_1):P5E_CPU1_PE0_TX_C_DP<15>
  B39  P5E_CPU1_PE0_TX_C_DP<14>    B39  @S9S_MB_2U_LIB.S9S_MB_2U(SCH_1):P5E_CPU1_PE0_TX_C_DP<14>
  B42  P5E_CPU1_PE0_TX_C_DP<13>    B42  @S9S_MB_2U_LIB.S9S_MB_2U(SCH_1):P5E_CPU1_PE0_TX_C_DP<13>
  B45  P5E_CPU1_PE0_TX_C_DP<12>    B45  @S9S_MB_2U_LIB.S9S_MB_2U(SCH_1):P5E_CPU1_PE0_TX_C_DP<12>
  B48  P5E_CPU1_PE0_TX_C_DP<11>    B48  @S9S_MB_2U_LIB.S9S_MB_2U(SCH_1):P5E_CPU1_PE0_TX_C_DP<11>
  B51  P5E_CPU1_PE0_TX_C_DP<10>    B51  @S9S_MB_2U_LIB.S9S_MB_2U(SCH_1):P5E_CPU1_PE0_TX_C_DP<10>
  B82  P5E_CPU1_PE0_TX_C_DP<0>    B82  @S9S_MB_2U_LIB.S9S_MB_2U(SCH_1):P5E_CPU1_PE0_TX_C_DP<0>
  B55  P5E_CPU1_PE0_TX_C_DN<9>    B55  @S9S_MB_2U_LIB.S9S_MB_2U(SCH_1):P5E_CPU1_PE0_TX_C_DN<9>
  B59  P5E_CPU1_PE0_TX_C_DN<8>    B59  @S9S_MB_2U_LIB.S9S_MB_2U(SCH_1):P5E_CPU1_PE0_TX_C_DN<8>
  B62  P5E_CPU1_PE0_TX_C_DN<7>    B62  @S9S_MB_2U_LIB.S9S_MB_2U(SCH_1):P5E_CPU1_PE0_TX_C_DN<7>
  B65  P5E_CPU1_PE0_TX_C_DN<6>    B65  @S9S_MB_2U_LIB.S9S_MB_2U(SCH_1):P5E_CPU1_PE0_TX_C_DN<6>
  B68  P5E_CPU1_PE0_TX_C_DN<5>    B68  @S9S_MB_2U_LIB.S9S_MB_2U(SCH_1):P5E_CPU1_PE0_TX_C_DN<5>
  B71  P5E_CPU1_PE0_TX_C_DN<4>    B71  @S9S_MB_2U_LIB.S9S_MB_2U(SCH_1):P5E_CPU1_PE0_TX_C_DN<4>
  B74  P5E_CPU1_PE0_TX_C_DN<3>    B74  @S9S_MB_2U_LIB.S9S_MB_2U(SCH_1):P5E_CPU1_PE0_TX_C_DN<3>
  B77  P5E_CPU1_PE0_TX_C_DN<2>    B77  @S9S_MB_2U_LIB.S9S_MB_2U(SCH_1):P5E_CPU1_PE0_TX_C_DN<2>
  B80  P5E_CPU1_PE0_TX_C_DN<1>    B80  @S9S_MB_2U_LIB.S9S_MB_2U(SCH_1):P5E_CPU1_PE0_TX_C_DN<1>
  B37  P5E_CPU1_PE0_TX_C_DN<15>    B37  @S9S_MB_2U_LIB.S9S_MB_2U(SCH_1):P5E_CPU1_PE0_TX_C_DN<15>
  B40  P5E_CPU1_PE0_TX_C_DN<14>    B40  @S9S_MB_2U_LIB.S9S_MB_2U(SCH_1):P5E_CPU1_PE0_TX_C_DN<14>
  B43  P5E_CPU1_PE0_TX_C_DN<13>    B43  @S9S_MB_2U_LIB.S9S_MB_2U(SCH_1):P5E_CPU1_PE0_TX_C_DN<13>
  B46  P5E_CPU1_PE0_TX_C_DN<12>    B46  @S9S_MB_2U_LIB.S9S_MB_2U(SCH_1):P5E_CPU1_PE0_TX_C_DN<12>
  B49  P5E_CPU1_PE0_TX_C_DN<11>    B49  @S9S_MB_2U_LIB.S9S_MB_2U(SCH_1):P5E_CPU1_PE0_TX_C_DN<11>
  B52  P5E_CPU1_PE0_TX_C_DN<10>    B52  @S9S_MB_2U_LIB.S9S_MB_2U(SCH_1):P5E_CPU1_PE0_TX_C_DN<10>
  B83  P5E_CPU1_PE0_TX_C_DN<0>    B83  @S9S_MB_2U_LIB.S9S_MB_2U(SCH_1):P5E_CPU1_PE0_TX_C_DN<0>
  A54  P5E_CPU1_PE0_RX_DP<9>    A54  @S9S_MB_2U_LIB.S9S_MB_2U(SCH_1):P5E_CPU1_PE0_RX_DP<9>
  A58  P5E_CPU1_PE0_RX_DP<8>    A58  @S9S_MB_2U_LIB.S9S_MB_2U(SCH_1):P5E_CPU1_PE0_RX_DP<8>
  A61  P5E_CPU1_PE0_RX_DP<7>    A61  @S9S_MB_2U_LIB.S9S_MB_2U(SCH_1):P5E_CPU1_PE0_RX_DP<7>
  A64  P5E_CPU1_PE0_RX_DP<6>    A64  @S9S_MB_2U_LIB.S9S_MB_2U(SCH_1):P5E_CPU1_PE0_RX_DP<6>
  A67  P5E_CPU1_PE0_RX_DP<5>    A67  @S9S_MB_2U_LIB.S9S_MB_2U(SCH_1):P5E_CPU1_PE0_RX_DP<5>
  A70  P5E_CPU1_PE0_RX_DP<4>    A70  @S9S_MB_2U_LIB.S9S_MB_2U(SCH_1):P5E_CPU1_PE0_RX_DP<4>
  A73  P5E_CPU1_PE0_RX_DP<3>    A73  @S9S_MB_2U_LIB.S9S_MB_2U(SCH_1):P5E_CPU1_PE0_RX_DP<3>
  A76  P5E_CPU1_PE0_RX_DP<2>    A76  @S9S_MB_2U_LIB.S9S_MB_2U(SCH_1):P5E_CPU1_PE0_RX_DP<2>
  A79  P5E_CPU1_PE0_RX_DP<1>    A79  @S9S_MB_2U_LIB.S9S_MB_2U(SCH_1):P5E_CPU1_PE0_RX_DP<1>
  A36  P5E_CPU1_PE0_RX_DP<15>    A36  @S9S_MB_2U_LIB.S9S_MB_2U(SCH_1):P5E_CPU1_PE0_RX_DP<15>
  A39  P5E_CPU1_PE0_RX_DP<14>    A39  @S9S_MB_2U_LIB.S9S_MB_2U(SCH_1):P5E_CPU1_PE0_RX_DP<14>
  A42  P5E_CPU1_PE0_RX_DP<13>    A42  @S9S_MB_2U_LIB.S9S_MB_2U(SCH_1):P5E_CPU1_PE0_RX_DP<13>
  A45  P5E_CPU1_PE0_RX_DP<12>    A45  @S9S_MB_2U_LIB.S9S_MB_2U(SCH_1):P5E_CPU1_PE0_RX_DP<12>
  A48  P5E_CPU1_PE0_RX_DP<11>    A48  @S9S_MB_2U_LIB.S9S_MB_2U(SCH_1):P5E_CPU1_PE0_RX_DP<11>
  A51  P5E_CPU1_PE0_RX_DP<10>    A51  @S9S_MB_2U_LIB.S9S_MB_2U(SCH_1):P5E_CPU1_PE0_RX_DP<10>
  A82  P5E_CPU1_PE0_RX_DP<0>    A82  @S9S_MB_2U_LIB.S9S_MB_2U(SCH_1):P5E_CPU1_PE0_RX_DP<0>
  A55  P5E_CPU1_PE0_RX_DN<9>    A55  @S9S_MB_2U_LIB.S9S_MB_2U(SCH_1):P5E_CPU1_PE0_RX_DN<9>
  A59  P5E_CPU1_PE0_RX_DN<8>    A59  @S9S_MB_2U_LIB.S9S_MB_2U(SCH_1):P5E_CPU1_PE0_RX_DN<8>
  A62  P5E_CPU1_PE0_RX_DN<7>    A62  @S9S_MB_2U_LIB.S9S_MB_2U(SCH_1):P5E_CPU1_PE0_RX_DN<7>
  A65  P5E_CPU1_PE0_RX_DN<6>    A65  @S9S_MB_2U_LIB.S9S_MB_2U(SCH_1):P5E_CPU1_PE0_RX_DN<6>
  A68  P5E_CPU1_PE0_RX_DN<5>    A68  @S9S_MB_2U_LIB.S9S_MB_2U(SCH_1):P5E_CPU1_PE0_RX_DN<5>
  A71  P5E_CPU1_PE0_RX_DN<4>    A71  @S9S_MB_2U_LIB.S9S_MB_2U(SCH_1):P5E_CPU1_PE0_RX_DN<4>
  A74  P5E_CPU1_PE0_RX_DN<3>    A74  @S9S_MB_2U_LIB.S9S_MB_2U(SCH_1):P5E_CPU1_PE0_RX_DN<3>
  A77  P5E_CPU1_PE0_RX_DN<2>    A77  @S9S_MB_2U_LIB.S9S_MB_2U(SCH_1):P5E_CPU1_PE0_RX_DN<2>
  A80  P5E_CPU1_PE0_RX_DN<1>    A80  @S9S_MB_2U_LIB.S9S_MB_2U(SCH_1):P5E_CPU1_PE0_RX_DN<1>
  A37  P5E_CPU1_PE0_RX_DN<15>    A37  @S9S_MB_2U_LIB.S9S_MB_2U(SCH_1):P5E_CPU1_PE0_RX_DN<15>
  A40  P5E_CPU1_PE0_RX_DN<14>    A40  @S9S_MB_2U_LIB.S9S_MB_2U(SCH_1):P5E_CPU1_PE0_RX_DN<14>
  A43  P5E_CPU1_PE0_RX_DN<13>    A43  @S9S_MB_2U_LIB.S9S_MB_2U(SCH_1):P5E_CPU1_PE0_RX_DN<13>
  A46  P5E_CPU1_PE0_RX_DN<12>    A46  @S9S_MB_2U_LIB.S9S_MB_2U(SCH_1):P5E_CPU1_PE0_RX_DN<12>
  A49  P5E_CPU1_PE0_RX_DN<11>    A49  @S9S_MB_2U_LIB.S9S_MB_2U(SCH_1):P5E_CPU1_PE0_RX_DN<11>
  A52  P5E_CPU1_PE0_RX_DN<10>    A52  @S9S_MB_2U_LIB.S9S_MB_2U(SCH_1):P5E_CPU1_PE0_RX_DN<10>
  A83  P5E_CPU1_PE0_RX_DN<0>    A83  @S9S_MB_2U_LIB.S9S_MB_2U(SCH_1):P5E_CPU1_PE0_RX_DN<0>
  B22  P3V3_AUX         B22  @S9S_MB_2U_LIB.S9S_MB_2U(SCH_1):P3V3_AUX
   A7  P12V_FRONT_CPU0     A7  @S9S_MB_2U_LIB.S9S_MB_2U(SCH_1):P12V_FRONT_CPU0
   A6  P12V_FRONT_CPU0     A6  @S9S_MB_2U_LIB.S9S_MB_2U(SCH_1):P12V_FRONT_CPU0
   A5  P12V_FRONT_CPU0     A5  @S9S_MB_2U_LIB.S9S_MB_2U(SCH_1):P12V_FRONT_CPU0
   A4  P12V_FRONT_CPU0     A4  @S9S_MB_2U_LIB.S9S_MB_2U(SCH_1):P12V_FRONT_CPU0
   A3  P12V_FRONT_CPU0     A3  @S9S_MB_2U_LIB.S9S_MB_2U(SCH_1):P12V_FRONT_CPU0
   A2  P12V_FRONT_CPU0     A2  @S9S_MB_2U_LIB.S9S_MB_2U(SCH_1):P12V_FRONT_CPU0
  B18  P12V_FRONT_CPU    B18  @S9S_MB_2U_LIB.S9S_MB_2U(SCH_1):P12V_FRONT_CPU
  B17  P12V_FRONT_CPU    B17  @S9S_MB_2U_LIB.S9S_MB_2U(SCH_1):P12V_FRONT_CPU
  B16  P12V_FRONT_CPU    B16  @S9S_MB_2U_LIB.S9S_MB_2U(SCH_1):P12V_FRONT_CPU
  B15  P12V_FRONT_CPU    B15  @S9S_MB_2U_LIB.S9S_MB_2U(SCH_1):P12V_FRONT_CPU
  B14  P12V_FRONT_CPU    B14  @S9S_MB_2U_LIB.S9S_MB_2U(SCH_1):P12V_FRONT_CPU
  B13  P12V_FRONT_CPU    B13  @S9S_MB_2U_LIB.S9S_MB_2U(SCH_1):P12V_FRONT_CPU
   B7  P12V_FRONT_CPU     B7  @S9S_MB_2U_LIB.S9S_MB_2U(SCH_1):P12V_FRONT_CPU
   B6  P12V_FRONT_CPU     B6  @S9S_MB_2U_LIB.S9S_MB_2U(SCH_1):P12V_FRONT_CPU
   B5  P12V_FRONT_CPU     B5  @S9S_MB_2U_LIB.S9S_MB_2U(SCH_1):P12V_FRONT_CPU
   B4  P12V_FRONT_CPU     B4  @S9S_MB_2U_LIB.S9S_MB_2U(SCH_1):P12V_FRONT_CPU
   B3  P12V_FRONT_CPU     B3  @S9S_MB_2U_LIB.S9S_MB_2U(SCH_1):P12V_FRONT_CPU
   B2  P12V_FRONT_CPU     B2  @S9S_MB_2U_LIB.S9S_MB_2U(SCH_1):P12V_FRONT_CPU
   B1  P12V_FRONT_CPU     B1  @S9S_MB_2U_LIB.S9S_MB_2U(SCH_1):P12V_FRONT_CPU
  A27  JTAG_RISER2_TRST_N    A27  @S9S_MB_2U_LIB.S9S_MB_2U(SCH_1):JTAG_RISER2_TRST_N
  A26  JTAG_RISER2_TMS    A26  @S9S_MB_2U_LIB.S9S_MB_2U(SCH_1):JTAG_RISER2_TMS
  A25  JTAG_RISER2_TDO    A25  @S9S_MB_2U_LIB.S9S_MB_2U(SCH_1):JTAG_RISER2_TDO
  A24  JTAG_RISER2_TDI    A24  @S9S_MB_2U_LIB.S9S_MB_2U(SCH_1):JTAG_RISER2_TDI
  A23  JTAG_RISER2_TCK    A23  @S9S_MB_2U_LIB.S9S_MB_2U(SCH_1):JTAG_RISER2_TCK
  B30  IRQ_LVC3_WAKE_R2_N    B30  @S9S_MB_2U_LIB.S9S_MB_2U(SCH_1):IRQ_LVC3_WAKE_R2_N
  B84  GND              B84  @S9S_MB_2U_LIB.S9S_MB_2U(SCH_1):GND
  B81  GND              B81  @S9S_MB_2U_LIB.S9S_MB_2U(SCH_1):GND
  B78  GND              B78  @S9S_MB_2U_LIB.S9S_MB_2U(SCH_1):GND
  B75  GND              B75  @S9S_MB_2U_LIB.S9S_MB_2U(SCH_1):GND
  B72  GND              B72  @S9S_MB_2U_LIB.S9S_MB_2U(SCH_1):GND
  B69  GND              B69  @S9S_MB_2U_LIB.S9S_MB_2U(SCH_1):GND
  B66  GND              B66  @S9S_MB_2U_LIB.S9S_MB_2U(SCH_1):GND
  B63  GND              B63  @S9S_MB_2U_LIB.S9S_MB_2U(SCH_1):GND
  B60  GND              B60  @S9S_MB_2U_LIB.S9S_MB_2U(SCH_1):GND
  B57  GND              B57  @S9S_MB_2U_LIB.S9S_MB_2U(SCH_1):GND
  B56  GND              B56  @S9S_MB_2U_LIB.S9S_MB_2U(SCH_1):GND
  B53  GND              B53  @S9S_MB_2U_LIB.S9S_MB_2U(SCH_1):GND
  B50  GND              B50  @S9S_MB_2U_LIB.S9S_MB_2U(SCH_1):GND
  B47  GND              B47  @S9S_MB_2U_LIB.S9S_MB_2U(SCH_1):GND
  B44  GND              B44  @S9S_MB_2U_LIB.S9S_MB_2U(SCH_1):GND
  B41  GND              B41  @S9S_MB_2U_LIB.S9S_MB_2U(SCH_1):GND
  B38  GND              B38  @S9S_MB_2U_LIB.S9S_MB_2U(SCH_1):GND
  B35  GND              B35  @S9S_MB_2U_LIB.S9S_MB_2U(SCH_1):GND
  B32  GND              B32  @S9S_MB_2U_LIB.S9S_MB_2U(SCH_1):GND
  B29  GND              B29  @S9S_MB_2U_LIB.S9S_MB_2U(SCH_1):GND
  B26  GND              B26  @S9S_MB_2U_LIB.S9S_MB_2U(SCH_1):GND
  B23  GND              B23  @S9S_MB_2U_LIB.S9S_MB_2U(SCH_1):GND
  B19  GND              B19  @S9S_MB_2U_LIB.S9S_MB_2U(SCH_1):GND
  B12  GND              B12  @S9S_MB_2U_LIB.S9S_MB_2U(SCH_1):GND
  B11  GND              B11  @S9S_MB_2U_LIB.S9S_MB_2U(SCH_1):GND
  B10  GND              B10  @S9S_MB_2U_LIB.S9S_MB_2U(SCH_1):GND
   B9  GND               B9  @S9S_MB_2U_LIB.S9S_MB_2U(SCH_1):GND
   B8  GND               B8  @S9S_MB_2U_LIB.S9S_MB_2U(SCH_1):GND
  A84  GND              A84  @S9S_MB_2U_LIB.S9S_MB_2U(SCH_1):GND
  A81  GND              A81  @S9S_MB_2U_LIB.S9S_MB_2U(SCH_1):GND
  A78  GND              A78  @S9S_MB_2U_LIB.S9S_MB_2U(SCH_1):GND
  A75  GND              A75  @S9S_MB_2U_LIB.S9S_MB_2U(SCH_1):GND
  A72  GND              A72  @S9S_MB_2U_LIB.S9S_MB_2U(SCH_1):GND
  A69  GND              A69  @S9S_MB_2U_LIB.S9S_MB_2U(SCH_1):GND
  A66  GND              A66  @S9S_MB_2U_LIB.S9S_MB_2U(SCH_1):GND
  A63  GND              A63  @S9S_MB_2U_LIB.S9S_MB_2U(SCH_1):GND
  A60  GND              A60  @S9S_MB_2U_LIB.S9S_MB_2U(SCH_1):GND
  A57  GND              A57  @S9S_MB_2U_LIB.S9S_MB_2U(SCH_1):GND
  A56  GND              A56  @S9S_MB_2U_LIB.S9S_MB_2U(SCH_1):GND
  A53  GND              A53  @S9S_MB_2U_LIB.S9S_MB_2U(SCH_1):GND
  A50  GND              A50  @S9S_MB_2U_LIB.S9S_MB_2U(SCH_1):GND
  A47  GND              A47  @S9S_MB_2U_LIB.S9S_MB_2U(SCH_1):GND
  A44  GND              A44  @S9S_MB_2U_LIB.S9S_MB_2U(SCH_1):GND
  A41  GND              A41  @S9S_MB_2U_LIB.S9S_MB_2U(SCH_1):GND
  A38  GND              A38  @S9S_MB_2U_LIB.S9S_MB_2U(SCH_1):GND
  A35  GND              A35  @S9S_MB_2U_LIB.S9S_MB_2U(SCH_1):GND
  A32  GND              A32  @S9S_MB_2U_LIB.S9S_MB_2U(SCH_1):GND
  A29  GND              A29  @S9S_MB_2U_LIB.S9S_MB_2U(SCH_1):GND
  A28  GND              A28  @S9S_MB_2U_LIB.S9S_MB_2U(SCH_1):GND
  A19  GND              A19  @S9S_MB_2U_LIB.S9S_MB_2U(SCH_1):GND
  A18  GND              A18  @S9S_MB_2U_LIB.S9S_MB_2U(SCH_1):GND
  A17  GND              A17  @S9S_MB_2U_LIB.S9S_MB_2U(SCH_1):GND
  A16  GND              A16  @S9S_MB_2U_LIB.S9S_MB_2U(SCH_1):GND
  A15  GND              A15  @S9S_MB_2U_LIB.S9S_MB_2U(SCH_1):GND
  A14  GND              A14  @S9S_MB_2U_LIB.S9S_MB_2U(SCH_1):GND
  A13  GND              A13  @S9S_MB_2U_LIB.S9S_MB_2U(SCH_1):GND
  A12  GND              A12  @S9S_MB_2U_LIB.S9S_MB_2U(SCH_1):GND
  A11  GND              A11  @S9S_MB_2U_LIB.S9S_MB_2U(SCH_1):GND
  A10  GND              A10  @S9S_MB_2U_LIB.S9S_MB_2U(SCH_1):GND
   A9  GND               A9  @S9S_MB_2U_LIB.S9S_MB_2U(SCH_1):GND
   A8  GND               A8  @S9S_MB_2U_LIB.S9S_MB_2U(SCH_1):GND
  B28  FM_RISER2_PWRBRK_N    B28  @S9S_MB_2U_LIB.S9S_MB_2U(SCH_1):FM_RISER2_PWRBRK_N
  A22  FM_RISER2_JTAG_SEL_N    A22  @S9S_MB_2U_LIB.S9S_MB_2U(SCH_1):FM_RISER2_JTAG_SEL_N
  B34  CLK_100M_PE_3_DP    B34  @S9S_MB_2U_LIB.S9S_MB_2U(SCH_1):CLK_100M_PE_3_DP
  B33  CLK_100M_PE_3_DN    B33  @S9S_MB_2U_LIB.S9S_MB_2U(SCH_1):CLK_100M_PE_3_DN
  A34  CLK_100M_PE_2_DP    A34  @S9S_MB_2U_LIB.S9S_MB_2U(SCH_1):CLK_100M_PE_2_DP
  A33  CLK_100M_PE_2_DN    A33  @S9S_MB_2U_LIB.S9S_MB_2U(SCH_1):CLK_100M_PE_2_DN

CONN56_ME2005602311011  I105  J90    [CONN56_ME2005602311011-CONN56_A]
   B8  NC               RFU  NC
   B7  NC               MFG  NC
  A15  NC             REFCLKP1  NC
  A14  NC             REFCLKN1  NC
   A8  SMB_E1S_0_3V3AUX_SDA  SMBDAT  @S9S_MB_2U_LIB.S9S_MB_2U(SCH_1):SMB_E1S_0_3V3AUX_SDA
   A7  SMB_E1S_0_3V3AUX_SCL  SMBCLK  @S9S_MB_2U_LIB.S9S_MB_2U(SCH_1):SMB_E1S_0_3V3AUX_SCL
   A9  RST_SMB_E1S_0_N  SMBRST#  @S9S_MB_2U_LIB.S9S_MB_2U(SCH_1):RST_SMB_E1S_0_N
  B10  RST_PCIE_E1S_0_PERST_N  PERST0#  @S9S_MB_2U_LIB.S9S_MB_2U(SCH_1):RST_PCIE_E1S_0_PERST_N
  B12  NC             PWRDIS  NC
  B27  P5E_CPU0_PE0_TX_C_DP<3>  PETP3  @S9S_MB_2U_LIB.S9S_MB_2U(SCH_1):P5E_CPU0_PE0_TX_C_DP<3>
  B24  P5E_CPU0_PE0_TX_C_DP<2>  PETP2  @S9S_MB_2U_LIB.S9S_MB_2U(SCH_1):P5E_CPU0_PE0_TX_C_DP<2>
  B21  P5E_CPU0_PE0_TX_C_DP<1>  PETP1  @S9S_MB_2U_LIB.S9S_MB_2U(SCH_1):P5E_CPU0_PE0_TX_C_DP<1>
  B18  P5E_CPU0_PE0_TX_C_DP<0>  PETP0  @S9S_MB_2U_LIB.S9S_MB_2U(SCH_1):P5E_CPU0_PE0_TX_C_DP<0>
  B26  P5E_CPU0_PE0_TX_C_DN<3>  PETN3  @S9S_MB_2U_LIB.S9S_MB_2U(SCH_1):P5E_CPU0_PE0_TX_C_DN<3>
  B23  P5E_CPU0_PE0_TX_C_DN<2>  PETN2  @S9S_MB_2U_LIB.S9S_MB_2U(SCH_1):P5E_CPU0_PE0_TX_C_DN<2>
  B20  P5E_CPU0_PE0_TX_C_DN<1>  PETN1  @S9S_MB_2U_LIB.S9S_MB_2U(SCH_1):P5E_CPU0_PE0_TX_C_DN<1>
  B17  P5E_CPU0_PE0_TX_C_DN<0>  PETN0  @S9S_MB_2U_LIB.S9S_MB_2U(SCH_1):P5E_CPU0_PE0_TX_C_DN<0>
  A27  P5E_CPU0_PE0_RX_DP<3>  PERP3  @S9S_MB_2U_LIB.S9S_MB_2U(SCH_1):P5E_CPU0_PE0_RX_DP<3>
  A24  P5E_CPU0_PE0_RX_DP<2>  PERP2  @S9S_MB_2U_LIB.S9S_MB_2U(SCH_1):P5E_CPU0_PE0_RX_DP<2>
  A21  P5E_CPU0_PE0_RX_DP<1>  PERP1  @S9S_MB_2U_LIB.S9S_MB_2U(SCH_1):P5E_CPU0_PE0_RX_DP<1>
  A18  P5E_CPU0_PE0_RX_DP<0>  PERP0  @S9S_MB_2U_LIB.S9S_MB_2U(SCH_1):P5E_CPU0_PE0_RX_DP<0>
  A26  P5E_CPU0_PE0_RX_DN<3>  PERN3  @S9S_MB_2U_LIB.S9S_MB_2U(SCH_1):P5E_CPU0_PE0_RX_DN<3>
  A23  P5E_CPU0_PE0_RX_DN<2>  PERN2  @S9S_MB_2U_LIB.S9S_MB_2U(SCH_1):P5E_CPU0_PE0_RX_DN<2>
  A20  P5E_CPU0_PE0_RX_DN<1>  PERN1  @S9S_MB_2U_LIB.S9S_MB_2U(SCH_1):P5E_CPU0_PE0_RX_DN<1>
  A17  P5E_CPU0_PE0_RX_DN<0>  PERN0  @S9S_MB_2U_LIB.S9S_MB_2U(SCH_1):P5E_CPU0_PE0_RX_DN<0>
  B11  P3V3_E1S_0     3.3VAUX  @S9S_MB_2U_LIB.S9S_MB_2U(SCH_1):P3V3_E1S_0
   B6  P12V_E1S_0     12V_B6  @S9S_MB_2U_LIB.S9S_MB_2U(SCH_1):P12V_E1S_0
   B5  P12V_E1S_0     12V_B5  @S9S_MB_2U_LIB.S9S_MB_2U(SCH_1):P12V_E1S_0
   B4  P12V_E1S_0     12V_B4  @S9S_MB_2U_LIB.S9S_MB_2U(SCH_1):P12V_E1S_0
   B3  P12V_E1S_0     12V_B3  @S9S_MB_2U_LIB.S9S_MB_2U(SCH_1):P12V_E1S_0
   B2  P12V_E1S_0     12V_B2  @S9S_MB_2U_LIB.S9S_MB_2U(SCH_1):P12V_E1S_0
   B1  P12V_E1S_0     12V_B1  @S9S_MB_2U_LIB.S9S_MB_2U(SCH_1):P12V_E1S_0
   B9  NC             DUALPORTEN#  NC
  B28  GND            GND_B28  @S9S_MB_2U_LIB.S9S_MB_2U(SCH_1):GND
  B25  GND            GND_B25  @S9S_MB_2U_LIB.S9S_MB_2U(SCH_1):GND
  B22  GND            GND_B22  @S9S_MB_2U_LIB.S9S_MB_2U(SCH_1):GND
  B19  GND            GND_B19  @S9S_MB_2U_LIB.S9S_MB_2U(SCH_1):GND
  B16  GND            GND_B16  @S9S_MB_2U_LIB.S9S_MB_2U(SCH_1):GND
  B13  GND            GND_B13  @S9S_MB_2U_LIB.S9S_MB_2U(SCH_1):GND
  A28  GND            GND_A28  @S9S_MB_2U_LIB.S9S_MB_2U(SCH_1):GND
  A25  GND            GND_A25  @S9S_MB_2U_LIB.S9S_MB_2U(SCH_1):GND
  A22  GND            GND_A22  @S9S_MB_2U_LIB.S9S_MB_2U(SCH_1):GND
  A19  GND            GND_A19  @S9S_MB_2U_LIB.S9S_MB_2U(SCH_1):GND
  A16  GND            GND_A16  @S9S_MB_2U_LIB.S9S_MB_2U(SCH_1):GND
  A13  GND            GND_A13  @S9S_MB_2U_LIB.S9S_MB_2U(SCH_1):GND
   A6  GND            GND_A6  @S9S_MB_2U_LIB.S9S_MB_2U(SCH_1):GND
   A5  GND            GND_A5  @S9S_MB_2U_LIB.S9S_MB_2U(SCH_1):GND
   A4  GND            GND_A4  @S9S_MB_2U_LIB.S9S_MB_2U(SCH_1):GND
   A3  GND            GND_A3  @S9S_MB_2U_LIB.S9S_MB_2U(SCH_1):GND
   A2  GND            GND_A2  @S9S_MB_2U_LIB.S9S_MB_2U(SCH_1):GND
   A1  GND            GND_A1  @S9S_MB_2U_LIB.S9S_MB_2U(SCH_1):GND
  A12  E1S_0_PRSNT_N  PRSNT0#  @S9S_MB_2U_LIB.S9S_MB_2U(SCH_1):E1S_0_PRSNT_N
  A11  NC             PERST1#||CLKREQ#  NC
  A10  E1S_0_LED_ACT_N  LED#||ACTIVITY  @S9S_MB_2U_LIB.S9S_MB_2U(SCH_1):E1S_0_LED_ACT_N
  B15  CLK_100M_E1S_0_DP  REFCLKP0  @S9S_MB_2U_LIB.S9S_MB_2U(SCH_1):CLK_100M_E1S_0_DP
  B14  CLK_100M_E1S_0_DN  REFCLKN0  @S9S_MB_2U_LIB.S9S_MB_2U(SCH_1):CLK_100M_E1S_0_DN

TP  I28  J90_S1  [TP_TP-NA,TP30]
    1  NC                TP  NC

TP  I29  J90_S2  [TP_TP-NA,TP30]
    1  NC                TP  NC

CONN56_ME2005602311011  I123  J91    [CONN56_ME2005602311011-CONN56_A]
   B8  NC               RFU  NC
   B7  NC               MFG  NC
  A15  NC             REFCLKP1  NC
  A14  NC             REFCLKN1  NC
   A8  SMB_E1S_1_3V3AUX_SDA  SMBDAT  @S9S_MB_2U_LIB.S9S_MB_2U(SCH_1):SMB_E1S_1_3V3AUX_SDA
   A7  SMB_E1S_1_3V3AUX_SCL  SMBCLK  @S9S_MB_2U_LIB.S9S_MB_2U(SCH_1):SMB_E1S_1_3V3AUX_SCL
   A9  RST_SMB_E1S_1_N  SMBRST#  @S9S_MB_2U_LIB.S9S_MB_2U(SCH_1):RST_SMB_E1S_1_N
  B10  RST_PCIE_E1S_1_PERST_N  PERST0#  @S9S_MB_2U_LIB.S9S_MB_2U(SCH_1):RST_PCIE_E1S_1_PERST_N
  B12  NC             PWRDIS  NC
  B27  P5E_CPU0_PE0_TX_C_DP<7>  PETP3  @S9S_MB_2U_LIB.S9S_MB_2U(SCH_1):P5E_CPU0_PE0_TX_C_DP<7>
  B24  P5E_CPU0_PE0_TX_C_DP<6>  PETP2  @S9S_MB_2U_LIB.S9S_MB_2U(SCH_1):P5E_CPU0_PE0_TX_C_DP<6>
  B21  P5E_CPU0_PE0_TX_C_DP<5>  PETP1  @S9S_MB_2U_LIB.S9S_MB_2U(SCH_1):P5E_CPU0_PE0_TX_C_DP<5>
  B18  P5E_CPU0_PE0_TX_C_DP<4>  PETP0  @S9S_MB_2U_LIB.S9S_MB_2U(SCH_1):P5E_CPU0_PE0_TX_C_DP<4>
  B26  P5E_CPU0_PE0_TX_C_DN<7>  PETN3  @S9S_MB_2U_LIB.S9S_MB_2U(SCH_1):P5E_CPU0_PE0_TX_C_DN<7>
  B23  P5E_CPU0_PE0_TX_C_DN<6>  PETN2  @S9S_MB_2U_LIB.S9S_MB_2U(SCH_1):P5E_CPU0_PE0_TX_C_DN<6>
  B20  P5E_CPU0_PE0_TX_C_DN<5>  PETN1  @S9S_MB_2U_LIB.S9S_MB_2U(SCH_1):P5E_CPU0_PE0_TX_C_DN<5>
  B17  P5E_CPU0_PE0_TX_C_DN<4>  PETN0  @S9S_MB_2U_LIB.S9S_MB_2U(SCH_1):P5E_CPU0_PE0_TX_C_DN<4>
  A27  P5E_CPU0_PE0_RX_DP<7>  PERP3  @S9S_MB_2U_LIB.S9S_MB_2U(SCH_1):P5E_CPU0_PE0_RX_DP<7>
  A24  P5E_CPU0_PE0_RX_DP<6>  PERP2  @S9S_MB_2U_LIB.S9S_MB_2U(SCH_1):P5E_CPU0_PE0_RX_DP<6>
  A21  P5E_CPU0_PE0_RX_DP<5>  PERP1  @S9S_MB_2U_LIB.S9S_MB_2U(SCH_1):P5E_CPU0_PE0_RX_DP<5>
  A18  P5E_CPU0_PE0_RX_DP<4>  PERP0  @S9S_MB_2U_LIB.S9S_MB_2U(SCH_1):P5E_CPU0_PE0_RX_DP<4>
  A26  P5E_CPU0_PE0_RX_DN<7>  PERN3  @S9S_MB_2U_LIB.S9S_MB_2U(SCH_1):P5E_CPU0_PE0_RX_DN<7>
  A23  P5E_CPU0_PE0_RX_DN<6>  PERN2  @S9S_MB_2U_LIB.S9S_MB_2U(SCH_1):P5E_CPU0_PE0_RX_DN<6>
  A20  P5E_CPU0_PE0_RX_DN<5>  PERN1  @S9S_MB_2U_LIB.S9S_MB_2U(SCH_1):P5E_CPU0_PE0_RX_DN<5>
  A17  P5E_CPU0_PE0_RX_DN<4>  PERN0  @S9S_MB_2U_LIB.S9S_MB_2U(SCH_1):P5E_CPU0_PE0_RX_DN<4>
  B11  P3V3_E1S_1     3.3VAUX  @S9S_MB_2U_LIB.S9S_MB_2U(SCH_1):P3V3_E1S_1
   B6  P12V_E1S_1     12V_B6  @S9S_MB_2U_LIB.S9S_MB_2U(SCH_1):P12V_E1S_1
   B5  P12V_E1S_1     12V_B5  @S9S_MB_2U_LIB.S9S_MB_2U(SCH_1):P12V_E1S_1
   B4  P12V_E1S_1     12V_B4  @S9S_MB_2U_LIB.S9S_MB_2U(SCH_1):P12V_E1S_1
   B3  P12V_E1S_1     12V_B3  @S9S_MB_2U_LIB.S9S_MB_2U(SCH_1):P12V_E1S_1
   B2  P12V_E1S_1     12V_B2  @S9S_MB_2U_LIB.S9S_MB_2U(SCH_1):P12V_E1S_1
   B1  P12V_E1S_1     12V_B1  @S9S_MB_2U_LIB.S9S_MB_2U(SCH_1):P12V_E1S_1
   B9  NC             DUALPORTEN#  NC
  B28  GND            GND_B28  @S9S_MB_2U_LIB.S9S_MB_2U(SCH_1):GND
  B25  GND            GND_B25  @S9S_MB_2U_LIB.S9S_MB_2U(SCH_1):GND
  B22  GND            GND_B22  @S9S_MB_2U_LIB.S9S_MB_2U(SCH_1):GND
  B19  GND            GND_B19  @S9S_MB_2U_LIB.S9S_MB_2U(SCH_1):GND
  B16  GND            GND_B16  @S9S_MB_2U_LIB.S9S_MB_2U(SCH_1):GND
  B13  GND            GND_B13  @S9S_MB_2U_LIB.S9S_MB_2U(SCH_1):GND
  A28  GND            GND_A28  @S9S_MB_2U_LIB.S9S_MB_2U(SCH_1):GND
  A25  GND            GND_A25  @S9S_MB_2U_LIB.S9S_MB_2U(SCH_1):GND
  A22  GND            GND_A22  @S9S_MB_2U_LIB.S9S_MB_2U(SCH_1):GND
  A19  GND            GND_A19  @S9S_MB_2U_LIB.S9S_MB_2U(SCH_1):GND
  A16  GND            GND_A16  @S9S_MB_2U_LIB.S9S_MB_2U(SCH_1):GND
  A13  GND            GND_A13  @S9S_MB_2U_LIB.S9S_MB_2U(SCH_1):GND
   A6  GND            GND_A6  @S9S_MB_2U_LIB.S9S_MB_2U(SCH_1):GND
   A5  GND            GND_A5  @S9S_MB_2U_LIB.S9S_MB_2U(SCH_1):GND
   A4  GND            GND_A4  @S9S_MB_2U_LIB.S9S_MB_2U(SCH_1):GND
   A3  GND            GND_A3  @S9S_MB_2U_LIB.S9S_MB_2U(SCH_1):GND
   A2  GND            GND_A2  @S9S_MB_2U_LIB.S9S_MB_2U(SCH_1):GND
   A1  GND            GND_A1  @S9S_MB_2U_LIB.S9S_MB_2U(SCH_1):GND
  A12  E1S_1_PRSNT_N  PRSNT0#  @S9S_MB_2U_LIB.S9S_MB_2U(SCH_1):E1S_1_PRSNT_N
  A11  NC             PERST1#||CLKREQ#  NC
  A10  E1S_1_LED_ACT_N  LED#||ACTIVITY  @S9S_MB_2U_LIB.S9S_MB_2U(SCH_1):E1S_1_LED_ACT_N
  B15  CLK_100M_E1S_1_DP  REFCLKP0  @S9S_MB_2U_LIB.S9S_MB_2U(SCH_1):CLK_100M_E1S_1_DP
  B14  CLK_100M_E1S_1_DN  REFCLKN0  @S9S_MB_2U_LIB.S9S_MB_2U(SCH_1):CLK_100M_E1S_1_DN

TP  I30  J91_S1  [TP_TP-NA,TP30]
    1  NC                TP  NC

TP  I31  J91_S2  [TP_TP-NA,TP30]
    1  NC                TP  NC

CONN56_ME2005602311011  I105  J92    [CONN56_ME2005602311011-CONN56_A]
   B8  NC               RFU  NC
   B7  NC               MFG  NC
  A15  NC             REFCLKP1  NC
  A14  NC             REFCLKN1  NC
   A8  SMB_E1S_2_3V3AUX_SDA  SMBDAT  @S9S_MB_2U_LIB.S9S_MB_2U(SCH_1):SMB_E1S_2_3V3AUX_SDA
   A7  SMB_E1S_2_3V3AUX_SCL  SMBCLK  @S9S_MB_2U_LIB.S9S_MB_2U(SCH_1):SMB_E1S_2_3V3AUX_SCL
   A9  RST_SMB_E1S_2_N  SMBRST#  @S9S_MB_2U_LIB.S9S_MB_2U(SCH_1):RST_SMB_E1S_2_N
  B10  RST_PCIE_E1S_2_PERST_N  PERST0#  @S9S_MB_2U_LIB.S9S_MB_2U(SCH_1):RST_PCIE_E1S_2_PERST_N
  B12  NC             PWRDIS  NC
  B21  P5E_CPU0_PE0_TX_C_DP<9>  PETP1  @S9S_MB_2U_LIB.S9S_MB_2U(SCH_1):P5E_CPU0_PE0_TX_C_DP<9>
  B18  P5E_CPU0_PE0_TX_C_DP<8>  PETP0  @S9S_MB_2U_LIB.S9S_MB_2U(SCH_1):P5E_CPU0_PE0_TX_C_DP<8>
  B27  P5E_CPU0_PE0_TX_C_DP<11>  PETP3  @S9S_MB_2U_LIB.S9S_MB_2U(SCH_1):P5E_CPU0_PE0_TX_C_DP<11>
  B24  P5E_CPU0_PE0_TX_C_DP<10>  PETP2  @S9S_MB_2U_LIB.S9S_MB_2U(SCH_1):P5E_CPU0_PE0_TX_C_DP<10>
  B20  P5E_CPU0_PE0_TX_C_DN<9>  PETN1  @S9S_MB_2U_LIB.S9S_MB_2U(SCH_1):P5E_CPU0_PE0_TX_C_DN<9>
  B17  P5E_CPU0_PE0_TX_C_DN<8>  PETN0  @S9S_MB_2U_LIB.S9S_MB_2U(SCH_1):P5E_CPU0_PE0_TX_C_DN<8>
  B26  P5E_CPU0_PE0_TX_C_DN<11>  PETN3  @S9S_MB_2U_LIB.S9S_MB_2U(SCH_1):P5E_CPU0_PE0_TX_C_DN<11>
  B23  P5E_CPU0_PE0_TX_C_DN<10>  PETN2  @S9S_MB_2U_LIB.S9S_MB_2U(SCH_1):P5E_CPU0_PE0_TX_C_DN<10>
  A21  P5E_CPU0_PE0_RX_DP<9>  PERP1  @S9S_MB_2U_LIB.S9S_MB_2U(SCH_1):P5E_CPU0_PE0_RX_DP<9>
  A18  P5E_CPU0_PE0_RX_DP<8>  PERP0  @S9S_MB_2U_LIB.S9S_MB_2U(SCH_1):P5E_CPU0_PE0_RX_DP<8>
  A27  P5E_CPU0_PE0_RX_DP<11>  PERP3  @S9S_MB_2U_LIB.S9S_MB_2U(SCH_1):P5E_CPU0_PE0_RX_DP<11>
  A24  P5E_CPU0_PE0_RX_DP<10>  PERP2  @S9S_MB_2U_LIB.S9S_MB_2U(SCH_1):P5E_CPU0_PE0_RX_DP<10>
  A20  P5E_CPU0_PE0_RX_DN<9>  PERN1  @S9S_MB_2U_LIB.S9S_MB_2U(SCH_1):P5E_CPU0_PE0_RX_DN<9>
  A17  P5E_CPU0_PE0_RX_DN<8>  PERN0  @S9S_MB_2U_LIB.S9S_MB_2U(SCH_1):P5E_CPU0_PE0_RX_DN<8>
  A26  P5E_CPU0_PE0_RX_DN<11>  PERN3  @S9S_MB_2U_LIB.S9S_MB_2U(SCH_1):P5E_CPU0_PE0_RX_DN<11>
  A23  P5E_CPU0_PE0_RX_DN<10>  PERN2  @S9S_MB_2U_LIB.S9S_MB_2U(SCH_1):P5E_CPU0_PE0_RX_DN<10>
  B11  P3V3_E1S_2     3.3VAUX  @S9S_MB_2U_LIB.S9S_MB_2U(SCH_1):P3V3_E1S_2
   B6  P12V_E1S_2     12V_B6  @S9S_MB_2U_LIB.S9S_MB_2U(SCH_1):P12V_E1S_2
   B5  P12V_E1S_2     12V_B5  @S9S_MB_2U_LIB.S9S_MB_2U(SCH_1):P12V_E1S_2
   B4  P12V_E1S_2     12V_B4  @S9S_MB_2U_LIB.S9S_MB_2U(SCH_1):P12V_E1S_2
   B3  P12V_E1S_2     12V_B3  @S9S_MB_2U_LIB.S9S_MB_2U(SCH_1):P12V_E1S_2
   B2  P12V_E1S_2     12V_B2  @S9S_MB_2U_LIB.S9S_MB_2U(SCH_1):P12V_E1S_2
   B1  P12V_E1S_2     12V_B1  @S9S_MB_2U_LIB.S9S_MB_2U(SCH_1):P12V_E1S_2
   B9  NC             DUALPORTEN#  NC
  B28  GND            GND_B28  @S9S_MB_2U_LIB.S9S_MB_2U(SCH_1):GND
  B25  GND            GND_B25  @S9S_MB_2U_LIB.S9S_MB_2U(SCH_1):GND
  B22  GND            GND_B22  @S9S_MB_2U_LIB.S9S_MB_2U(SCH_1):GND
  B19  GND            GND_B19  @S9S_MB_2U_LIB.S9S_MB_2U(SCH_1):GND
  B16  GND            GND_B16  @S9S_MB_2U_LIB.S9S_MB_2U(SCH_1):GND
  B13  GND            GND_B13  @S9S_MB_2U_LIB.S9S_MB_2U(SCH_1):GND
  A28  GND            GND_A28  @S9S_MB_2U_LIB.S9S_MB_2U(SCH_1):GND
  A25  GND            GND_A25  @S9S_MB_2U_LIB.S9S_MB_2U(SCH_1):GND
  A22  GND            GND_A22  @S9S_MB_2U_LIB.S9S_MB_2U(SCH_1):GND
  A19  GND            GND_A19  @S9S_MB_2U_LIB.S9S_MB_2U(SCH_1):GND
  A16  GND            GND_A16  @S9S_MB_2U_LIB.S9S_MB_2U(SCH_1):GND
  A13  GND            GND_A13  @S9S_MB_2U_LIB.S9S_MB_2U(SCH_1):GND
   A6  GND            GND_A6  @S9S_MB_2U_LIB.S9S_MB_2U(SCH_1):GND
   A5  GND            GND_A5  @S9S_MB_2U_LIB.S9S_MB_2U(SCH_1):GND
   A4  GND            GND_A4  @S9S_MB_2U_LIB.S9S_MB_2U(SCH_1):GND
   A3  GND            GND_A3  @S9S_MB_2U_LIB.S9S_MB_2U(SCH_1):GND
   A2  GND            GND_A2  @S9S_MB_2U_LIB.S9S_MB_2U(SCH_1):GND
   A1  GND            GND_A1  @S9S_MB_2U_LIB.S9S_MB_2U(SCH_1):GND
  A12  E1S_2_PRSNT_N  PRSNT0#  @S9S_MB_2U_LIB.S9S_MB_2U(SCH_1):E1S_2_PRSNT_N
  A11  NC             PERST1#||CLKREQ#  NC
  A10  E1S_2_LED_ACT_N  LED#||ACTIVITY  @S9S_MB_2U_LIB.S9S_MB_2U(SCH_1):E1S_2_LED_ACT_N
  B15  CLK_100M_E1S_2_DP  REFCLKP0  @S9S_MB_2U_LIB.S9S_MB_2U(SCH_1):CLK_100M_E1S_2_DP
  B14  CLK_100M_E1S_2_DN  REFCLKN0  @S9S_MB_2U_LIB.S9S_MB_2U(SCH_1):CLK_100M_E1S_2_DN

TP  I32  J92_S1  [TP_TP-NA,TP30]
    1  NC                TP  NC

TP  I34  J92_S2  [TP_TP-NA,TP30]
    1  NC                TP  NC

CONN56_ME2005602311011  I123  J93    [CONN56_ME2005602311011-CONN56_A]
   B8  NC               RFU  NC
   B7  NC               MFG  NC
  A15  NC             REFCLKP1  NC
  A14  NC             REFCLKN1  NC
   A8  SMB_E1S_3_3V3AUX_SDA  SMBDAT  @S9S_MB_2U_LIB.S9S_MB_2U(SCH_1):SMB_E1S_3_3V3AUX_SDA
   A7  SMB_E1S_3_3V3AUX_SCL  SMBCLK  @S9S_MB_2U_LIB.S9S_MB_2U(SCH_1):SMB_E1S_3_3V3AUX_SCL
   A9  RST_SMB_E1S_3_N  SMBRST#  @S9S_MB_2U_LIB.S9S_MB_2U(SCH_1):RST_SMB_E1S_3_N
  B10  RST_PCIE_E1S_3_PERST_N  PERST0#  @S9S_MB_2U_LIB.S9S_MB_2U(SCH_1):RST_PCIE_E1S_3_PERST_N
  B12  NC             PWRDIS  NC
  B27  P5E_CPU0_PE0_TX_C_DP<15>  PETP3  @S9S_MB_2U_LIB.S9S_MB_2U(SCH_1):P5E_CPU0_PE0_TX_C_DP<15>
  B24  P5E_CPU0_PE0_TX_C_DP<14>  PETP2  @S9S_MB_2U_LIB.S9S_MB_2U(SCH_1):P5E_CPU0_PE0_TX_C_DP<14>
  B21  P5E_CPU0_PE0_TX_C_DP<13>  PETP1  @S9S_MB_2U_LIB.S9S_MB_2U(SCH_1):P5E_CPU0_PE0_TX_C_DP<13>
  B18  P5E_CPU0_PE0_TX_C_DP<12>  PETP0  @S9S_MB_2U_LIB.S9S_MB_2U(SCH_1):P5E_CPU0_PE0_TX_C_DP<12>
  B26  P5E_CPU0_PE0_TX_C_DN<15>  PETN3  @S9S_MB_2U_LIB.S9S_MB_2U(SCH_1):P5E_CPU0_PE0_TX_C_DN<15>
  B23  P5E_CPU0_PE0_TX_C_DN<14>  PETN2  @S9S_MB_2U_LIB.S9S_MB_2U(SCH_1):P5E_CPU0_PE0_TX_C_DN<14>
  B20  P5E_CPU0_PE0_TX_C_DN<13>  PETN1  @S9S_MB_2U_LIB.S9S_MB_2U(SCH_1):P5E_CPU0_PE0_TX_C_DN<13>
  B17  P5E_CPU0_PE0_TX_C_DN<12>  PETN0  @S9S_MB_2U_LIB.S9S_MB_2U(SCH_1):P5E_CPU0_PE0_TX_C_DN<12>
  A27  P5E_CPU0_PE0_RX_DP<15>  PERP3  @S9S_MB_2U_LIB.S9S_MB_2U(SCH_1):P5E_CPU0_PE0_RX_DP<15>
  A24  P5E_CPU0_PE0_RX_DP<14>  PERP2  @S9S_MB_2U_LIB.S9S_MB_2U(SCH_1):P5E_CPU0_PE0_RX_DP<14>
  A21  P5E_CPU0_PE0_RX_DP<13>  PERP1  @S9S_MB_2U_LIB.S9S_MB_2U(SCH_1):P5E_CPU0_PE0_RX_DP<13>
  A18  P5E_CPU0_PE0_RX_DP<12>  PERP0  @S9S_MB_2U_LIB.S9S_MB_2U(SCH_1):P5E_CPU0_PE0_RX_DP<12>
  A26  P5E_CPU0_PE0_RX_DN<15>  PERN3  @S9S_MB_2U_LIB.S9S_MB_2U(SCH_1):P5E_CPU0_PE0_RX_DN<15>
  A23  P5E_CPU0_PE0_RX_DN<14>  PERN2  @S9S_MB_2U_LIB.S9S_MB_2U(SCH_1):P5E_CPU0_PE0_RX_DN<14>
  A20  P5E_CPU0_PE0_RX_DN<13>  PERN1  @S9S_MB_2U_LIB.S9S_MB_2U(SCH_1):P5E_CPU0_PE0_RX_DN<13>
  A17  P5E_CPU0_PE0_RX_DN<12>  PERN0  @S9S_MB_2U_LIB.S9S_MB_2U(SCH_1):P5E_CPU0_PE0_RX_DN<12>
  B11  P3V3_E1S_3     3.3VAUX  @S9S_MB_2U_LIB.S9S_MB_2U(SCH_1):P3V3_E1S_3
   B6  P12V_E1S_3     12V_B6  @S9S_MB_2U_LIB.S9S_MB_2U(SCH_1):P12V_E1S_3
   B5  P12V_E1S_3     12V_B5  @S9S_MB_2U_LIB.S9S_MB_2U(SCH_1):P12V_E1S_3
   B4  P12V_E1S_3     12V_B4  @S9S_MB_2U_LIB.S9S_MB_2U(SCH_1):P12V_E1S_3
   B3  P12V_E1S_3     12V_B3  @S9S_MB_2U_LIB.S9S_MB_2U(SCH_1):P12V_E1S_3
   B2  P12V_E1S_3     12V_B2  @S9S_MB_2U_LIB.S9S_MB_2U(SCH_1):P12V_E1S_3
   B1  P12V_E1S_3     12V_B1  @S9S_MB_2U_LIB.S9S_MB_2U(SCH_1):P12V_E1S_3
   B9  NC             DUALPORTEN#  NC
  B28  GND            GND_B28  @S9S_MB_2U_LIB.S9S_MB_2U(SCH_1):GND
  B25  GND            GND_B25  @S9S_MB_2U_LIB.S9S_MB_2U(SCH_1):GND
  B22  GND            GND_B22  @S9S_MB_2U_LIB.S9S_MB_2U(SCH_1):GND
  B19  GND            GND_B19  @S9S_MB_2U_LIB.S9S_MB_2U(SCH_1):GND
  B16  GND            GND_B16  @S9S_MB_2U_LIB.S9S_MB_2U(SCH_1):GND
  B13  GND            GND_B13  @S9S_MB_2U_LIB.S9S_MB_2U(SCH_1):GND
  A28  GND            GND_A28  @S9S_MB_2U_LIB.S9S_MB_2U(SCH_1):GND
  A25  GND            GND_A25  @S9S_MB_2U_LIB.S9S_MB_2U(SCH_1):GND
  A22  GND            GND_A22  @S9S_MB_2U_LIB.S9S_MB_2U(SCH_1):GND
  A19  GND            GND_A19  @S9S_MB_2U_LIB.S9S_MB_2U(SCH_1):GND
  A16  GND            GND_A16  @S9S_MB_2U_LIB.S9S_MB_2U(SCH_1):GND
  A13  GND            GND_A13  @S9S_MB_2U_LIB.S9S_MB_2U(SCH_1):GND
   A6  GND            GND_A6  @S9S_MB_2U_LIB.S9S_MB_2U(SCH_1):GND
   A5  GND            GND_A5  @S9S_MB_2U_LIB.S9S_MB_2U(SCH_1):GND
   A4  GND            GND_A4  @S9S_MB_2U_LIB.S9S_MB_2U(SCH_1):GND
   A3  GND            GND_A3  @S9S_MB_2U_LIB.S9S_MB_2U(SCH_1):GND
   A2  GND            GND_A2  @S9S_MB_2U_LIB.S9S_MB_2U(SCH_1):GND
   A1  GND            GND_A1  @S9S_MB_2U_LIB.S9S_MB_2U(SCH_1):GND
  A12  E1S_3_PRSNT_N  PRSNT0#  @S9S_MB_2U_LIB.S9S_MB_2U(SCH_1):E1S_3_PRSNT_N
  A11  NC             PERST1#||CLKREQ#  NC
  A10  E1S_3_LED_ACT_N  LED#||ACTIVITY  @S9S_MB_2U_LIB.S9S_MB_2U(SCH_1):E1S_3_LED_ACT_N
  B15  CLK_100M_E1S_3_DP  REFCLKP0  @S9S_MB_2U_LIB.S9S_MB_2U(SCH_1):CLK_100M_E1S_3_DP
  B14  CLK_100M_E1S_3_DN  REFCLKN0  @S9S_MB_2U_LIB.S9S_MB_2U(SCH_1):CLK_100M_E1S_3_DN

TP  I33  J93_S1  [TP_TP-NA,TP30]
    1  NC                TP  NC

TP  I35  J93_S2  [TP_TP-NA,TP30]
    1  NC                TP  NC

CONN3_210HP1030BR1  I123  JP1    [CONN3_210HP1030BR1-CONN3_210-HA]
    2  SMB_VR_3V3AUX_SDA_R      2  @S9S_MB_2U_LIB.S9S_MB_2U(SCH_1):SMB_VR_3V3AUX_SDA_R
    3  SMB_VR_3V3AUX_SCL_R      3  @S9S_MB_2U_LIB.S9S_MB_2U(SCH_1):SMB_VR_3V3AUX_SCL_R
    1  GND                1  @S9S_MB_2U_LIB.S9S_MB_2U(SCH_1):GND

CONN3_HFK1030G000LAF  I58  JP5    [CONN3_HFK1030G000LAF-CONN3_HFKA]
    3  P5V                3  @S9S_MB_2U_LIB.S9S_MB_2U(SCH_1):P5V
    1  P12V_FRONT_CPU      1  @S9S_MB_2U_LIB.S9S_MB_2U(SCH_1):P12V_FRONT_CPU
    2  GND                2  @S9S_MB_2U_LIB.S9S_MB_2U(SCH_1):GND

CONN3_210HP1030BR1  I64  JP7    [CONN3_210HP1030BR1-CONN3_210-HA]
    2  GND                2  @S9S_MB_2U_LIB.S9S_MB_2U(SCH_1):GND
    3  FM_SMB_PEHPCPU1_PCIE_ALERT_N      3  @S9S_MB_2U_LIB.S9S_MB_2U(SCH_1):FM_SMB_PEHPCPU1_PCIE_ALERT_N
    1  FM_SMB_PEHPCPU0_PCIE_ALERT_N      1  @S9S_MB_2U_LIB.S9S_MB_2U(SCH_1):FM_SMB_PEHPCPU0_PCIE_ALERT_N

CONN3_HFK1030G000LAF  I86  JP8    [CONN3_HFK1030G000LAF-CONN3_HFKA]
    3  NC                 3  NC
    1  GND                1  @S9S_MB_2U_LIB.S9S_MB_2U(SCH_1):GND
    2  FM_INTRUDER_HDR_PCH_N      2  @S9S_MB_2U_LIB.S9S_MB_2U(SCH_1):FM_INTRUDER_HDR_PCH_N

Q_INDUCTOR  I20  L1     [Q_INDUCTOR_SMLF-FCM2012KF-601TA]
    2  P3V3_AUX_CLK_GEN_VDD_CK440      2  @S9S_MB_2U_LIB.S9S_MB_2U(SCH_1):P3V3_AUX_CLK_GEN_VDD_CK440
    1  P3V3_AUX           1  @S9S_MB_2U_LIB.S9S_MB_2U(SCH_1):P3V3_AUX

Q_INDUCTOR  I135  L2     [Q_INDUCTOR_SMLF-BLM18PG121SN1DA]
    2  P1V05_PCH_PLL_AUX      2  @S9S_MB_2U_LIB.S9S_MB_2U(SCH_1):P1V05_PCH_PLL_AUX
    1  P1V05_PCH_AUX      1  @S9S_MB_2U_LIB.S9S_MB_2U(SCH_1):P1V05_PCH_AUX

Q_INDUCTOR  I170  L3     [Q_INDUCTOR_SMLF-BLM18SG331TN1DA]
    2  P3V3_DB2000_VDD      2  @S9S_MB_2U_LIB.S9S_MB_2U(SCH_1):P3V3_DB2000_VDD
    1  P3V3               1  @S9S_MB_2U_LIB.S9S_MB_2U(SCH_1):P3V3

Q_INDUCTOR  I177  L4     [Q_INDUCTOR_SMLF-BLM18SG331TN1DA]
    2  P3V3_DB2000_FB_VDD      2  @S9S_MB_2U_LIB.S9S_MB_2U(SCH_1):P3V3_DB2000_FB_VDD
    1  P3V3               1  @S9S_MB_2U_LIB.S9S_MB_2U(SCH_1):P3V3

Q_INDUCTOR4P_12  I22  L5     [Q_INDUCTOR4P_12-67/320MA,320MAA]
    3  USB3_9_TX_DP_FB      3  @S9S_MB_2U_LIB.S9S_MB_2U(SCH_1):USB3_9_TX_DP_FB
    4  USB3_9_TX_DP_C      4  @S9S_MB_2U_LIB.S9S_MB_2U(SCH_1):USB3_9_TX_DP_C
    2  USB3_9_TX_DN_FB      2  @S9S_MB_2U_LIB.S9S_MB_2U(SCH_1):USB3_9_TX_DN_FB
    1  USB3_9_TX_DN_C      1  @S9S_MB_2U_LIB.S9S_MB_2U(SCH_1):USB3_9_TX_DN_C

Q_INDUCTOR4P_12  I18  L6     [Q_INDUCTOR4P_12-67/320MA,320MAA]
    3  USB3_9_RX_DP_FB      3  @S9S_MB_2U_LIB.S9S_MB_2U(SCH_1):USB3_9_RX_DP_FB
    4  USB3_9_RX_DP       4  @S9S_MB_2U_LIB.S9S_MB_2U(SCH_1):USB3_9_RX_DP
    2  USB3_9_RX_DN_FB      2  @S9S_MB_2U_LIB.S9S_MB_2U(SCH_1):USB3_9_RX_DN_FB
    1  USB3_9_RX_DN       1  @S9S_MB_2U_LIB.S9S_MB_2U(SCH_1):USB3_9_RX_DN

Q_INDUCTOR4P_12  I4   L9     [Q_INDUCTOR4P_12-67/320MA,320MAA]
    2  USB2_1_F_DP        2  @S9S_MB_2U_LIB.S9S_MB_2U(SCH_1):USB2_1_F_DP
    3  USB2_1_F_DN        3  @S9S_MB_2U_LIB.S9S_MB_2U(SCH_1):USB2_1_F_DN
    1  USB2_1_DP          1  @S9S_MB_2U_LIB.S9S_MB_2U(SCH_1):USB2_1_DP
    4  USB2_1_DN          4  @S9S_MB_2U_LIB.S9S_MB_2U(SCH_1):USB2_1_DN

Q_INDUCTOR  I145  L10    [Q_INDUCTOR_SMLF-BLM18PG121SN1DA]
    2  P1V8_PCH_PLL_AUX      2  @S9S_MB_2U_LIB.S9S_MB_2U(SCH_1):P1V8_PCH_PLL_AUX
    1  P1V8_PCH_AUX       1  @S9S_MB_2U_LIB.S9S_MB_2U(SCH_1):P1V8_PCH_AUX

Q_INDUCTOR  I56  L11    [Q_INDUCTOR_SMLF-BLM15AG121SN1DA]
    1  IRQ_PSU_ALERT_N      1  @S9S_MB_2U_LIB.S9S_MB_2U(SCH_1):IRQ_PSU_ALERT_N
    2  NC                 2  NC

Q_INDUCTOR  I57  L12    [Q_INDUCTOR_SMLF-BLM15AG121SN1DA]
    1  PSU1_THROTTLE_R      1  @S9S_MB_2U_LIB.S9S_MB_2U(SCH_1):PSU1_THROTTLE_R
    2  FM_PSU_THROTTLE_L      2  @S9S_MB_2U_LIB.S9S_MB_2U(SCH_1):FM_PSU_THROTTLE_L

Q_INDUCTOR  I41  L13    [Q_INDUCTOR_SMLF-FCM2012KF-601TA]
    2  P3V3_AUX_CLK_GEN_VDDXTAL_CK440      2  @S9S_MB_2U_LIB.S9S_MB_2U(SCH_1):P3V3_AUX_CLK_GEN_VDDXTAL_CK440
    1  P3V3_AUX           1  @S9S_MB_2U_LIB.S9S_MB_2U(SCH_1):P3V3_AUX

Q_INDUCTOR  I60  L14    [Q_INDUCTOR_SMLF-FCM2012KF-601TA]
    2  P3V3_AUX_CLK_GEN_VDDMXCK_CK440      2  @S9S_MB_2U_LIB.S9S_MB_2U(SCH_1):P3V3_AUX_CLK_GEN_VDDMXCK_CK440
    1  P3V3_AUX           1  @S9S_MB_2U_LIB.S9S_MB_2U(SCH_1):P3V3_AUX

Q_INDUCTOR  I228  L36    [Q_INDUCTOR_SMLF-BLM18PG121SN1DA]
    2  PVCCA_AUX_PLD      2  @S9S_MB_2U_LIB.S9S_MB_2U(SCH_1):PVCCA_AUX_PLD
    1  P3V3_AUX           1  @S9S_MB_2U_LIB.S9S_MB_2U(SCH_1):P3V3_AUX

ME_DUMMY_SYMBOL  I10  ME2    [ME_DUMMY_SYMBOL-PICKUP_SMDC20,A]

ME_DUMMY_SYMBOL  I11  ME3    [ME_DUMMY_SYMBOL-PICKUP_SMDC20,A]

ME_DUMMY_SYMBOL  I9   ME4    [ME_DUMMY_SYMBOL-PICKUP_SMDC20,A]

ME_DUMMY_SYMBOL  I3   ME5    [ME_DUMMY_SYMBOL-PICKUP_SMDC10,A]

ME_DUMMY_SYMBOL  I4   ME6    [ME_DUMMY_SYMBOL-PICKUP_SMDC10,A]

ME_DUMMY_SYMBOL  I2   ME7    [ME_DUMMY_SYMBOL-PICKUP_SMDC10,A]

DUMMY_SYMBOL  I19  ME8    [DUMMY_SYMBOL-QUANTA_LOGO_7X26,A]
    1  NC                 1  NC

ME_DUMMY_SYMBOL  I20  ME9    [ME_DUMMY_SYMBOL-PICKUP_SMDC20,A]

ME_DUMMY_SYMBOL  I21  ME10   [ME_DUMMY_SYMBOL-PICKUP_SMDC20,A]

ME_DUMMY_SYMBOL  I22  ME11   [ME_DUMMY_SYMBOL-PICKUP_SMDC20,A]

ME_DUMMY_SYMBOL  I23  ME12   [ME_DUMMY_SYMBOL-PICKUP_SMDC20,A]

ME_DUMMY_SYMBOL  I25  ME13   [ME_DUMMY_SYMBOL-PICKUP_SMDC20,A]

ME_DUMMY_SYMBOL  I26  ME14   [ME_DUMMY_SYMBOL-PICKUP_SMDC20,A]

ME_DUMMY_SYMBOL  I24  ME15   [ME_DUMMY_SYMBOL-PICKUP_SMDC20,A]

ME_DUMMY_SYMBOL  I27  ME16   [ME_DUMMY_SYMBOL-PICKUP_SMDC10,A]

OSC4_SIT1602AI2233E50000000D  I58  OSC1   [OSC4_SIT1602AI2233E50000000D-5A]
    4  P3V3_AUX         VDD  @S9S_MB_2U_LIB.S9S_MB_2U(SCH_1):P3V3_AUX
    2  GND              GND  @S9S_MB_2U_LIB.S9S_MB_2U(SCH_1):GND
    3  CLK_50M_RMII     OUT  @S9S_MB_2U_LIB.S9S_MB_2U(SCH_1):CLK_50M_RMII
    1  CLK_50M_EN        OE  @S9S_MB_2U_LIB.S9S_MB_2U(SCH_1):CLK_50M_EN

Q_OSC4P  I132  OSC2   [Q_OSC4P_SMLF-25MHZ,OSC,BF62500A]
    1  PU_CLK25M_OSC_FPGA_EN     OE  @S9S_MB_2U_LIB.S9S_MB_2U(SCH_1):PU_CLK25M_OSC_FPGA_EN
    4  P3V3_AUX         VDD  @S9S_MB_2U_LIB.S9S_MB_2U(SCH_1):P3V3_AUX
    2  GND              GND  @S9S_MB_2U_LIB.S9S_MB_2U(SCH_1):GND
    3  CLK_25M_OSC_FPGA_R    OUT  @S9S_MB_2U_LIB.S9S_MB_2U(SCH_1):CLK_25M_OSC_FPGA_R

Q_CAPP  I130  PC16   [Q_CAPP_THLF-560UF,2.5V,20%,OSCA]
    1  PVCCIN_CPU0        A  @S9S_MB_2U_LIB.S9S_MB_2U(SCH_1):PVCCIN_CPU0
    2  GND                B  @S9S_MB_2U_LIB.S9S_MB_2U(SCH_1):GND

Q_CAP  I169  PC27   [Q_CAP_0402-3300PF,50V,10%,X7R,A]
    1  PVNN_MAIN_CPU0_REF      A  @S9S_MB_2U_LIB.S9S_MB_2U(SCH_1):PVNN_MAIN_CPU0_REF
    2  GND                B  @S9S_MB_2U_LIB.S9S_MB_2U(SCH_1):GND

Q_CAP  I179  PC28   [Q_CAP_0402-3300PF,50V,10%,X7R,A]
    1  PVNN_MAIN_CPU1_REF      A  @S9S_MB_2U_LIB.S9S_MB_2U(SCH_1):PVNN_MAIN_CPU1_REF
    2  GND                B  @S9S_MB_2U_LIB.S9S_MB_2U(SCH_1):GND

Q_CAP  I22  PC71   [Q_CAP_C0805-22UF,16V,20%,X6S,CA]
    1  SW_P3V3_AUX_FLT      A  @S9S_MB_2U_LIB.S9S_MB_2U(SCH_1):SW_P3V3_AUX_FLT
    2  GND                B  @S9S_MB_2U_LIB.S9S_MB_2U(SCH_1):GND

Q_CAPP  I105  PC83   [Q_CAPP_THLF-560UF,2.5V,20%,OSCA]
    1  PVCCIN_CPU1        A  @S9S_MB_2U_LIB.S9S_MB_2U(SCH_1):PVCCIN_CPU1
    2  GND                B  @S9S_MB_2U_LIB.S9S_MB_2U(SCH_1):GND

Q_CAP  I8   PC113  [Q_CAP_C0402-1UF,25V,10%,X6S,CHA]
    1  P1V05_PCH_AUX_VCC      A  @S9S_MB_2U_LIB.S9S_MB_2U(SCH_1):P1V05_PCH_AUX_VCC
    2  GND                B  @S9S_MB_2U_LIB.S9S_MB_2U(SCH_1):GND

Q_CAPP  I14  PC117  [Q_CAPP_SMLF-470UF,2V,20%,POSCAA]
    1  P1V05_PCH_AUX      A  @S9S_MB_2U_LIB.S9S_MB_2U(SCH_1):P1V05_PCH_AUX
    2  GND                B  @S9S_MB_2U_LIB.S9S_MB_2U(SCH_1):GND

Q_CAP  I10  PC175  [Q_CAP_C0402-2.2UF,10V,10%,X6S,A]
    1  PVCCFA_EHV_CPU0_VDD1      A  @S9S_MB_2U_LIB.S9S_MB_2U(SCH_1):PVCCFA_EHV_CPU0_VDD1
    2  GND                B  @S9S_MB_2U_LIB.S9S_MB_2U(SCH_1):GND

Q_CAP  I18  PC176  [Q_CAP_0402-3300PF,50V,10%,X7R,A]
    1  SW_P12V_PVCCINFAON_CPU0_FLT      A  @S9S_MB_2U_LIB.S9S_MB_2U(SCH_1):SW_P12V_PVCCINFAON_CPU0_FLT
    2  GND                B  @S9S_MB_2U_LIB.S9S_MB_2U(SCH_1):GND

Q_CAP  I31  PC177  [Q_CAP_C0402-1UF,16V,10%,X6S,CHA]
    1  SW_P12V_PVCCINFAON_CPU0_FLT      A  @S9S_MB_2U_LIB.S9S_MB_2U(SCH_1):SW_P12V_PVCCINFAON_CPU0_FLT
    2  GND                B  @S9S_MB_2U_LIB.S9S_MB_2U(SCH_1):GND

Q_CAP  I21  PC178  [Q_CAP_C0402-100NF,50V,10%,X7R,A]
    2  SW_PVCCFA_EHV_CPU0_BOOTR1      B  @S9S_MB_2U_LIB.S9S_MB_2U(SCH_1):SW_PVCCFA_EHV_CPU0_BOOTR1
    1  SW_PVCCFA_EHV_CPU0_BOOT1_R      A  @S9S_MB_2U_LIB.S9S_MB_2U(SCH_1):SW_PVCCFA_EHV_CPU0_BOOT1_R

Q_CAP  I35  PC179  [Q_CAP_C0805-22UF,16V,20%,X6S,CA]
    1  SW_P12V_PVCCINFAON_CPU0_FLT      A  @S9S_MB_2U_LIB.S9S_MB_2U(SCH_1):SW_P12V_PVCCINFAON_CPU0_FLT
    2  GND                B  @S9S_MB_2U_LIB.S9S_MB_2U(SCH_1):GND

Q_CAP  I32  PC180  [Q_CAP_C0805-22UF,16V,20%,X6S,CA]
    1  SW_P12V_PVCCINFAON_CPU0_FLT      A  @S9S_MB_2U_LIB.S9S_MB_2U(SCH_1):SW_P12V_PVCCINFAON_CPU0_FLT
    2  GND                B  @S9S_MB_2U_LIB.S9S_MB_2U(SCH_1):GND

Q_CAP  I22  PC181  [Q_CAP_C0402-100NF,50V,10%,X7R,A]
    1  PVCCFA_EHV_CPU0      A  @S9S_MB_2U_LIB.S9S_MB_2U(SCH_1):PVCCFA_EHV_CPU0
    2  GND                B  @S9S_MB_2U_LIB.S9S_MB_2U(SCH_1):GND

Q_CAP  I24  PC184  [Q_CAP_0805-22UF,4V,20%,X6S,TMPA]
    1  PVCCFA_EHV_CPU0      A  @S9S_MB_2U_LIB.S9S_MB_2U(SCH_1):PVCCFA_EHV_CPU0
    2  GND                B  @S9S_MB_2U_LIB.S9S_MB_2U(SCH_1):GND

Q_CAP  I25  PC186  [Q_CAP_0805-22UF,4V,20%,X6S,TMPA]
    1  PVCCFA_EHV_CPU0      A  @S9S_MB_2U_LIB.S9S_MB_2U(SCH_1):PVCCFA_EHV_CPU0
    2  GND                B  @S9S_MB_2U_LIB.S9S_MB_2U(SCH_1):GND

Q_CAP  I174  PC187  [Q_CAP_C0402-2.2UF,10V,10%,X6S,A]
    1  PVCCINFAON_CPU0_VDD1      A  @S9S_MB_2U_LIB.S9S_MB_2U(SCH_1):PVCCINFAON_CPU0_VDD1
    2  GND                B  @S9S_MB_2U_LIB.S9S_MB_2U(SCH_1):GND

Q_CAP  I153  PC188  [Q_CAP_C0402-2.2UF,10V,10%,X6S,A]
    1  PVCCINFAON_CPU0_VDD2      A  @S9S_MB_2U_LIB.S9S_MB_2U(SCH_1):PVCCINFAON_CPU0_VDD2
    2  GND                B  @S9S_MB_2U_LIB.S9S_MB_2U(SCH_1):GND

Q_CAPP  I54  PC189  [Q_CAPP_SMLF-470UF,2.5V,20%,EMPA]
    1  PVCCIN_CPU1        A  @S9S_MB_2U_LIB.S9S_MB_2U(SCH_1):PVCCIN_CPU1
    2  GND                B  @S9S_MB_2U_LIB.S9S_MB_2U(SCH_1):GND

Q_CAP  I178  PC189_P0_1  [Q_CAP_0402-3300PF,50V,10%,X7R,A]
    1  SW_P12V_PVCCINFAON_CPU0_FLT      A  @S9S_MB_2U_LIB.S9S_MB_2U(SCH_1):SW_P12V_PVCCINFAON_CPU0_FLT
    2  GND                B  @S9S_MB_2U_LIB.S9S_MB_2U(SCH_1):GND

Q_CAP  I167  PC190_P0_2  [Q_CAP_0402-3300PF,50V,10%,X7R,A]
    1  SW_P12V_PVCCINFAON_CPU0_FLT      A  @S9S_MB_2U_LIB.S9S_MB_2U(SCH_1):SW_P12V_PVCCINFAON_CPU0_FLT
    2  GND                B  @S9S_MB_2U_LIB.S9S_MB_2U(SCH_1):GND

Q_CAP  I179  PC191_P0_1  [Q_CAP_C0402-1UF,16V,10%,X6S,CHA]
    1  SW_P12V_PVCCINFAON_CPU0_FLT      A  @S9S_MB_2U_LIB.S9S_MB_2U(SCH_1):SW_P12V_PVCCINFAON_CPU0_FLT
    2  GND                B  @S9S_MB_2U_LIB.S9S_MB_2U(SCH_1):GND

Q_CAP  I168  PC192_P0_2  [Q_CAP_C0402-1UF,16V,10%,X6S,CHA]
    1  SW_P12V_PVCCINFAON_CPU0_FLT      A  @S9S_MB_2U_LIB.S9S_MB_2U(SCH_1):SW_P12V_PVCCINFAON_CPU0_FLT
    2  GND                B  @S9S_MB_2U_LIB.S9S_MB_2U(SCH_1):GND

Q_CAP  I205  PC193  [Q_CAP_C0402-100NF,50V,10%,X7R,A]
    2  SW_PVCCINFAON_CPU0_BOOTR1      B  @S9S_MB_2U_LIB.S9S_MB_2U(SCH_1):SW_PVCCINFAON_CPU0_BOOTR1
    1  SW_PVCCINFAON_CPU0_BOOT1_R      A  @S9S_MB_2U_LIB.S9S_MB_2U(SCH_1):SW_PVCCINFAON_CPU0_BOOT1_R

Q_CAP  I183  PC194  [Q_CAP_C0402-100NF,50V,10%,X7R,A]
    2  SW_PVCCINFAON_CPU0_BOOTR2      B  @S9S_MB_2U_LIB.S9S_MB_2U(SCH_1):SW_PVCCINFAON_CPU0_BOOTR2
    1  SW_PVCCINFAON_CPU0_BOOT2_R      A  @S9S_MB_2U_LIB.S9S_MB_2U(SCH_1):SW_PVCCINFAON_CPU0_BOOT2_R

Q_CAP  I204  PC195_P0_1  [Q_CAP_C0805-22UF,16V,20%,X6S,CA]
    1  SW_P12V_PVCCINFAON_CPU0_FLT      A  @S9S_MB_2U_LIB.S9S_MB_2U(SCH_1):SW_P12V_PVCCINFAON_CPU0_FLT
    2  GND                B  @S9S_MB_2U_LIB.S9S_MB_2U(SCH_1):GND

Q_CAP  I186  PC196_P0_2  [Q_CAP_C0805-22UF,16V,20%,X6S,CA]
    1  SW_P12V_PVCCINFAON_CPU0_FLT      A  @S9S_MB_2U_LIB.S9S_MB_2U(SCH_1):SW_P12V_PVCCINFAON_CPU0_FLT
    2  GND                B  @S9S_MB_2U_LIB.S9S_MB_2U(SCH_1):GND

Q_CAP  I206  PC197_P0_1  [Q_CAP_C0805-22UF,16V,20%,X6S,CA]
    1  SW_P12V_PVCCINFAON_CPU0_FLT      A  @S9S_MB_2U_LIB.S9S_MB_2U(SCH_1):SW_P12V_PVCCINFAON_CPU0_FLT
    2  GND                B  @S9S_MB_2U_LIB.S9S_MB_2U(SCH_1):GND

Q_CAP  I187  PC198_P0_2  [Q_CAP_C0805-22UF,16V,20%,X6S,CA]
    1  SW_P12V_PVCCINFAON_CPU0_FLT      A  @S9S_MB_2U_LIB.S9S_MB_2U(SCH_1):SW_P12V_PVCCINFAON_CPU0_FLT
    2  GND                B  @S9S_MB_2U_LIB.S9S_MB_2U(SCH_1):GND

Q_CAP  I191  PC199_P0_1  [Q_CAP_C0402-100NF,50V,10%,X7R,A]
    1  PVCCINFAON_CPU0      A  @S9S_MB_2U_LIB.S9S_MB_2U(SCH_1):PVCCINFAON_CPU0
    2  GND                B  @S9S_MB_2U_LIB.S9S_MB_2U(SCH_1):GND

Q_CAP  I192  PC202_P0_1  [Q_CAP_0805-22UF,4V,20%,X6S,TMPA]
    1  PVCCINFAON_CPU0      A  @S9S_MB_2U_LIB.S9S_MB_2U(SCH_1):PVCCINFAON_CPU0
    2  GND                B  @S9S_MB_2U_LIB.S9S_MB_2U(SCH_1):GND

Q_CAP  I194  PC203_P0_2  [Q_CAP_0805-22UF,4V,20%,X6S,TMPA]
    1  PVCCINFAON_CPU0      A  @S9S_MB_2U_LIB.S9S_MB_2U(SCH_1):PVCCINFAON_CPU0
    2  GND                B  @S9S_MB_2U_LIB.S9S_MB_2U(SCH_1):GND

Q_CAP  I197  PC204_P0_1  [Q_CAP_0805-22UF,4V,20%,X6S,TMPA]
    1  PVCCINFAON_CPU0      A  @S9S_MB_2U_LIB.S9S_MB_2U(SCH_1):PVCCINFAON_CPU0
    2  GND                B  @S9S_MB_2U_LIB.S9S_MB_2U(SCH_1):GND

Q_CAP  I195  PC205_P0_2  [Q_CAP_0805-22UF,4V,20%,X6S,TMPA]
    1  PVCCINFAON_CPU0      A  @S9S_MB_2U_LIB.S9S_MB_2U(SCH_1):PVCCINFAON_CPU0
    2  GND                B  @S9S_MB_2U_LIB.S9S_MB_2U(SCH_1):GND

Q_CAPP  I213  PC207  [Q_CAPP_THLF-270UF,16V,20%,OSCOA]
    1  SW_P12V_PVCCINFAON_CPU0_FLT      A  @S9S_MB_2U_LIB.S9S_MB_2U(SCH_1):SW_P12V_PVCCINFAON_CPU0_FLT
    2  GND                B  @S9S_MB_2U_LIB.S9S_MB_2U(SCH_1):GND

Q_CAPP  I214  PC208  [Q_CAPP_THLF-270UF,16V,20%,OSCOA]
    1  SW_P12V_PVCCINFAON_CPU0_FLT      A  @S9S_MB_2U_LIB.S9S_MB_2U(SCH_1):SW_P12V_PVCCINFAON_CPU0_FLT
    2  GND                B  @S9S_MB_2U_LIB.S9S_MB_2U(SCH_1):GND

Q_CAP  I35  PC214  [Q_CAP_0402-0.1UF,25V,10%,EMPTYA]
    1  PVCCINFAON_CPU0_CSPIN      A  @S9S_MB_2U_LIB.S9S_MB_2U(SCH_1):PVCCINFAON_CPU0_CSPIN
    2  GND                B  @S9S_MB_2U_LIB.S9S_MB_2U(SCH_1):GND

Q_CAP  I47  PC215  [Q_CAP_0402-3300PF,50V,10%,X7R,A]
    2  VSENSE_PVCCINFAON_CPU0_DN      B  @S9S_MB_2U_LIB.S9S_MB_2U(SCH_1):VSENSE_PVCCINFAON_CPU0_DN
    1  SH_PVCCINFAON_CPU0_R      A  @S9S_MB_2U_LIB.S9S_MB_2U(SCH_1):SH_PVCCINFAON_CPU0_R

Q_CAP  I46  PC216  [Q_CAP_0402-3300PF,50V,10%,X7R,A]
    2  VSENSE_PVCCFA_EHV_CPU0_DN      B  @S9S_MB_2U_LIB.S9S_MB_2U(SCH_1):VSENSE_PVCCFA_EHV_CPU0_DN
    1  SH_PVCCFA_EHV_CPU0_R      A  @S9S_MB_2U_LIB.S9S_MB_2U(SCH_1):SH_PVCCFA_EHV_CPU0_R

Q_CAP  I65  PC217  [Q_CAP_0402-1000PF,50V,5%,X7R,TA]
    1  PVCCINFAON_CPU0_EN_R      A  @S9S_MB_2U_LIB.S9S_MB_2U(SCH_1):PVCCINFAON_CPU0_EN_R
    2  GND                B  @S9S_MB_2U_LIB.S9S_MB_2U(SCH_1):GND

Q_CAP  I69  PC218  [Q_CAP_0402-1000PF,50V,5%,EMPTYA]
    1  PWRGD_PVCCINFAON_CPU0_R      A  @S9S_MB_2U_LIB.S9S_MB_2U(SCH_1):PWRGD_PVCCINFAON_CPU0_R
    2  GND                B  @S9S_MB_2U_LIB.S9S_MB_2U(SCH_1):GND

Q_CAP  I37  PC219  [Q_CAP_0402-1000PF,50V,5%,X7R,TA]
    1  PVCCFA_EHV_CPU0_EN_R      A  @S9S_MB_2U_LIB.S9S_MB_2U(SCH_1):PVCCFA_EHV_CPU0_EN_R
    2  GND                B  @S9S_MB_2U_LIB.S9S_MB_2U(SCH_1):GND

Q_CAP  I38  PC220  [Q_CAP_0402-1000PF,50V,5%,EMPTYA]
    1  PWRGD_PVCCFA_EHV_CPU0_R      A  @S9S_MB_2U_LIB.S9S_MB_2U(SCH_1):PWRGD_PVCCFA_EHV_CPU0_R
    2  GND                B  @S9S_MB_2U_LIB.S9S_MB_2U(SCH_1):GND

Q_CAP  I49  PC221  [Q_CAP_0402-0.1UF,25V,10%,X7R,CA]
    1  PVCCINFAON_CPU0_VIN_CSNIN      A  @S9S_MB_2U_LIB.S9S_MB_2U(SCH_1):PVCCINFAON_CPU0_VIN_CSNIN
    2  GND                B  @S9S_MB_2U_LIB.S9S_MB_2U(SCH_1):GND

Q_CAP  I55  PC222  [Q_CAP_0402-470PF,50V,10%,X7R,TA]
    1  PVCCINFAON_CPU0_ATSEN      A  @S9S_MB_2U_LIB.S9S_MB_2U(SCH_1):PVCCINFAON_CPU0_ATSEN
    2  GND                B  @S9S_MB_2U_LIB.S9S_MB_2U(SCH_1):GND

Q_CAP  I88  PC223  [Q_CAP_C0402-100NF,50V,10%,EMPTA]
    1  PVCCINFAON_CPU0_VCC      A  @S9S_MB_2U_LIB.S9S_MB_2U(SCH_1):PVCCINFAON_CPU0_VCC
    2  GND                B  @S9S_MB_2U_LIB.S9S_MB_2U(SCH_1):GND

Q_CAP  I87  PC224  [Q_CAP_0402-4.7UF,6.3V,20%,X6S,A]
    1  PVCCINFAON_CPU0_VREF      A  @S9S_MB_2U_LIB.S9S_MB_2U(SCH_1):PVCCINFAON_CPU0_VREF
    2  GND                B  @S9S_MB_2U_LIB.S9S_MB_2U(SCH_1):GND

Q_CAP  I92  PC225  [Q_CAP_C0402-1UF,16V,10%,X6S,CHA]
    1  PVCCINFAON_CPU0_VCC      A  @S9S_MB_2U_LIB.S9S_MB_2U(SCH_1):PVCCINFAON_CPU0_VCC
    2  GND                B  @S9S_MB_2U_LIB.S9S_MB_2U(SCH_1):GND

Q_CAP  I9   PC226  [Q_CAP_C0402-2.2UF,10V,10%,X6S,A]
    1  PVCCIN_CPU0_VDD8      A  @S9S_MB_2U_LIB.S9S_MB_2U(SCH_1):PVCCIN_CPU0_VDD8
    2  GND                B  @S9S_MB_2U_LIB.S9S_MB_2U(SCH_1):GND

Q_CAP  I25  PC227  [Q_CAP_C0402-2.2UF,10V,10%,X6S,A]
    1  PVCCIN_CPU0_VDD7      A  @S9S_MB_2U_LIB.S9S_MB_2U(SCH_1):PVCCIN_CPU0_VDD7
    2  GND                B  @S9S_MB_2U_LIB.S9S_MB_2U(SCH_1):GND

Q_CAP  I19  PC228_P0_8  [Q_CAP_C0402-2.2UF,10V,10%,X6S,A]
    1  PVCCIN_CPU0_PVCC      A  @S9S_MB_2U_LIB.S9S_MB_2U(SCH_1):PVCCIN_CPU0_PVCC
    2  GND                B  @S9S_MB_2U_LIB.S9S_MB_2U(SCH_1):GND

Q_CAP  I30  PC229_P0_7  [Q_CAP_C0402-2.2UF,10V,10%,X6S,A]
    1  PVCCIN_CPU0_PVCC      A  @S9S_MB_2U_LIB.S9S_MB_2U(SCH_1):PVCCIN_CPU0_PVCC
    2  GND                B  @S9S_MB_2U_LIB.S9S_MB_2U(SCH_1):GND

Q_CAP  I36  PC230_P0_8  [Q_CAP_0402-3300PF,50V,10%,X7R,A]
    1  SW_P12V_PVCCIN_CPU0_FLT      A  @S9S_MB_2U_LIB.S9S_MB_2U(SCH_1):SW_P12V_PVCCIN_CPU0_FLT
    2  GND                B  @S9S_MB_2U_LIB.S9S_MB_2U(SCH_1):GND

Q_CAP  I50  PC231_P0_7  [Q_CAP_0402-3300PF,50V,10%,X7R,A]
    1  SW_P12V_PVCCIN_CPU0_FLT      A  @S9S_MB_2U_LIB.S9S_MB_2U(SCH_1):SW_P12V_PVCCIN_CPU0_FLT
    2  GND                B  @S9S_MB_2U_LIB.S9S_MB_2U(SCH_1):GND

Q_CAP  I37  PC232_P0_8  [Q_CAP_C0402-1UF,16V,10%,X6S,CHA]
    1  SW_P12V_PVCCIN_CPU0_FLT      A  @S9S_MB_2U_LIB.S9S_MB_2U(SCH_1):SW_P12V_PVCCIN_CPU0_FLT
    2  GND                B  @S9S_MB_2U_LIB.S9S_MB_2U(SCH_1):GND

Q_CAP  I51  PC233_P0_7  [Q_CAP_C0402-1UF,16V,10%,X6S,CHA]
    1  SW_P12V_PVCCIN_CPU0_FLT      A  @S9S_MB_2U_LIB.S9S_MB_2U(SCH_1):SW_P12V_PVCCIN_CPU0_FLT
    2  GND                B  @S9S_MB_2U_LIB.S9S_MB_2U(SCH_1):GND

Q_CAP  I33  PC234  [Q_CAP_C0402-100NF,50V,10%,X7R,A]
    2  SW_PVCCIN_CPU0_BOOTR8      B  @S9S_MB_2U_LIB.S9S_MB_2U(SCH_1):SW_PVCCIN_CPU0_BOOTR8
    1  SW_PVCCIN_CPU0_BOOT8_R      A  @S9S_MB_2U_LIB.S9S_MB_2U(SCH_1):SW_PVCCIN_CPU0_BOOT8_R

Q_CAP  I55  PC235  [Q_CAP_C0402-100NF,50V,10%,X7R,A]
    2  SW_PVCCIN_CPU0_BOOTR7      B  @S9S_MB_2U_LIB.S9S_MB_2U(SCH_1):SW_PVCCIN_CPU0_BOOTR7
    1  SW_PVCCIN_CPU0_BOOT7_R      A  @S9S_MB_2U_LIB.S9S_MB_2U(SCH_1):SW_PVCCIN_CPU0_BOOT7_R

Q_CAP  I38  PC236_P0_8  [Q_CAP_C0805-22UF,16V,20%,X6S,CA]
    1  SW_P12V_PVCCIN_CPU0_FLT      A  @S9S_MB_2U_LIB.S9S_MB_2U(SCH_1):SW_P12V_PVCCIN_CPU0_FLT
    2  GND                B  @S9S_MB_2U_LIB.S9S_MB_2U(SCH_1):GND

Q_CAP  I179  PC237  [Q_CAP_0402-680PF,50V,10%,X7R,TA]
    1  PVNN_MAIN_CPU0_FB_RC      A  @S9S_MB_2U_LIB.S9S_MB_2U(SCH_1):PVNN_MAIN_CPU0_FB_RC
    2  PVNN_MAIN_CPU0      B  @S9S_MB_2U_LIB.S9S_MB_2U(SCH_1):PVNN_MAIN_CPU0

Q_CAP  I52  PC237_P0_7  [Q_CAP_C0805-22UF,16V,20%,X6S,CA]
    1  SW_P12V_PVCCIN_CPU0_FLT      A  @S9S_MB_2U_LIB.S9S_MB_2U(SCH_1):SW_P12V_PVCCIN_CPU0_FLT
    2  GND                B  @S9S_MB_2U_LIB.S9S_MB_2U(SCH_1):GND

Q_CAP  I189  PC238  [Q_CAP_0402-680PF,50V,10%,X7R,TA]
    1  PVNN_MAIN_CPU1_FB_RC      A  @S9S_MB_2U_LIB.S9S_MB_2U(SCH_1):PVNN_MAIN_CPU1_FB_RC
    2  PVNN_MAIN_CPU1      B  @S9S_MB_2U_LIB.S9S_MB_2U(SCH_1):PVNN_MAIN_CPU1

Q_CAP  I39  PC238_P0_8  [Q_CAP_C0805-22UF,16V,20%,X6S,CA]
    1  SW_P12V_PVCCIN_CPU0_FLT      A  @S9S_MB_2U_LIB.S9S_MB_2U(SCH_1):SW_P12V_PVCCIN_CPU0_FLT
    2  GND                B  @S9S_MB_2U_LIB.S9S_MB_2U(SCH_1):GND

Q_CAP  I57  PC239_P0_7  [Q_CAP_C0805-22UF,16V,20%,X6S,CA]
    1  SW_P12V_PVCCIN_CPU0_FLT      A  @S9S_MB_2U_LIB.S9S_MB_2U(SCH_1):SW_P12V_PVCCIN_CPU0_FLT
    2  GND                B  @S9S_MB_2U_LIB.S9S_MB_2U(SCH_1):GND

Q_CAP  I40  PC240_P0_8  [Q_CAP_C0805-22UF,16V,20%,X6S,CA]
    1  SW_P12V_PVCCIN_CPU0_FLT      A  @S9S_MB_2U_LIB.S9S_MB_2U(SCH_1):SW_P12V_PVCCIN_CPU0_FLT
    2  GND                B  @S9S_MB_2U_LIB.S9S_MB_2U(SCH_1):GND

Q_CAP  I58  PC241_P0_7  [Q_CAP_C0805-22UF,16V,20%,X6S,CA]
    1  SW_P12V_PVCCIN_CPU0_FLT      A  @S9S_MB_2U_LIB.S9S_MB_2U(SCH_1):SW_P12V_PVCCIN_CPU0_FLT
    2  GND                B  @S9S_MB_2U_LIB.S9S_MB_2U(SCH_1):GND

Q_CAP  I104  PC242_P0_8  [Q_CAP_C0402-1UF,16V,10%,X6S,CHA]
    1  PVCCIN_CPU0        A  @S9S_MB_2U_LIB.S9S_MB_2U(SCH_1):PVCCIN_CPU0
    2  GND                B  @S9S_MB_2U_LIB.S9S_MB_2U(SCH_1):GND

Q_CAP  I79  PC243_P0_7  [Q_CAP_C0402-1UF,16V,10%,X6S,CHA]
    1  PVCCIN_CPU0        A  @S9S_MB_2U_LIB.S9S_MB_2U(SCH_1):PVCCIN_CPU0
    2  GND                B  @S9S_MB_2U_LIB.S9S_MB_2U(SCH_1):GND

Q_CAP  I103  PC244_P0_8  [Q_CAP_0805-22UF,4V,20%,X6S,TMPA]
    1  PVCCIN_CPU0        A  @S9S_MB_2U_LIB.S9S_MB_2U(SCH_1):PVCCIN_CPU0
    2  GND                B  @S9S_MB_2U_LIB.S9S_MB_2U(SCH_1):GND

Q_CAP  I78  PC245_P0_7  [Q_CAP_0805-22UF,4V,20%,X6S,TMPA]
    1  PVCCIN_CPU0        A  @S9S_MB_2U_LIB.S9S_MB_2U(SCH_1):PVCCIN_CPU0
    2  GND                B  @S9S_MB_2U_LIB.S9S_MB_2U(SCH_1):GND

Q_CAP  I101  PC246_P0_8  [Q_CAP_0805-22UF,4V,20%,X6S,TMPA]
    1  PVCCIN_CPU0        A  @S9S_MB_2U_LIB.S9S_MB_2U(SCH_1):PVCCIN_CPU0
    2  GND                B  @S9S_MB_2U_LIB.S9S_MB_2U(SCH_1):GND

Q_CAP  I77  PC247_P0_7  [Q_CAP_0805-22UF,4V,20%,X6S,TMPA]
    1  PVCCIN_CPU0        A  @S9S_MB_2U_LIB.S9S_MB_2U(SCH_1):PVCCIN_CPU0
    2  GND                B  @S9S_MB_2U_LIB.S9S_MB_2U(SCH_1):GND

Q_CAP  I10  PC248  [Q_CAP_C0402-2.2UF,10V,10%,X6S,A]
    1  PVCCIN_CPU0_VDD6      A  @S9S_MB_2U_LIB.S9S_MB_2U(SCH_1):PVCCIN_CPU0_VDD6
    2  GND                B  @S9S_MB_2U_LIB.S9S_MB_2U(SCH_1):GND

Q_CAP  I30  PC249  [Q_CAP_C0402-2.2UF,10V,10%,X6S,A]
    1  PVCCIN_CPU0_VDD5      A  @S9S_MB_2U_LIB.S9S_MB_2U(SCH_1):PVCCIN_CPU0_VDD5
    2  GND                B  @S9S_MB_2U_LIB.S9S_MB_2U(SCH_1):GND

Q_CAP  I12  PC250_P0_6  [Q_CAP_C0402-2.2UF,10V,10%,X6S,A]
    1  PVCCIN_CPU0_PVCC      A  @S9S_MB_2U_LIB.S9S_MB_2U(SCH_1):PVCCIN_CPU0_PVCC
    2  GND                B  @S9S_MB_2U_LIB.S9S_MB_2U(SCH_1):GND

Q_CAP  I34  PC251_P0_5  [Q_CAP_C0402-2.2UF,10V,10%,X6S,A]
    1  PVCCIN_CPU0_PVCC      A  @S9S_MB_2U_LIB.S9S_MB_2U(SCH_1):PVCCIN_CPU0_PVCC
    2  GND                B  @S9S_MB_2U_LIB.S9S_MB_2U(SCH_1):GND

Q_CAP  I15  PC252_P0_6  [Q_CAP_0402-3300PF,50V,10%,X7R,A]
    1  SW_P12V_PVCCIN_CPU0_FLT      A  @S9S_MB_2U_LIB.S9S_MB_2U(SCH_1):SW_P12V_PVCCIN_CPU0_FLT
    2  GND                B  @S9S_MB_2U_LIB.S9S_MB_2U(SCH_1):GND

Q_CAP  I38  PC253_P0_5  [Q_CAP_0402-3300PF,50V,10%,X7R,A]
    1  SW_P12V_PVCCIN_CPU0_FLT      A  @S9S_MB_2U_LIB.S9S_MB_2U(SCH_1):SW_P12V_PVCCIN_CPU0_FLT
    2  GND                B  @S9S_MB_2U_LIB.S9S_MB_2U(SCH_1):GND

Q_CAP  I18  PC254_P0_6  [Q_CAP_C0402-1UF,16V,10%,X6S,CHA]
    1  SW_P12V_PVCCIN_CPU0_FLT      A  @S9S_MB_2U_LIB.S9S_MB_2U(SCH_1):SW_P12V_PVCCIN_CPU0_FLT
    2  GND                B  @S9S_MB_2U_LIB.S9S_MB_2U(SCH_1):GND

Q_CAP  I39  PC255_P0_5  [Q_CAP_C0402-1UF,16V,10%,X6S,CHA]
    1  SW_P12V_PVCCIN_CPU0_FLT      A  @S9S_MB_2U_LIB.S9S_MB_2U(SCH_1):SW_P12V_PVCCIN_CPU0_FLT
    2  GND                B  @S9S_MB_2U_LIB.S9S_MB_2U(SCH_1):GND

Q_CAP  I16  PC256  [Q_CAP_C0402-100NF,50V,10%,X7R,A]
    2  SW_PVCCIN_CPU0_BOOTR6      B  @S9S_MB_2U_LIB.S9S_MB_2U(SCH_1):SW_PVCCIN_CPU0_BOOTR6
    1  SW_PVCCIN_CPU0_BOOT6_R      A  @S9S_MB_2U_LIB.S9S_MB_2U(SCH_1):SW_PVCCIN_CPU0_BOOT6_R

Q_CAP  I42  PC257  [Q_CAP_C0402-100NF,50V,10%,X7R,A]
    2  SW_PVCCIN_CPU0_BOOTR5      B  @S9S_MB_2U_LIB.S9S_MB_2U(SCH_1):SW_PVCCIN_CPU0_BOOTR5
    1  SW_PVCCIN_CPU0_BOOT5_R      A  @S9S_MB_2U_LIB.S9S_MB_2U(SCH_1):SW_PVCCIN_CPU0_BOOT5_R

Q_CAP  I19  PC258_P0_6  [Q_CAP_C0805-22UF,16V,20%,X6S,CA]
    1  SW_P12V_PVCCIN_CPU0_FLT      A  @S9S_MB_2U_LIB.S9S_MB_2U(SCH_1):SW_P12V_PVCCIN_CPU0_FLT
    2  GND                B  @S9S_MB_2U_LIB.S9S_MB_2U(SCH_1):GND

Q_CAP  I40  PC259_P0_5  [Q_CAP_C0805-22UF,16V,20%,X6S,CA]
    1  SW_P12V_PVCCIN_CPU0_FLT      A  @S9S_MB_2U_LIB.S9S_MB_2U(SCH_1):SW_P12V_PVCCIN_CPU0_FLT
    2  GND                B  @S9S_MB_2U_LIB.S9S_MB_2U(SCH_1):GND

Q_CAP  I41  PC260_P0_6  [Q_CAP_C0805-22UF,16V,20%,X6S,CA]
    1  SW_P12V_PVCCIN_CPU0_FLT      A  @S9S_MB_2U_LIB.S9S_MB_2U(SCH_1):SW_P12V_PVCCIN_CPU0_FLT
    2  GND                B  @S9S_MB_2U_LIB.S9S_MB_2U(SCH_1):GND

Q_CAP  I59  PC261_P0_5  [Q_CAP_C0805-22UF,16V,20%,X6S,CA]
    1  SW_P12V_PVCCIN_CPU0_FLT      A  @S9S_MB_2U_LIB.S9S_MB_2U(SCH_1):SW_P12V_PVCCIN_CPU0_FLT
    2  GND                B  @S9S_MB_2U_LIB.S9S_MB_2U(SCH_1):GND

Q_CAP  I45  PC262_P0_6  [Q_CAP_C0805-22UF,16V,20%,X6S,CA]
    1  SW_P12V_PVCCIN_CPU0_FLT      A  @S9S_MB_2U_LIB.S9S_MB_2U(SCH_1):SW_P12V_PVCCIN_CPU0_FLT
    2  GND                B  @S9S_MB_2U_LIB.S9S_MB_2U(SCH_1):GND

Q_CAP  I60  PC263_P0_5  [Q_CAP_C0805-22UF,16V,20%,X6S,CA]
    1  SW_P12V_PVCCIN_CPU0_FLT      A  @S9S_MB_2U_LIB.S9S_MB_2U(SCH_1):SW_P12V_PVCCIN_CPU0_FLT
    2  GND                B  @S9S_MB_2U_LIB.S9S_MB_2U(SCH_1):GND

Q_CAP  I95  PC266_P0_6  [Q_CAP_0805-22UF,4V,20%,X6S,TMPA]
    1  PVCCIN_CPU0        A  @S9S_MB_2U_LIB.S9S_MB_2U(SCH_1):PVCCIN_CPU0
    2  GND                B  @S9S_MB_2U_LIB.S9S_MB_2U(SCH_1):GND

Q_CAP  I80  PC267_P0_5  [Q_CAP_0805-22UF,4V,20%,X6S,TMPA]
    1  PVCCIN_CPU0        A  @S9S_MB_2U_LIB.S9S_MB_2U(SCH_1):PVCCIN_CPU0
    2  GND                B  @S9S_MB_2U_LIB.S9S_MB_2U(SCH_1):GND

Q_CAP  I94  PC268_P0_6  [Q_CAP_0805-22UF,4V,20%,X6S,TMPA]
    1  PVCCIN_CPU0        A  @S9S_MB_2U_LIB.S9S_MB_2U(SCH_1):PVCCIN_CPU0
    2  GND                B  @S9S_MB_2U_LIB.S9S_MB_2U(SCH_1):GND

Q_CAP  I79  PC269_P0_5  [Q_CAP_0805-22UF,4V,20%,X6S,TMPA]
    1  PVCCIN_CPU0        A  @S9S_MB_2U_LIB.S9S_MB_2U(SCH_1):PVCCIN_CPU0
    2  GND                B  @S9S_MB_2U_LIB.S9S_MB_2U(SCH_1):GND

Q_CAP  I8   PC270  [Q_CAP_C0402-2.2UF,10V,10%,X6S,A]
    1  PVCCIN_CPU0_VDD4      A  @S9S_MB_2U_LIB.S9S_MB_2U(SCH_1):PVCCIN_CPU0_VDD4
    2  GND                B  @S9S_MB_2U_LIB.S9S_MB_2U(SCH_1):GND

Q_CAP  I26  PC271  [Q_CAP_C0402-2.2UF,10V,10%,X6S,A]
    1  PVCCIN_CPU0_VDD3      A  @S9S_MB_2U_LIB.S9S_MB_2U(SCH_1):PVCCIN_CPU0_VDD3
    2  GND                B  @S9S_MB_2U_LIB.S9S_MB_2U(SCH_1):GND

Q_CAP  I17  PC272_P0_4  [Q_CAP_C0402-2.2UF,10V,10%,X6S,A]
    1  PVCCIN_CPU0_PVCC      A  @S9S_MB_2U_LIB.S9S_MB_2U(SCH_1):PVCCIN_CPU0_PVCC
    2  GND                B  @S9S_MB_2U_LIB.S9S_MB_2U(SCH_1):GND

Q_CAP  I32  PC273_P0_3  [Q_CAP_C0402-2.2UF,10V,10%,X6S,A]
    1  PVCCIN_CPU0_PVCC      A  @S9S_MB_2U_LIB.S9S_MB_2U(SCH_1):PVCCIN_CPU0_PVCC
    2  GND                B  @S9S_MB_2U_LIB.S9S_MB_2U(SCH_1):GND

Q_CAP  I36  PC274_P0_4  [Q_CAP_0402-3300PF,50V,10%,X7R,A]
    1  SW_P12V_PVCCIN_CPU0_FLT      A  @S9S_MB_2U_LIB.S9S_MB_2U(SCH_1):SW_P12V_PVCCIN_CPU0_FLT
    2  GND                B  @S9S_MB_2U_LIB.S9S_MB_2U(SCH_1):GND

Q_CAP  I48  PC275_P0_3  [Q_CAP_0402-3300PF,50V,10%,X7R,A]
    1  SW_P12V_PVCCIN_CPU0_FLT      A  @S9S_MB_2U_LIB.S9S_MB_2U(SCH_1):SW_P12V_PVCCIN_CPU0_FLT
    2  GND                B  @S9S_MB_2U_LIB.S9S_MB_2U(SCH_1):GND

Q_CAP  I37  PC276_P0_4  [Q_CAP_C0402-1UF,16V,10%,X6S,CHA]
    1  SW_P12V_PVCCIN_CPU0_FLT      A  @S9S_MB_2U_LIB.S9S_MB_2U(SCH_1):SW_P12V_PVCCIN_CPU0_FLT
    2  GND                B  @S9S_MB_2U_LIB.S9S_MB_2U(SCH_1):GND

Q_CAP  I50  PC277_P0_3  [Q_CAP_C0402-1UF,16V,10%,X6S,CHA]
    1  SW_P12V_PVCCIN_CPU0_FLT      A  @S9S_MB_2U_LIB.S9S_MB_2U(SCH_1):SW_P12V_PVCCIN_CPU0_FLT
    2  GND                B  @S9S_MB_2U_LIB.S9S_MB_2U(SCH_1):GND

Q_CAP  I39  PC278  [Q_CAP_C0402-100NF,50V,10%,X7R,A]
    2  SW_PVCCIN_CPU0_BOOTR4      B  @S9S_MB_2U_LIB.S9S_MB_2U(SCH_1):SW_PVCCIN_CPU0_BOOTR4
    1  SW_PVCCIN_CPU0_BOOT4_R      A  @S9S_MB_2U_LIB.S9S_MB_2U(SCH_1):SW_PVCCIN_CPU0_BOOT4_R

Q_CAP  I53  PC279  [Q_CAP_C0402-100NF,50V,10%,X7R,A]
    2  SW_PVCCIN_CPU0_BOOTR3      B  @S9S_MB_2U_LIB.S9S_MB_2U(SCH_1):SW_PVCCIN_CPU0_BOOTR3
    1  SW_PVCCIN_CPU0_BOOT3_R      A  @S9S_MB_2U_LIB.S9S_MB_2U(SCH_1):SW_PVCCIN_CPU0_BOOT3_R

Q_CAP  I38  PC280_P0_4  [Q_CAP_C0805-22UF,16V,20%,X6S,CA]
    1  SW_P12V_PVCCIN_CPU0_FLT      A  @S9S_MB_2U_LIB.S9S_MB_2U(SCH_1):SW_P12V_PVCCIN_CPU0_FLT
    2  GND                B  @S9S_MB_2U_LIB.S9S_MB_2U(SCH_1):GND

Q_CAP  I51  PC281_P0_3  [Q_CAP_C0805-22UF,16V,20%,X6S,CA]
    1  SW_P12V_PVCCIN_CPU0_FLT      A  @S9S_MB_2U_LIB.S9S_MB_2U(SCH_1):SW_P12V_PVCCIN_CPU0_FLT
    2  GND                B  @S9S_MB_2U_LIB.S9S_MB_2U(SCH_1):GND

Q_CAP  I40  PC282_P0_4  [Q_CAP_C0805-22UF,16V,20%,X6S,CA]
    1  SW_P12V_PVCCIN_CPU0_FLT      A  @S9S_MB_2U_LIB.S9S_MB_2U(SCH_1):SW_P12V_PVCCIN_CPU0_FLT
    2  GND                B  @S9S_MB_2U_LIB.S9S_MB_2U(SCH_1):GND

Q_CAP  I55  PC283_P0_3  [Q_CAP_C0805-22UF,16V,20%,X6S,CA]
    1  SW_P12V_PVCCIN_CPU0_FLT      A  @S9S_MB_2U_LIB.S9S_MB_2U(SCH_1):SW_P12V_PVCCIN_CPU0_FLT
    2  GND                B  @S9S_MB_2U_LIB.S9S_MB_2U(SCH_1):GND

Q_CAP  I42  PC284_P0_4  [Q_CAP_C0805-22UF,16V,20%,X6S,CA]
    1  SW_P12V_PVCCIN_CPU0_FLT      A  @S9S_MB_2U_LIB.S9S_MB_2U(SCH_1):SW_P12V_PVCCIN_CPU0_FLT
    2  GND                B  @S9S_MB_2U_LIB.S9S_MB_2U(SCH_1):GND

Q_CAP  I56  PC285_P0_3  [Q_CAP_C0805-22UF,16V,20%,X6S,CA]
    1  SW_P12V_PVCCIN_CPU0_FLT      A  @S9S_MB_2U_LIB.S9S_MB_2U(SCH_1):SW_P12V_PVCCIN_CPU0_FLT
    2  GND                B  @S9S_MB_2U_LIB.S9S_MB_2U(SCH_1):GND

Q_CAP  I96  PC288_P0_4  [Q_CAP_0805-22UF,4V,20%,X6S,TMPA]
    1  PVCCIN_CPU0        A  @S9S_MB_2U_LIB.S9S_MB_2U(SCH_1):PVCCIN_CPU0
    2  GND                B  @S9S_MB_2U_LIB.S9S_MB_2U(SCH_1):GND

Q_CAP  I79  PC289_P0_3  [Q_CAP_0805-22UF,4V,20%,X6S,TMPA]
    1  PVCCIN_CPU0        A  @S9S_MB_2U_LIB.S9S_MB_2U(SCH_1):PVCCIN_CPU0
    2  GND                B  @S9S_MB_2U_LIB.S9S_MB_2U(SCH_1):GND

Q_CAP  I95  PC290_P0_4  [Q_CAP_0805-22UF,4V,20%,X6S,TMPA]
    1  PVCCIN_CPU0        A  @S9S_MB_2U_LIB.S9S_MB_2U(SCH_1):PVCCIN_CPU0
    2  GND                B  @S9S_MB_2U_LIB.S9S_MB_2U(SCH_1):GND

Q_CAP  I78  PC291_P0_3  [Q_CAP_0805-22UF,4V,20%,X6S,TMPA]
    1  PVCCIN_CPU0        A  @S9S_MB_2U_LIB.S9S_MB_2U(SCH_1):PVCCIN_CPU0
    2  GND                B  @S9S_MB_2U_LIB.S9S_MB_2U(SCH_1):GND

Q_CAP  I8   PC292  [Q_CAP_C0402-2.2UF,10V,10%,X6S,A]
    1  PVCCIN_CPU0_VDD2      A  @S9S_MB_2U_LIB.S9S_MB_2U(SCH_1):PVCCIN_CPU0_VDD2
    2  GND                B  @S9S_MB_2U_LIB.S9S_MB_2U(SCH_1):GND

Q_CAP  I30  PC293  [Q_CAP_C0402-2.2UF,10V,10%,X6S,A]
    1  PVCCIN_CPU0_VDD1      A  @S9S_MB_2U_LIB.S9S_MB_2U(SCH_1):PVCCIN_CPU0_VDD1
    2  GND                B  @S9S_MB_2U_LIB.S9S_MB_2U(SCH_1):GND

Q_CAP  I18  PC294_P0_2  [Q_CAP_C0402-2.2UF,10V,10%,X6S,A]
    1  PVCCIN_CPU0_PVCC      A  @S9S_MB_2U_LIB.S9S_MB_2U(SCH_1):PVCCIN_CPU0_PVCC
    2  GND                B  @S9S_MB_2U_LIB.S9S_MB_2U(SCH_1):GND

Q_CAP  I35  PC295_P0_1  [Q_CAP_C0402-2.2UF,10V,10%,X6S,A]
    1  PVCCIN_CPU0_PVCC      A  @S9S_MB_2U_LIB.S9S_MB_2U(SCH_1):PVCCIN_CPU0_PVCC
    2  GND                B  @S9S_MB_2U_LIB.S9S_MB_2U(SCH_1):GND

Q_CAP  I22  PC296_P0_2  [Q_CAP_0402-3300PF,50V,10%,X7R,A]
    1  SW_P12V_PVCCIN_CPU0_FLT      A  @S9S_MB_2U_LIB.S9S_MB_2U(SCH_1):SW_P12V_PVCCIN_CPU0_FLT
    2  GND                B  @S9S_MB_2U_LIB.S9S_MB_2U(SCH_1):GND

Q_CAP  I40  PC297_P0_1  [Q_CAP_0402-3300PF,50V,10%,X7R,A]
    1  SW_P12V_PVCCIN_CPU0_FLT      A  @S9S_MB_2U_LIB.S9S_MB_2U(SCH_1):SW_P12V_PVCCIN_CPU0_FLT
    2  GND                B  @S9S_MB_2U_LIB.S9S_MB_2U(SCH_1):GND

Q_CAP  I23  PC298_P0_2  [Q_CAP_C0402-1UF,16V,10%,X6S,CHA]
    1  SW_P12V_PVCCIN_CPU0_FLT      A  @S9S_MB_2U_LIB.S9S_MB_2U(SCH_1):SW_P12V_PVCCIN_CPU0_FLT
    2  GND                B  @S9S_MB_2U_LIB.S9S_MB_2U(SCH_1):GND

Q_CAP  I41  PC299_P0_1  [Q_CAP_C0402-1UF,16V,10%,X6S,CHA]
    1  SW_P12V_PVCCIN_CPU0_FLT      A  @S9S_MB_2U_LIB.S9S_MB_2U(SCH_1):SW_P12V_PVCCIN_CPU0_FLT
    2  GND                B  @S9S_MB_2U_LIB.S9S_MB_2U(SCH_1):GND

Q_CAP  I44  PC300  [Q_CAP_C0402-100NF,50V,10%,X7R,A]
    2  SW_PVCCIN_CPU0_BOOTR2      B  @S9S_MB_2U_LIB.S9S_MB_2U(SCH_1):SW_PVCCIN_CPU0_BOOTR2
    1  SW_PVCCIN_CPU0_BOOT2_R      A  @S9S_MB_2U_LIB.S9S_MB_2U(SCH_1):SW_PVCCIN_CPU0_BOOT2_R

Q_CAP  I62  PC301  [Q_CAP_C0402-100NF,50V,10%,X7R,A]
    2  SW_PVCCIN_CPU0_BOOTR1      B  @S9S_MB_2U_LIB.S9S_MB_2U(SCH_1):SW_PVCCIN_CPU0_BOOTR1
    1  SW_PVCCIN_CPU0_BOOT1_R      A  @S9S_MB_2U_LIB.S9S_MB_2U(SCH_1):SW_PVCCIN_CPU0_BOOT1_R

Q_CAP  I24  PC302_P0_2  [Q_CAP_C0805-22UF,16V,20%,X6S,CA]
    1  SW_P12V_PVCCIN_CPU0_FLT      A  @S9S_MB_2U_LIB.S9S_MB_2U(SCH_1):SW_P12V_PVCCIN_CPU0_FLT
    2  GND                B  @S9S_MB_2U_LIB.S9S_MB_2U(SCH_1):GND

Q_CAP  I65  PC303_P0_1  [Q_CAP_C0805-22UF,16V,20%,X6S,CA]
    1  SW_P12V_PVCCIN_CPU0_FLT      A  @S9S_MB_2U_LIB.S9S_MB_2U(SCH_1):SW_P12V_PVCCIN_CPU0_FLT
    2  GND                B  @S9S_MB_2U_LIB.S9S_MB_2U(SCH_1):GND

Q_CAP  I46  PC304_P0_2  [Q_CAP_C0805-22UF,16V,20%,X6S,CA]
    1  SW_P12V_PVCCIN_CPU0_FLT      A  @S9S_MB_2U_LIB.S9S_MB_2U(SCH_1):SW_P12V_PVCCIN_CPU0_FLT
    2  GND                B  @S9S_MB_2U_LIB.S9S_MB_2U(SCH_1):GND

Q_CAP  I66  PC305_P0_1  [Q_CAP_C0805-22UF,16V,20%,X6S,CA]
    1  SW_P12V_PVCCIN_CPU0_FLT      A  @S9S_MB_2U_LIB.S9S_MB_2U(SCH_1):SW_P12V_PVCCIN_CPU0_FLT
    2  GND                B  @S9S_MB_2U_LIB.S9S_MB_2U(SCH_1):GND

Q_CAP  I47  PC306_P0_2  [Q_CAP_C0805-22UF,16V,20%,X6S,CA]
    1  SW_P12V_PVCCIN_CPU0_FLT      A  @S9S_MB_2U_LIB.S9S_MB_2U(SCH_1):SW_P12V_PVCCIN_CPU0_FLT
    2  GND                B  @S9S_MB_2U_LIB.S9S_MB_2U(SCH_1):GND

Q_CAP  I67  PC307_P0_1  [Q_CAP_C0805-22UF,16V,20%,X6S,CA]
    1  SW_P12V_PVCCIN_CPU0_FLT      A  @S9S_MB_2U_LIB.S9S_MB_2U(SCH_1):SW_P12V_PVCCIN_CPU0_FLT
    2  GND                B  @S9S_MB_2U_LIB.S9S_MB_2U(SCH_1):GND

Q_CAP  I111  PC308_P0_1  [Q_CAP_C0402-100NF,50V,10%,X7R,A]
    1  PVCCIN_CPU0        A  @S9S_MB_2U_LIB.S9S_MB_2U(SCH_1):PVCCIN_CPU0
    2  GND                B  @S9S_MB_2U_LIB.S9S_MB_2U(SCH_1):GND

Q_CAP  I110  PC310_P0_1  [Q_CAP_C0402-1UF,16V,10%,X6S,CHA]
    1  PVCCIN_CPU0        A  @S9S_MB_2U_LIB.S9S_MB_2U(SCH_1):PVCCIN_CPU0
    2  GND                B  @S9S_MB_2U_LIB.S9S_MB_2U(SCH_1):GND

Q_CAP  I128  PC311_P0_2  [Q_CAP_0805-22UF,4V,20%,X6S,TMPA]
    1  PVCCIN_CPU0        A  @S9S_MB_2U_LIB.S9S_MB_2U(SCH_1):PVCCIN_CPU0
    2  GND                B  @S9S_MB_2U_LIB.S9S_MB_2U(SCH_1):GND

Q_CAP  I109  PC312_P0_1  [Q_CAP_0805-22UF,4V,20%,X6S,TMPA]
    1  PVCCIN_CPU0        A  @S9S_MB_2U_LIB.S9S_MB_2U(SCH_1):PVCCIN_CPU0
    2  GND                B  @S9S_MB_2U_LIB.S9S_MB_2U(SCH_1):GND

Q_CAP  I127  PC313_P0_2  [Q_CAP_0805-22UF,4V,20%,X6S,TMPA]
    1  PVCCIN_CPU0        A  @S9S_MB_2U_LIB.S9S_MB_2U(SCH_1):PVCCIN_CPU0
    2  GND                B  @S9S_MB_2U_LIB.S9S_MB_2U(SCH_1):GND

Q_CAP  I108  PC314_P0_1  [Q_CAP_0805-22UF,4V,20%,X6S,TMPA]
    1  PVCCIN_CPU0        A  @S9S_MB_2U_LIB.S9S_MB_2U(SCH_1):PVCCIN_CPU0
    2  GND                B  @S9S_MB_2U_LIB.S9S_MB_2U(SCH_1):GND

Q_CAPP  I74  PC315  [Q_CAPP_THLF-270UF,16V,20%,OSCOA]
    1  SW_P12V_PVCCIN_CPU0_FLT      A  @S9S_MB_2U_LIB.S9S_MB_2U(SCH_1):SW_P12V_PVCCIN_CPU0_FLT
    2  GND                B  @S9S_MB_2U_LIB.S9S_MB_2U(SCH_1):GND

Q_CAPP  I56  PC316  [Q_CAPP_THLF-560UF,2.5V,20%,OSCA]
    1  PVCCIN_CPU0        A  @S9S_MB_2U_LIB.S9S_MB_2U(SCH_1):PVCCIN_CPU0
    2  GND                B  @S9S_MB_2U_LIB.S9S_MB_2U(SCH_1):GND

Q_CAPP  I76  PC318  [Q_CAPP_THLF-270UF,16V,20%,OSCOA]
    1  SW_P12V_PVCCIN_CPU0_FLT      A  @S9S_MB_2U_LIB.S9S_MB_2U(SCH_1):SW_P12V_PVCCIN_CPU0_FLT
    2  GND                B  @S9S_MB_2U_LIB.S9S_MB_2U(SCH_1):GND

Q_CAPP  I58  PC319  [Q_CAPP_THLF-560UF,2.5V,20%,OSCA]
    1  PVCCIN_CPU0        A  @S9S_MB_2U_LIB.S9S_MB_2U(SCH_1):PVCCIN_CPU0
    2  GND                B  @S9S_MB_2U_LIB.S9S_MB_2U(SCH_1):GND

Q_CAPP  I77  PC321  [Q_CAPP_THLF-270UF,16V,20%,OSCOA]
    1  SW_P12V_PVCCIN_CPU0_FLT      A  @S9S_MB_2U_LIB.S9S_MB_2U(SCH_1):SW_P12V_PVCCIN_CPU0_FLT
    2  GND                B  @S9S_MB_2U_LIB.S9S_MB_2U(SCH_1):GND

Q_CAPP  I59  PC322  [Q_CAPP_THLF-560UF,2.5V,20%,OSCA]
    1  PVCCIN_CPU0        A  @S9S_MB_2U_LIB.S9S_MB_2U(SCH_1):PVCCIN_CPU0
    2  GND                B  @S9S_MB_2U_LIB.S9S_MB_2U(SCH_1):GND

Q_CAPP  I55  PC323  [Q_CAPP_SMLF-470UF,2.5V,20%,EMPA]
    1  PVCCIN_CPU0        A  @S9S_MB_2U_LIB.S9S_MB_2U(SCH_1):PVCCIN_CPU0
    2  GND                B  @S9S_MB_2U_LIB.S9S_MB_2U(SCH_1):GND

Q_CAPP  I84  PC324  [Q_CAPP_THLF-270UF,16V,20%,OSCOA]
    1  SW_P12V_PVCCIN_CPU0_FLT      A  @S9S_MB_2U_LIB.S9S_MB_2U(SCH_1):SW_P12V_PVCCIN_CPU0_FLT
    2  GND                B  @S9S_MB_2U_LIB.S9S_MB_2U(SCH_1):GND

Q_CAPP  I81  PC325  [Q_CAPP_THLF-560UF,2.5V,20%,OSCA]
    1  PVCCIN_CPU0        A  @S9S_MB_2U_LIB.S9S_MB_2U(SCH_1):PVCCIN_CPU0
    2  GND                B  @S9S_MB_2U_LIB.S9S_MB_2U(SCH_1):GND

Q_CAPP  I79  PC326  [Q_CAPP_SMLF-470UF,2.5V,20%,EMPA]
    1  PVCCIN_CPU0        A  @S9S_MB_2U_LIB.S9S_MB_2U(SCH_1):PVCCIN_CPU0
    2  GND                B  @S9S_MB_2U_LIB.S9S_MB_2U(SCH_1):GND

Q_CAP  I104  PC327  [Q_CAP_C0603-10UF,4V,20%,EMPTY,A]
    1  PVNN_TERM_CPU0      A  @S9S_MB_2U_LIB.S9S_MB_2U(SCH_1):PVNN_TERM_CPU0
    2  GND                B  @S9S_MB_2U_LIB.S9S_MB_2U(SCH_1):GND

Q_CAP  I106  PC328  [Q_CAP_C0402-100NF,50V,10%,X7R,A]
    1  PVNN_TERM_CPU0      A  @S9S_MB_2U_LIB.S9S_MB_2U(SCH_1):PVNN_TERM_CPU0
    2  GND                B  @S9S_MB_2U_LIB.S9S_MB_2U(SCH_1):GND

Q_CAP  I38  PC329  [Q_CAP_0402-0.1UF,25V,10%,EMPTYA]
    1  PVCCIN_CPU0_CSPIN      A  @S9S_MB_2U_LIB.S9S_MB_2U(SCH_1):PVCCIN_CPU0_CSPIN
    2  GND                B  @S9S_MB_2U_LIB.S9S_MB_2U(SCH_1):GND

Q_CAP  I45  PC330  [Q_CAP_0402-0.1UF,25V,10%,X7R,CA]
    1  PVCCIN_CPU0_VIN_CSNIN      A  @S9S_MB_2U_LIB.S9S_MB_2U(SCH_1):PVCCIN_CPU0_VIN_CSNIN
    2  GND                B  @S9S_MB_2U_LIB.S9S_MB_2U(SCH_1):GND

Q_CAP  I62  PC331  [Q_CAP_0402-3300PF,50V,10%,X7R,A]
    2  VSENSE_PVCCIN_CPU0_DN      B  @S9S_MB_2U_LIB.S9S_MB_2U(SCH_1):VSENSE_PVCCIN_CPU0_DN
    1  SH_PVCCIN_CPU0_R      A  @S9S_MB_2U_LIB.S9S_MB_2U(SCH_1):SH_PVCCIN_CPU0_R

Q_CAP  I67  PC332  [Q_CAP_0402-1000PF,50V,5%,X7R,TA]
    1  PVCCIN_CPU0_EN_R      A  @S9S_MB_2U_LIB.S9S_MB_2U(SCH_1):PVCCIN_CPU0_EN_R
    2  GND                B  @S9S_MB_2U_LIB.S9S_MB_2U(SCH_1):GND

Q_CAP  I72  PC333  [Q_CAP_0402-1000PF,50V,5%,EMPTYA]
    1  PWRGD_PVCCIN_CPU0_R      A  @S9S_MB_2U_LIB.S9S_MB_2U(SCH_1):PWRGD_PVCCIN_CPU0_R
    2  GND                B  @S9S_MB_2U_LIB.S9S_MB_2U(SCH_1):GND

Q_CAP  I75  PC334  [Q_CAP_C0402-100NF,50V,10%,EMPTA]
    1  PVCCIN_CPU0_VCC      A  @S9S_MB_2U_LIB.S9S_MB_2U(SCH_1):PVCCIN_CPU0_VCC
    2  GND                B  @S9S_MB_2U_LIB.S9S_MB_2U(SCH_1):GND

Q_CAP  I74  PC335  [Q_CAP_0402-4.7UF,6.3V,20%,X6S,A]
    1  PVCCIN_CPU0_VREF      A  @S9S_MB_2U_LIB.S9S_MB_2U(SCH_1):PVCCIN_CPU0_VREF
    2  GND                B  @S9S_MB_2U_LIB.S9S_MB_2U(SCH_1):GND

Q_CAP  I58  PC336  [Q_CAP_0402-470PF,50V,10%,X7R,TA]
    1  PVCCIN_CPU0_ATSEN      A  @S9S_MB_2U_LIB.S9S_MB_2U(SCH_1):PVCCIN_CPU0_ATSEN
    2  GND                B  @S9S_MB_2U_LIB.S9S_MB_2U(SCH_1):GND

Q_CAP  I119  PC337  [Q_CAP_C0402-1UF,16V,10%,X6S,CHA]
    1  PVCCIN_CPU0_VCC      A  @S9S_MB_2U_LIB.S9S_MB_2U(SCH_1):PVCCIN_CPU0_VCC
    2  GND                B  @S9S_MB_2U_LIB.S9S_MB_2U(SCH_1):GND

Q_CAP  I10  PC373  [Q_CAP_C0402-2.2UF,10V,10%,X6S,A]
    1  PVCCD_HV_CPU1_VDD1      A  @S9S_MB_2U_LIB.S9S_MB_2U(SCH_1):PVCCD_HV_CPU1_VDD1
    2  GND                B  @S9S_MB_2U_LIB.S9S_MB_2U(SCH_1):GND

Q_CAP  I18  PC374  [Q_CAP_0402-3300PF,50V,10%,X7R,A]
    1  SW_P12V_PVCCINFAON_CPU1_FLT      A  @S9S_MB_2U_LIB.S9S_MB_2U(SCH_1):SW_P12V_PVCCINFAON_CPU1_FLT
    2  GND                B  @S9S_MB_2U_LIB.S9S_MB_2U(SCH_1):GND

Q_CAP  I20  PC375  [Q_CAP_C0402-1UF,16V,10%,X6S,CHA]
    1  SW_P12V_PVCCINFAON_CPU1_FLT      A  @S9S_MB_2U_LIB.S9S_MB_2U(SCH_1):SW_P12V_PVCCINFAON_CPU1_FLT
    2  GND                B  @S9S_MB_2U_LIB.S9S_MB_2U(SCH_1):GND

Q_CAP  I25  PC376  [Q_CAP_C0402-100NF,50V,10%,X7R,A]
    2  SW_PVCCD_HV_CPU1_BOOTR1      B  @S9S_MB_2U_LIB.S9S_MB_2U(SCH_1):SW_PVCCD_HV_CPU1_BOOTR1
    1  SW_PVCCD_HV_CPU1_BOOT1_R      A  @S9S_MB_2U_LIB.S9S_MB_2U(SCH_1):SW_PVCCD_HV_CPU1_BOOT1_R

Q_CAP  I29  PC377  [Q_CAP_C0805-22UF,16V,20%,X6S,CA]
    1  SW_P12V_PVCCINFAON_CPU1_FLT      A  @S9S_MB_2U_LIB.S9S_MB_2U(SCH_1):SW_P12V_PVCCINFAON_CPU1_FLT
    2  GND                B  @S9S_MB_2U_LIB.S9S_MB_2U(SCH_1):GND

Q_CAP  I30  PC378  [Q_CAP_C0805-22UF,16V,20%,X6S,CA]
    1  SW_P12V_PVCCINFAON_CPU1_FLT      A  @S9S_MB_2U_LIB.S9S_MB_2U(SCH_1):SW_P12V_PVCCINFAON_CPU1_FLT
    2  GND                B  @S9S_MB_2U_LIB.S9S_MB_2U(SCH_1):GND

Q_CAP  I27  PC379  [Q_CAP_C0402-100NF,50V,10%,X7R,A]
    1  PVCCD_HV_CPU1      A  @S9S_MB_2U_LIB.S9S_MB_2U(SCH_1):PVCCD_HV_CPU1
    2  GND                B  @S9S_MB_2U_LIB.S9S_MB_2U(SCH_1):GND

Q_CAP  I28  PC381  [Q_CAP_0805-22UF,4V,20%,X6S,TMPA]
    1  PVCCD_HV_CPU1      A  @S9S_MB_2U_LIB.S9S_MB_2U(SCH_1):PVCCD_HV_CPU1
    2  GND                B  @S9S_MB_2U_LIB.S9S_MB_2U(SCH_1):GND

Q_CAP  I34  PC382  [Q_CAP_0805-22UF,4V,20%,X6S,TMPA]
    1  PVCCD_HV_CPU1      A  @S9S_MB_2U_LIB.S9S_MB_2U(SCH_1):PVCCD_HV_CPU1
    2  GND                B  @S9S_MB_2U_LIB.S9S_MB_2U(SCH_1):GND

Q_CAPP  I21  PC384  [Q_CAPP_THLF-560UF,2.5V,20%,OSCA]
    1  PVCCD_HV_CPU1      A  @S9S_MB_2U_LIB.S9S_MB_2U(SCH_1):PVCCD_HV_CPU1
    2  GND                B  @S9S_MB_2U_LIB.S9S_MB_2U(SCH_1):GND

Q_CAPP  I23  PC385  [Q_CAPP_THLF-560UF,2.5V,20%,OSCA]
    1  PVCCD_HV_CPU1      A  @S9S_MB_2U_LIB.S9S_MB_2U(SCH_1):PVCCD_HV_CPU1
    2  GND                B  @S9S_MB_2U_LIB.S9S_MB_2U(SCH_1):GND

Q_CAP  I237  PC386  [Q_CAP_0402-0.1UF,25V,10%,X7R,CA]
    1  PVCCD_HV_CPU1_ISENSE_P      A  @S9S_MB_2U_LIB.S9S_MB_2U(SCH_1):PVCCD_HV_CPU1_ISENSE_P
    2  GND                B  @S9S_MB_2U_LIB.S9S_MB_2U(SCH_1):GND

Q_CAP  I253  PC388  [Q_CAP_0402-1000PF,50V,5%,EMPTYA]
    1  PWRGD_PVCCD_HV_CPU1_R      A  @S9S_MB_2U_LIB.S9S_MB_2U(SCH_1):PWRGD_PVCCD_HV_CPU1_R
    2  GND                B  @S9S_MB_2U_LIB.S9S_MB_2U(SCH_1):GND

Q_CAP  I248  PC389  [Q_CAP_0402-3300PF,50V,10%,X7R,A]
    2  VSENSE_PVCCD_HV_CPU1_DN      B  @S9S_MB_2U_LIB.S9S_MB_2U(SCH_1):VSENSE_PVCCD_HV_CPU1_DN
    1  SH_PVCCD_HV_CPU1_R      A  @S9S_MB_2U_LIB.S9S_MB_2U(SCH_1):SH_PVCCD_HV_CPU1_R

Q_CAP  I240  PC390  [Q_CAP_0402-0.1UF,25V,10%,X7R,CA]
    1  PVCCD_HV_CPU1_ISENSE_N      A  @S9S_MB_2U_LIB.S9S_MB_2U(SCH_1):PVCCD_HV_CPU1_ISENSE_N
    2  GND                B  @S9S_MB_2U_LIB.S9S_MB_2U(SCH_1):GND

Q_CAP  I257  PC391  [Q_CAP_C0402-100NF,50V,10%,EMPTA]
    1  PVCCD_HV_CPU1_VCC      A  @S9S_MB_2U_LIB.S9S_MB_2U(SCH_1):PVCCD_HV_CPU1_VCC
    2  GND                B  @S9S_MB_2U_LIB.S9S_MB_2U(SCH_1):GND

Q_CAP  I255  PC392  [Q_CAP_0402-4.7UF,6.3V,20%,X6S,A]
    1  PVCCD_HV_CPU1_VREF      A  @S9S_MB_2U_LIB.S9S_MB_2U(SCH_1):PVCCD_HV_CPU1_VREF
    2  GND                B  @S9S_MB_2U_LIB.S9S_MB_2U(SCH_1):GND

Q_CAP  I251  PC393  [Q_CAP_0402-470PF,50V,10%,X7R,TA]
    1  PVCCD_HV_CPU1_ATSEN      A  @S9S_MB_2U_LIB.S9S_MB_2U(SCH_1):PVCCD_HV_CPU1_ATSEN
    2  GND                B  @S9S_MB_2U_LIB.S9S_MB_2U(SCH_1):GND

Q_CAP  I258  PC394  [Q_CAP_C0402-1UF,16V,10%,X6S,CHA]
    1  PVCCD_HV_CPU1_VCC      A  @S9S_MB_2U_LIB.S9S_MB_2U(SCH_1):PVCCD_HV_CPU1_VCC
    2  GND                B  @S9S_MB_2U_LIB.S9S_MB_2U(SCH_1):GND

Q_CAP  I230  PC395  [Q_CAP_C0402-2.2UF,10V,10%,X6S,A]
    1  PVCCFA_EHV_FIVRA_CPU1_VDD1      A  @S9S_MB_2U_LIB.S9S_MB_2U(SCH_1):PVCCFA_EHV_FIVRA_CPU1_VDD1
    2  GND                B  @S9S_MB_2U_LIB.S9S_MB_2U(SCH_1):GND

Q_CAP  I214  PC396  [Q_CAP_C0402-2.2UF,10V,10%,X6S,A]
    1  PVCCFA_EHV_FIVRA_CPU1_VDD2      A  @S9S_MB_2U_LIB.S9S_MB_2U(SCH_1):PVCCFA_EHV_FIVRA_CPU1_VDD2
    2  GND                B  @S9S_MB_2U_LIB.S9S_MB_2U(SCH_1):GND

Q_CAP  I238  PC397_P1_1  [Q_CAP_0402-3300PF,50V,10%,X7R,A]
    1  SW_P12V_PVCCFA_EHV_FIVRA_CPU1_R      A  @S9S_MB_2U_LIB.S9S_MB_2U(SCH_1):SW_P12V_PVCCFA_EHV_FIVRA_CPU1_R
    2  GND                B  @S9S_MB_2U_LIB.S9S_MB_2U(SCH_1):GND

Q_CAP  I223  PC398_P1_2  [Q_CAP_0402-3300PF,50V,10%,X7R,A]
    1  SW_P12V_PVCCFA_EHV_FIVRA_CPU1_L      A  @S9S_MB_2U_LIB.S9S_MB_2U(SCH_1):SW_P12V_PVCCFA_EHV_FIVRA_CPU1_L
    2  GND                B  @S9S_MB_2U_LIB.S9S_MB_2U(SCH_1):GND

Q_CAP  I257  PC399_P1_1  [Q_CAP_C0402-1UF,16V,10%,X6S,CHA]
    1  SW_P12V_PVCCFA_EHV_FIVRA_CPU1_R      A  @S9S_MB_2U_LIB.S9S_MB_2U(SCH_1):SW_P12V_PVCCFA_EHV_FIVRA_CPU1_R
    2  GND                B  @S9S_MB_2U_LIB.S9S_MB_2U(SCH_1):GND

Q_CAP  I243  PC400_P1_2  [Q_CAP_C0402-1UF,16V,10%,X6S,CHA]
    1  SW_P12V_PVCCFA_EHV_FIVRA_CPU1_L      A  @S9S_MB_2U_LIB.S9S_MB_2U(SCH_1):SW_P12V_PVCCFA_EHV_FIVRA_CPU1_L
    2  GND                B  @S9S_MB_2U_LIB.S9S_MB_2U(SCH_1):GND

Q_CAP  I261  PC401  [Q_CAP_C0402-100NF,50V,10%,X7R,A]
    2  SW_PVCCFA_EHV_FIVRA_CPU1_BOOTR1      B  @S9S_MB_2U_LIB.S9S_MB_2U(SCH_1):SW_PVCCFA_EHV_FIVRA_CPU1_BOOTR1
    1  SW_PVCCFA_EHV_FIVRA_CPU1_BOOT1_      A  @S9S_MB_2U_LIB.S9S_MB_2U(SCH_1):SW_PVCCFA_EHV_FIVRA_CPU1_BOOT1_R

Q_CAP  I241  PC402  [Q_CAP_C0402-100NF,50V,10%,X7R,A]
    2  SW_PVCCFA_EHV_FIVRA_CPU1_BOOTR2      B  @S9S_MB_2U_LIB.S9S_MB_2U(SCH_1):SW_PVCCFA_EHV_FIVRA_CPU1_BOOTR2
    1  SW_PVCCFA_EHV_FIVRA_CPU1_BOOT2_      A  @S9S_MB_2U_LIB.S9S_MB_2U(SCH_1):SW_PVCCFA_EHV_FIVRA_CPU1_BOOT2_R

Q_CAP  I258  PC403_P1_1  [Q_CAP_C0805-22UF,16V,20%,X6S,CA]
    1  SW_P12V_PVCCFA_EHV_FIVRA_CPU1_R      A  @S9S_MB_2U_LIB.S9S_MB_2U(SCH_1):SW_P12V_PVCCFA_EHV_FIVRA_CPU1_R
    2  GND                B  @S9S_MB_2U_LIB.S9S_MB_2U(SCH_1):GND

Q_CAP  I244  PC404_P1_2  [Q_CAP_C0805-22UF,16V,20%,X6S,CA]
    1  SW_P12V_PVCCFA_EHV_FIVRA_CPU1_L      A  @S9S_MB_2U_LIB.S9S_MB_2U(SCH_1):SW_P12V_PVCCFA_EHV_FIVRA_CPU1_L
    2  GND                B  @S9S_MB_2U_LIB.S9S_MB_2U(SCH_1):GND

Q_CAP  I259  PC405_P1_1  [Q_CAP_C0805-22UF,16V,20%,X6S,CA]
    1  SW_P12V_PVCCFA_EHV_FIVRA_CPU1_R      A  @S9S_MB_2U_LIB.S9S_MB_2U(SCH_1):SW_P12V_PVCCFA_EHV_FIVRA_CPU1_R
    2  GND                B  @S9S_MB_2U_LIB.S9S_MB_2U(SCH_1):GND

Q_CAP  I245  PC406_P1_2  [Q_CAP_C0805-22UF,16V,20%,X6S,CA]
    1  SW_P12V_PVCCFA_EHV_FIVRA_CPU1_L      A  @S9S_MB_2U_LIB.S9S_MB_2U(SCH_1):SW_P12V_PVCCFA_EHV_FIVRA_CPU1_L
    2  GND                B  @S9S_MB_2U_LIB.S9S_MB_2U(SCH_1):GND

Q_CAP  I282  PC408_P1_2  [Q_CAP_C0402-1UF,16V,10%,X6S,CHA]
    1  PVCCFA_EHV_FIVRA_CPU1      A  @S9S_MB_2U_LIB.S9S_MB_2U(SCH_1):PVCCFA_EHV_FIVRA_CPU1
    2  GND                B  @S9S_MB_2U_LIB.S9S_MB_2U(SCH_1):GND

Q_CAP  I265  PC410_P1_1  [Q_CAP_0805-22UF,4V,20%,X6S,TMPA]
    1  PVCCFA_EHV_FIVRA_CPU1      A  @S9S_MB_2U_LIB.S9S_MB_2U(SCH_1):PVCCFA_EHV_FIVRA_CPU1
    2  GND                B  @S9S_MB_2U_LIB.S9S_MB_2U(SCH_1):GND

Q_CAP  I248  PC411_P1_2  [Q_CAP_0805-22UF,4V,20%,X6S,TMPA]
    1  PVCCFA_EHV_FIVRA_CPU1      A  @S9S_MB_2U_LIB.S9S_MB_2U(SCH_1):PVCCFA_EHV_FIVRA_CPU1
    2  GND                B  @S9S_MB_2U_LIB.S9S_MB_2U(SCH_1):GND

Q_CAP  I268  PC412_P1_1  [Q_CAP_0805-22UF,4V,20%,X6S,TMPA]
    1  PVCCFA_EHV_FIVRA_CPU1      A  @S9S_MB_2U_LIB.S9S_MB_2U(SCH_1):PVCCFA_EHV_FIVRA_CPU1
    2  GND                B  @S9S_MB_2U_LIB.S9S_MB_2U(SCH_1):GND

Q_CAP  I249  PC413_P1_2  [Q_CAP_0805-22UF,4V,20%,X6S,TMPA]
    1  PVCCFA_EHV_FIVRA_CPU1      A  @S9S_MB_2U_LIB.S9S_MB_2U(SCH_1):PVCCFA_EHV_FIVRA_CPU1
    2  GND                B  @S9S_MB_2U_LIB.S9S_MB_2U(SCH_1):GND

Q_CAPP  I252  PC414  [Q_CAPP_THLF-560UF,2.5V,20%,OSCA]
    1  PVCCFA_EHV_FIVRA_CPU1      A  @S9S_MB_2U_LIB.S9S_MB_2U(SCH_1):PVCCFA_EHV_FIVRA_CPU1
    2  GND                B  @S9S_MB_2U_LIB.S9S_MB_2U(SCH_1):GND

Q_CAPP  I253  PC415  [Q_CAPP_THLF-560UF,2.5V,20%,OSCA]
    1  PVCCFA_EHV_FIVRA_CPU1      A  @S9S_MB_2U_LIB.S9S_MB_2U(SCH_1):PVCCFA_EHV_FIVRA_CPU1
    2  GND                B  @S9S_MB_2U_LIB.S9S_MB_2U(SCH_1):GND

Q_CAPP  I254  PC416  [Q_CAPP_THLF-560UF,2.5V,20%,OSCA]
    1  PVCCFA_EHV_FIVRA_CPU1      A  @S9S_MB_2U_LIB.S9S_MB_2U(SCH_1):PVCCFA_EHV_FIVRA_CPU1
    2  GND                B  @S9S_MB_2U_LIB.S9S_MB_2U(SCH_1):GND

Q_CAPP  I275  PC417  [Q_CAPP_THLF-270UF,16V,20%,OSCOA]
    1  SW_P12V_PVCCFA_EHV_FIVRA_CPU1_L      A  @S9S_MB_2U_LIB.S9S_MB_2U(SCH_1):SW_P12V_PVCCFA_EHV_FIVRA_CPU1_L
    2  GND                B  @S9S_MB_2U_LIB.S9S_MB_2U(SCH_1):GND

Q_CAPP  I270  PC418  [Q_CAPP_SMLF-470UF,2.5V,20%,SPCA]
    1  PVCCFA_EHV_FIVRA_CPU1      A  @S9S_MB_2U_LIB.S9S_MB_2U(SCH_1):PVCCFA_EHV_FIVRA_CPU1
    2  GND                B  @S9S_MB_2U_LIB.S9S_MB_2U(SCH_1):GND

Q_CAP  I206  PC420  [Q_CAP_0402-1000PF,50V,5%,X7R,TA]
    1  PVCCFA_EHV_FIVRA_CPU1_EN_R      A  @S9S_MB_2U_LIB.S9S_MB_2U(SCH_1):PVCCFA_EHV_FIVRA_CPU1_EN_R
    2  GND                B  @S9S_MB_2U_LIB.S9S_MB_2U(SCH_1):GND

Q_CAP  I205  PC421  [Q_CAP_0402-1000PF,50V,5%,EMPTYA]
    1  PWRGD_PVCCFA_EHV_FIVRA_CPU1_R      A  @S9S_MB_2U_LIB.S9S_MB_2U(SCH_1):PWRGD_PVCCFA_EHV_FIVRA_CPU1_R
    2  GND                B  @S9S_MB_2U_LIB.S9S_MB_2U(SCH_1):GND

Q_CAP  I219  PC422  [Q_CAP_0402-3300PF,50V,10%,X7R,A]
    2  VSENSE_PVCCFA_EHV_FIVRA_CPU1_DN      B  @S9S_MB_2U_LIB.S9S_MB_2U(SCH_1):VSENSE_PVCCFA_EHV_FIVRA_CPU1_DN
    1  SH_PVCCFA_EHV_FIVRA_CPU1_R      A  @S9S_MB_2U_LIB.S9S_MB_2U(SCH_1):SH_PVCCFA_EHV_FIVRA_CPU1_R

Q_CAP  I9   PC428  [Q_CAP_C0402-2.2UF,10V,10%,X6S,A]
    1  PVCCFA_EHV_CPU1_VDD1      A  @S9S_MB_2U_LIB.S9S_MB_2U(SCH_1):PVCCFA_EHV_CPU1_VDD1
    2  GND                B  @S9S_MB_2U_LIB.S9S_MB_2U(SCH_1):GND

Q_CAP  I20  PC429  [Q_CAP_0402-3300PF,50V,10%,X7R,A]
    1  SW_P12V_PVCCINFAON_CPU1_FLT      A  @S9S_MB_2U_LIB.S9S_MB_2U(SCH_1):SW_P12V_PVCCINFAON_CPU1_FLT
    2  GND                B  @S9S_MB_2U_LIB.S9S_MB_2U(SCH_1):GND

Q_CAP  I21  PC430  [Q_CAP_C0402-1UF,16V,10%,X6S,CHA]
    1  SW_P12V_PVCCINFAON_CPU1_FLT      A  @S9S_MB_2U_LIB.S9S_MB_2U(SCH_1):SW_P12V_PVCCINFAON_CPU1_FLT
    2  GND                B  @S9S_MB_2U_LIB.S9S_MB_2U(SCH_1):GND

Q_CAP  I24  PC431  [Q_CAP_C0402-100NF,50V,10%,X7R,A]
    2  SW_PVCCFA_EHV_CPU1_BOOTR1      B  @S9S_MB_2U_LIB.S9S_MB_2U(SCH_1):SW_PVCCFA_EHV_CPU1_BOOTR1
    1  SW_PVCCFA_EHV_CPU1_BOOT1_R      A  @S9S_MB_2U_LIB.S9S_MB_2U(SCH_1):SW_PVCCFA_EHV_CPU1_BOOT1_R

Q_CAP  I22  PC432  [Q_CAP_C0805-22UF,16V,20%,X6S,CA]
    1  SW_P12V_PVCCINFAON_CPU1_FLT      A  @S9S_MB_2U_LIB.S9S_MB_2U(SCH_1):SW_P12V_PVCCINFAON_CPU1_FLT
    2  GND                B  @S9S_MB_2U_LIB.S9S_MB_2U(SCH_1):GND

Q_CAP  I27  PC433  [Q_CAP_C0805-22UF,16V,20%,X6S,CA]
    1  SW_P12V_PVCCINFAON_CPU1_FLT      A  @S9S_MB_2U_LIB.S9S_MB_2U(SCH_1):SW_P12V_PVCCINFAON_CPU1_FLT
    2  GND                B  @S9S_MB_2U_LIB.S9S_MB_2U(SCH_1):GND

Q_CAP  I25  PC434  [Q_CAP_C0402-100NF,50V,10%,X7R,A]
    1  PVCCFA_EHV_CPU1      A  @S9S_MB_2U_LIB.S9S_MB_2U(SCH_1):PVCCFA_EHV_CPU1
    2  GND                B  @S9S_MB_2U_LIB.S9S_MB_2U(SCH_1):GND

Q_CAP  I30  PC435  [Q_CAP_0805-22UF,4V,20%,X6S,TMPA]
    1  PVCCFA_EHV_CPU1      A  @S9S_MB_2U_LIB.S9S_MB_2U(SCH_1):PVCCFA_EHV_CPU1
    2  GND                B  @S9S_MB_2U_LIB.S9S_MB_2U(SCH_1):GND

Q_CAP  I31  PC437  [Q_CAP_0805-22UF,4V,20%,X6S,TMPA]
    1  PVCCFA_EHV_CPU1      A  @S9S_MB_2U_LIB.S9S_MB_2U(SCH_1):PVCCFA_EHV_CPU1
    2  GND                B  @S9S_MB_2U_LIB.S9S_MB_2U(SCH_1):GND

Q_CAP  I26  PC440  [Q_CAP_C0402-2.2UF,10V,10%,X6S,A]
    1  PVCCINFAON_CPU1_VDD1      A  @S9S_MB_2U_LIB.S9S_MB_2U(SCH_1):PVCCINFAON_CPU1_VDD1
    2  GND                B  @S9S_MB_2U_LIB.S9S_MB_2U(SCH_1):GND

Q_CAP  I14  PC441  [Q_CAP_C0402-2.2UF,10V,10%,X6S,A]
    1  PVCCINFAON_CPU1_VDD2      A  @S9S_MB_2U_LIB.S9S_MB_2U(SCH_1):PVCCINFAON_CPU1_VDD2
    2  GND                B  @S9S_MB_2U_LIB.S9S_MB_2U(SCH_1):GND

Q_CAP  I50  PC442_P1_1  [Q_CAP_0402-3300PF,50V,10%,X7R,A]
    1  SW_P12V_PVCCINFAON_CPU1_FLT      A  @S9S_MB_2U_LIB.S9S_MB_2U(SCH_1):SW_P12V_PVCCINFAON_CPU1_FLT
    2  GND                B  @S9S_MB_2U_LIB.S9S_MB_2U(SCH_1):GND

Q_CAP  I34  PC443_P1_2  [Q_CAP_0402-3300PF,50V,10%,X7R,A]
    1  SW_P12V_PVCCINFAON_CPU1_FLT      A  @S9S_MB_2U_LIB.S9S_MB_2U(SCH_1):SW_P12V_PVCCINFAON_CPU1_FLT
    2  GND                B  @S9S_MB_2U_LIB.S9S_MB_2U(SCH_1):GND

Q_CAP  I51  PC444_P1_1  [Q_CAP_C0402-1UF,16V,10%,X6S,CHA]
    1  SW_P12V_PVCCINFAON_CPU1_FLT      A  @S9S_MB_2U_LIB.S9S_MB_2U(SCH_1):SW_P12V_PVCCINFAON_CPU1_FLT
    2  GND                B  @S9S_MB_2U_LIB.S9S_MB_2U(SCH_1):GND

Q_CAP  I36  PC445_P1_2  [Q_CAP_C0402-1UF,16V,10%,X6S,CHA]
    1  SW_P12V_PVCCINFAON_CPU1_FLT      A  @S9S_MB_2U_LIB.S9S_MB_2U(SCH_1):SW_P12V_PVCCINFAON_CPU1_FLT
    2  GND                B  @S9S_MB_2U_LIB.S9S_MB_2U(SCH_1):GND

Q_CAP  I54  PC446  [Q_CAP_C0402-100NF,50V,10%,X7R,A]
    2  SW_PVCCINFAON_CPU1_BOOTR1      B  @S9S_MB_2U_LIB.S9S_MB_2U(SCH_1):SW_PVCCINFAON_CPU1_BOOTR1
    1  SW_PVCCINFAON_CPU1_BOOT1_R      A  @S9S_MB_2U_LIB.S9S_MB_2U(SCH_1):SW_PVCCINFAON_CPU1_BOOT1_R

Q_CAP  I40  PC447  [Q_CAP_C0402-100NF,50V,10%,X7R,A]
    2  SW_PVCCINFAON_CPU1_BOOTR2      B  @S9S_MB_2U_LIB.S9S_MB_2U(SCH_1):SW_PVCCINFAON_CPU1_BOOTR2
    1  SW_PVCCINFAON_CPU1_BOOT2_R      A  @S9S_MB_2U_LIB.S9S_MB_2U(SCH_1):SW_PVCCINFAON_CPU1_BOOT2_R

Q_CAP  I56  PC448_P1_1  [Q_CAP_C0805-22UF,16V,20%,X6S,CA]
    1  SW_P12V_PVCCINFAON_CPU1_FLT      A  @S9S_MB_2U_LIB.S9S_MB_2U(SCH_1):SW_P12V_PVCCINFAON_CPU1_FLT
    2  GND                B  @S9S_MB_2U_LIB.S9S_MB_2U(SCH_1):GND

Q_CAP  I38  PC449_P1_2  [Q_CAP_C0805-22UF,16V,20%,X6S,CA]
    1  SW_P12V_PVCCINFAON_CPU1_FLT      A  @S9S_MB_2U_LIB.S9S_MB_2U(SCH_1):SW_P12V_PVCCINFAON_CPU1_FLT
    2  GND                B  @S9S_MB_2U_LIB.S9S_MB_2U(SCH_1):GND

Q_CAP  I57  PC450_P1_1  [Q_CAP_C0805-22UF,16V,20%,X6S,CA]
    1  SW_P12V_PVCCINFAON_CPU1_FLT      A  @S9S_MB_2U_LIB.S9S_MB_2U(SCH_1):SW_P12V_PVCCINFAON_CPU1_FLT
    2  GND                B  @S9S_MB_2U_LIB.S9S_MB_2U(SCH_1):GND

Q_CAP  I39  PC451_P1_2  [Q_CAP_C0805-22UF,16V,20%,X6S,CA]
    1  SW_P12V_PVCCINFAON_CPU1_FLT      A  @S9S_MB_2U_LIB.S9S_MB_2U(SCH_1):SW_P12V_PVCCINFAON_CPU1_FLT
    2  GND                B  @S9S_MB_2U_LIB.S9S_MB_2U(SCH_1):GND

Q_CAP  I58  PC452_P1_1  [Q_CAP_C0402-100NF,50V,10%,X7R,A]
    1  PVCCINFAON_CPU1      A  @S9S_MB_2U_LIB.S9S_MB_2U(SCH_1):PVCCINFAON_CPU1
    2  GND                B  @S9S_MB_2U_LIB.S9S_MB_2U(SCH_1):GND

Q_CAP  I59  PC455_P1_1  [Q_CAP_0805-22UF,4V,20%,X6S,TMPA]
    1  PVCCINFAON_CPU1      A  @S9S_MB_2U_LIB.S9S_MB_2U(SCH_1):PVCCINFAON_CPU1
    2  GND                B  @S9S_MB_2U_LIB.S9S_MB_2U(SCH_1):GND

Q_CAP  I41  PC456_P1_2  [Q_CAP_0805-22UF,4V,20%,X6S,TMPA]
    1  PVCCINFAON_CPU1      A  @S9S_MB_2U_LIB.S9S_MB_2U(SCH_1):PVCCINFAON_CPU1
    2  GND                B  @S9S_MB_2U_LIB.S9S_MB_2U(SCH_1):GND

Q_CAP  I62  PC457_P1_1  [Q_CAP_0805-22UF,4V,20%,X6S,TMPA]
    1  PVCCINFAON_CPU1      A  @S9S_MB_2U_LIB.S9S_MB_2U(SCH_1):PVCCINFAON_CPU1
    2  GND                B  @S9S_MB_2U_LIB.S9S_MB_2U(SCH_1):GND

Q_CAP  I43  PC458_P1_2  [Q_CAP_0805-22UF,4V,20%,X6S,TMPA]
    1  PVCCINFAON_CPU1      A  @S9S_MB_2U_LIB.S9S_MB_2U(SCH_1):PVCCINFAON_CPU1
    2  GND                B  @S9S_MB_2U_LIB.S9S_MB_2U(SCH_1):GND

Q_CAPP  I74  PC460  [Q_CAPP_THLF-270UF,16V,20%,OSCOA]
    1  SW_P12V_PVCCINFAON_CPU1_FLT      A  @S9S_MB_2U_LIB.S9S_MB_2U(SCH_1):SW_P12V_PVCCINFAON_CPU1_FLT
    2  GND                B  @S9S_MB_2U_LIB.S9S_MB_2U(SCH_1):GND

Q_CAPP  I75  PC461  [Q_CAPP_THLF-270UF,16V,20%,OSCOA]
    1  SW_P12V_PVCCINFAON_CPU1_FLT      A  @S9S_MB_2U_LIB.S9S_MB_2U(SCH_1):SW_P12V_PVCCINFAON_CPU1_FLT
    2  GND                B  @S9S_MB_2U_LIB.S9S_MB_2U(SCH_1):GND

Q_CAP  I54  PC467  [Q_CAP_0402-0.1UF,25V,10%,EMPTYA]
    1  PVCCINFAON_CPU1_CSPIN      A  @S9S_MB_2U_LIB.S9S_MB_2U(SCH_1):PVCCINFAON_CPU1_CSPIN
    2  GND                B  @S9S_MB_2U_LIB.S9S_MB_2U(SCH_1):GND

Q_CAP  I65  PC468  [Q_CAP_0402-3300PF,50V,10%,X7R,A]
    2  VSENSE_PVCCINFAON_CPU1_DN      B  @S9S_MB_2U_LIB.S9S_MB_2U(SCH_1):VSENSE_PVCCINFAON_CPU1_DN
    1  SH_PVCCINFAON_CPU1_R      A  @S9S_MB_2U_LIB.S9S_MB_2U(SCH_1):SH_PVCCINFAON_CPU1_R

Q_CAP  I64  PC469  [Q_CAP_0402-3300PF,50V,10%,X7R,A]
    2  VSENSE_PVCCFA_EHV_CPU1_DN      B  @S9S_MB_2U_LIB.S9S_MB_2U(SCH_1):VSENSE_PVCCFA_EHV_CPU1_DN
    1  SH_PVCCFA_EHV_CPU1_R      A  @S9S_MB_2U_LIB.S9S_MB_2U(SCH_1):SH_PVCCFA_EHV_CPU1_R

Q_CAP  I74  PC470  [Q_CAP_0402-1000PF,50V,5%,X7R,TA]
    1  PVCCINFAON_CPU1_EN_R      A  @S9S_MB_2U_LIB.S9S_MB_2U(SCH_1):PVCCINFAON_CPU1_EN_R
    2  GND                B  @S9S_MB_2U_LIB.S9S_MB_2U(SCH_1):GND

Q_CAP  I76  PC471  [Q_CAP_0402-1000PF,50V,5%,EMPTYA]
    1  PWRGD_PVCCINFAON_CPU1_R      A  @S9S_MB_2U_LIB.S9S_MB_2U(SCH_1):PWRGD_PVCCINFAON_CPU1_R
    2  GND                B  @S9S_MB_2U_LIB.S9S_MB_2U(SCH_1):GND

Q_CAP  I59  PC472  [Q_CAP_0402-1000PF,50V,5%,X7R,TA]
    1  PVCCFA_EHV_CPU1_EN_R      A  @S9S_MB_2U_LIB.S9S_MB_2U(SCH_1):PVCCFA_EHV_CPU1_EN_R
    2  GND                B  @S9S_MB_2U_LIB.S9S_MB_2U(SCH_1):GND

Q_CAP  I58  PC473  [Q_CAP_0402-1000PF,50V,5%,EMPTYA]
    1  PWRGD_PVCCFA_EHV_CPU1_R      A  @S9S_MB_2U_LIB.S9S_MB_2U(SCH_1):PWRGD_PVCCFA_EHV_CPU1_R
    2  GND                B  @S9S_MB_2U_LIB.S9S_MB_2U(SCH_1):GND

Q_CAP  I57  PC474  [Q_CAP_0402-0.1UF,25V,10%,X7R,CA]
    1  PVCCINFAON_CPU1_VIN_CSNIN      A  @S9S_MB_2U_LIB.S9S_MB_2U(SCH_1):PVCCINFAON_CPU1_VIN_CSNIN
    2  GND                B  @S9S_MB_2U_LIB.S9S_MB_2U(SCH_1):GND

Q_CAP  I67  PC475  [Q_CAP_0402-470PF,50V,10%,X7R,TA]
    1  PVCCINFAON_CPU1_ATSEN      A  @S9S_MB_2U_LIB.S9S_MB_2U(SCH_1):PVCCINFAON_CPU1_ATSEN
    2  GND                B  @S9S_MB_2U_LIB.S9S_MB_2U(SCH_1):GND

Q_CAP  I82  PC476  [Q_CAP_C0402-100NF,50V,10%,EMPTA]
    1  PVCCINFAON_CPU1_VCC      A  @S9S_MB_2U_LIB.S9S_MB_2U(SCH_1):PVCCINFAON_CPU1_VCC
    2  GND                B  @S9S_MB_2U_LIB.S9S_MB_2U(SCH_1):GND

Q_CAP  I80  PC477  [Q_CAP_0402-4.7UF,6.3V,20%,X6S,A]
    1  PVCCINFAON_CPU1_VREF      A  @S9S_MB_2U_LIB.S9S_MB_2U(SCH_1):PVCCINFAON_CPU1_VREF
    2  GND                B  @S9S_MB_2U_LIB.S9S_MB_2U(SCH_1):GND

Q_CAP  I83  PC478  [Q_CAP_C0402-1UF,16V,10%,X6S,CHA]
    1  PVCCINFAON_CPU1_VCC      A  @S9S_MB_2U_LIB.S9S_MB_2U(SCH_1):PVCCINFAON_CPU1_VCC
    2  GND                B  @S9S_MB_2U_LIB.S9S_MB_2U(SCH_1):GND

Q_CAP  I25  PC479  [Q_CAP_C0402-2.2UF,10V,10%,X6S,A]
    1  PVCCIN_CPU1_VDD8      A  @S9S_MB_2U_LIB.S9S_MB_2U(SCH_1):PVCCIN_CPU1_VDD8
    2  GND                B  @S9S_MB_2U_LIB.S9S_MB_2U(SCH_1):GND

Q_CAP  I32  PC480  [Q_CAP_C0402-2.2UF,10V,10%,X6S,A]
    1  PVCCIN_CPU1_VDD7      A  @S9S_MB_2U_LIB.S9S_MB_2U(SCH_1):PVCCIN_CPU1_VDD7
    2  GND                B  @S9S_MB_2U_LIB.S9S_MB_2U(SCH_1):GND

Q_CAP  I28  PC481_P1_8  [Q_CAP_C0402-2.2UF,10V,10%,X6S,A]
    1  PVCCIN_CPU1_PVCC      A  @S9S_MB_2U_LIB.S9S_MB_2U(SCH_1):PVCCIN_CPU1_PVCC
    2  GND                B  @S9S_MB_2U_LIB.S9S_MB_2U(SCH_1):GND

Q_CAP  I36  PC482_P1_7  [Q_CAP_C0402-2.2UF,10V,10%,X6S,A]
    1  PVCCIN_CPU1_PVCC      A  @S9S_MB_2U_LIB.S9S_MB_2U(SCH_1):PVCCIN_CPU1_PVCC
    2  GND                B  @S9S_MB_2U_LIB.S9S_MB_2U(SCH_1):GND

Q_CAP  I38  PC483_P1_8  [Q_CAP_0402-3300PF,50V,10%,X7R,A]
    1  SW_P12V_PVCCIN_CPU1_FLT      A  @S9S_MB_2U_LIB.S9S_MB_2U(SCH_1):SW_P12V_PVCCIN_CPU1_FLT
    2  GND                B  @S9S_MB_2U_LIB.S9S_MB_2U(SCH_1):GND

Q_CAP  I46  PC484_P1_7  [Q_CAP_0402-3300PF,50V,10%,X7R,A]
    1  SW_P12V_PVCCIN_CPU1_FLT      A  @S9S_MB_2U_LIB.S9S_MB_2U(SCH_1):SW_P12V_PVCCIN_CPU1_FLT
    2  GND                B  @S9S_MB_2U_LIB.S9S_MB_2U(SCH_1):GND

Q_CAP  I40  PC485_P1_8  [Q_CAP_C0402-1UF,16V,10%,X6S,CHA]
    1  SW_P12V_PVCCIN_CPU1_FLT      A  @S9S_MB_2U_LIB.S9S_MB_2U(SCH_1):SW_P12V_PVCCIN_CPU1_FLT
    2  GND                B  @S9S_MB_2U_LIB.S9S_MB_2U(SCH_1):GND

Q_CAP  I48  PC486_P1_7  [Q_CAP_C0402-1UF,16V,10%,X6S,CHA]
    1  SW_P12V_PVCCIN_CPU1_FLT      A  @S9S_MB_2U_LIB.S9S_MB_2U(SCH_1):SW_P12V_PVCCIN_CPU1_FLT
    2  GND                B  @S9S_MB_2U_LIB.S9S_MB_2U(SCH_1):GND

Q_CAP  I41  PC487  [Q_CAP_C0402-100NF,50V,10%,X7R,A]
    2  SW_PVCCIN_CPU1_BOOTR8      B  @S9S_MB_2U_LIB.S9S_MB_2U(SCH_1):SW_PVCCIN_CPU1_BOOTR8
    1  SW_PVCCIN_CPU1_BOOT8_R      A  @S9S_MB_2U_LIB.S9S_MB_2U(SCH_1):SW_PVCCIN_CPU1_BOOT8_R

Q_CAP  I49  PC488  [Q_CAP_C0402-100NF,50V,10%,X7R,A]
    2  SW_PVCCIN_CPU1_BOOTR7      B  @S9S_MB_2U_LIB.S9S_MB_2U(SCH_1):SW_PVCCIN_CPU1_BOOTR7
    1  SW_PVCCIN_CPU1_BOOT7_R      A  @S9S_MB_2U_LIB.S9S_MB_2U(SCH_1):SW_PVCCIN_CPU1_BOOT7_R

Q_CAP  I42  PC489_P1_8  [Q_CAP_C0805-22UF,16V,20%,X6S,CA]
    1  SW_P12V_PVCCIN_CPU1_FLT      A  @S9S_MB_2U_LIB.S9S_MB_2U(SCH_1):SW_P12V_PVCCIN_CPU1_FLT
    2  GND                B  @S9S_MB_2U_LIB.S9S_MB_2U(SCH_1):GND

Q_CAP  I52  PC490_P1_7  [Q_CAP_C0805-22UF,16V,20%,X6S,CA]
    1  SW_P12V_PVCCIN_CPU1_FLT      A  @S9S_MB_2U_LIB.S9S_MB_2U(SCH_1):SW_P12V_PVCCIN_CPU1_FLT
    2  GND                B  @S9S_MB_2U_LIB.S9S_MB_2U(SCH_1):GND

Q_CAP  I43  PC491_P1_8  [Q_CAP_C0805-22UF,16V,20%,X6S,CA]
    1  SW_P12V_PVCCIN_CPU1_FLT      A  @S9S_MB_2U_LIB.S9S_MB_2U(SCH_1):SW_P12V_PVCCIN_CPU1_FLT
    2  GND                B  @S9S_MB_2U_LIB.S9S_MB_2U(SCH_1):GND

Q_CAP  I53  PC492_P1_7  [Q_CAP_C0805-22UF,16V,20%,X6S,CA]
    1  SW_P12V_PVCCIN_CPU1_FLT      A  @S9S_MB_2U_LIB.S9S_MB_2U(SCH_1):SW_P12V_PVCCIN_CPU1_FLT
    2  GND                B  @S9S_MB_2U_LIB.S9S_MB_2U(SCH_1):GND

Q_CAP  I44  PC493_P1_8  [Q_CAP_C0805-22UF,16V,20%,X6S,CA]
    1  SW_P12V_PVCCIN_CPU1_FLT      A  @S9S_MB_2U_LIB.S9S_MB_2U(SCH_1):SW_P12V_PVCCIN_CPU1_FLT
    2  GND                B  @S9S_MB_2U_LIB.S9S_MB_2U(SCH_1):GND

Q_CAP  I54  PC494_P1_7  [Q_CAP_C0805-22UF,16V,20%,X6S,CA]
    1  SW_P12V_PVCCIN_CPU1_FLT      A  @S9S_MB_2U_LIB.S9S_MB_2U(SCH_1):SW_P12V_PVCCIN_CPU1_FLT
    2  GND                B  @S9S_MB_2U_LIB.S9S_MB_2U(SCH_1):GND

Q_CAP  I103  PC495_P1_8  [Q_CAP_C0402-1UF,16V,10%,X6S,CHA]
    1  PVCCIN_CPU1        A  @S9S_MB_2U_LIB.S9S_MB_2U(SCH_1):PVCCIN_CPU1
    2  GND                B  @S9S_MB_2U_LIB.S9S_MB_2U(SCH_1):GND

Q_CAP  I84  PC496_P1_7  [Q_CAP_C0402-1UF,16V,10%,X6S,CHA]
    1  PVCCIN_CPU1        A  @S9S_MB_2U_LIB.S9S_MB_2U(SCH_1):PVCCIN_CPU1
    2  GND                B  @S9S_MB_2U_LIB.S9S_MB_2U(SCH_1):GND

Q_CAP  I102  PC497_P1_8  [Q_CAP_0805-22UF,4V,20%,X6S,TMPA]
    1  PVCCIN_CPU1        A  @S9S_MB_2U_LIB.S9S_MB_2U(SCH_1):PVCCIN_CPU1
    2  GND                B  @S9S_MB_2U_LIB.S9S_MB_2U(SCH_1):GND

Q_CAP  I83  PC498_P1_7  [Q_CAP_0805-22UF,4V,20%,X6S,TMPA]
    1  PVCCIN_CPU1        A  @S9S_MB_2U_LIB.S9S_MB_2U(SCH_1):PVCCIN_CPU1
    2  GND                B  @S9S_MB_2U_LIB.S9S_MB_2U(SCH_1):GND

Q_CAP  I101  PC499_P1_8  [Q_CAP_0805-22UF,4V,20%,X6S,TMPA]
    1  PVCCIN_CPU1        A  @S9S_MB_2U_LIB.S9S_MB_2U(SCH_1):PVCCIN_CPU1
    2  GND                B  @S9S_MB_2U_LIB.S9S_MB_2U(SCH_1):GND

Q_CAP  I81  PC500_P1_7  [Q_CAP_0805-22UF,4V,20%,X6S,TMPA]
    1  PVCCIN_CPU1        A  @S9S_MB_2U_LIB.S9S_MB_2U(SCH_1):PVCCIN_CPU1
    2  GND                B  @S9S_MB_2U_LIB.S9S_MB_2U(SCH_1):GND

Q_CAP  I8   PC501  [Q_CAP_C0402-2.2UF,10V,10%,X6S,A]
    1  PVCCIN_CPU1_VDD6      A  @S9S_MB_2U_LIB.S9S_MB_2U(SCH_1):PVCCIN_CPU1_VDD6
    2  GND                B  @S9S_MB_2U_LIB.S9S_MB_2U(SCH_1):GND

Q_CAP  I20  PC502  [Q_CAP_C0402-2.2UF,10V,10%,X6S,A]
    1  PVCCIN_CPU1_VDD5      A  @S9S_MB_2U_LIB.S9S_MB_2U(SCH_1):PVCCIN_CPU1_VDD5
    2  GND                B  @S9S_MB_2U_LIB.S9S_MB_2U(SCH_1):GND

Q_CAP  I29  PC503_P1_6  [Q_CAP_C0402-2.2UF,10V,10%,X6S,A]
    1  PVCCIN_CPU1_PVCC      A  @S9S_MB_2U_LIB.S9S_MB_2U(SCH_1):PVCCIN_CPU1_PVCC
    2  GND                B  @S9S_MB_2U_LIB.S9S_MB_2U(SCH_1):GND

Q_CAP  I34  PC504_P1_5  [Q_CAP_C0402-2.2UF,10V,10%,X6S,A]
    1  PVCCIN_CPU1_PVCC      A  @S9S_MB_2U_LIB.S9S_MB_2U(SCH_1):PVCCIN_CPU1_PVCC
    2  GND                B  @S9S_MB_2U_LIB.S9S_MB_2U(SCH_1):GND

Q_CAP  I37  PC505_P1_6  [Q_CAP_0402-3300PF,50V,10%,X7R,A]
    1  SW_P12V_PVCCIN_CPU1_FLT      A  @S9S_MB_2U_LIB.S9S_MB_2U(SCH_1):SW_P12V_PVCCIN_CPU1_FLT
    2  GND                B  @S9S_MB_2U_LIB.S9S_MB_2U(SCH_1):GND

Q_CAP  I48  PC506_P1_5  [Q_CAP_0402-3300PF,50V,10%,X7R,A]
    1  SW_P12V_PVCCIN_CPU1_FLT      A  @S9S_MB_2U_LIB.S9S_MB_2U(SCH_1):SW_P12V_PVCCIN_CPU1_FLT
    2  GND                B  @S9S_MB_2U_LIB.S9S_MB_2U(SCH_1):GND

Q_CAP  I38  PC507_P1_6  [Q_CAP_C0402-1UF,16V,10%,X6S,CHA]
    1  SW_P12V_PVCCIN_CPU1_FLT      A  @S9S_MB_2U_LIB.S9S_MB_2U(SCH_1):SW_P12V_PVCCIN_CPU1_FLT
    2  GND                B  @S9S_MB_2U_LIB.S9S_MB_2U(SCH_1):GND

Q_CAP  I49  PC508_P1_5  [Q_CAP_C0402-1UF,16V,10%,X6S,CHA]
    1  SW_P12V_PVCCIN_CPU1_FLT      A  @S9S_MB_2U_LIB.S9S_MB_2U(SCH_1):SW_P12V_PVCCIN_CPU1_FLT
    2  GND                B  @S9S_MB_2U_LIB.S9S_MB_2U(SCH_1):GND

Q_CAP  I41  PC509  [Q_CAP_C0402-100NF,50V,10%,X7R,A]
    2  SW_PVCCIN_CPU1_BOOTR6      B  @S9S_MB_2U_LIB.S9S_MB_2U(SCH_1):SW_PVCCIN_CPU1_BOOTR6
    1  SW_PVCCIN_CPU1_BOOT6_R      A  @S9S_MB_2U_LIB.S9S_MB_2U(SCH_1):SW_PVCCIN_CPU1_BOOT6_R

Q_CAP  I53  PC510  [Q_CAP_C0402-100NF,50V,10%,X7R,A]
    2  SW_PVCCIN_CPU1_BOOTR5      B  @S9S_MB_2U_LIB.S9S_MB_2U(SCH_1):SW_PVCCIN_CPU1_BOOTR5
    1  SW_PVCCIN_CPU1_BOOT5_R      A  @S9S_MB_2U_LIB.S9S_MB_2U(SCH_1):SW_PVCCIN_CPU1_BOOT5_R

Q_CAP  I39  PC511_P1_6  [Q_CAP_C0805-22UF,16V,20%,X6S,CA]
    1  SW_P12V_PVCCIN_CPU1_FLT      A  @S9S_MB_2U_LIB.S9S_MB_2U(SCH_1):SW_P12V_PVCCIN_CPU1_FLT
    2  GND                B  @S9S_MB_2U_LIB.S9S_MB_2U(SCH_1):GND

Q_CAP  I50  PC512_P1_5  [Q_CAP_C0805-22UF,16V,20%,X6S,CA]
    1  SW_P12V_PVCCIN_CPU1_FLT      A  @S9S_MB_2U_LIB.S9S_MB_2U(SCH_1):SW_P12V_PVCCIN_CPU1_FLT
    2  GND                B  @S9S_MB_2U_LIB.S9S_MB_2U(SCH_1):GND

Q_CAP  I44  PC513_P1_6  [Q_CAP_C0805-22UF,16V,20%,X6S,CA]
    1  SW_P12V_PVCCIN_CPU1_FLT      A  @S9S_MB_2U_LIB.S9S_MB_2U(SCH_1):SW_P12V_PVCCIN_CPU1_FLT
    2  GND                B  @S9S_MB_2U_LIB.S9S_MB_2U(SCH_1):GND

Q_CAP  I54  PC514_P1_5  [Q_CAP_C0805-22UF,16V,20%,X6S,CA]
    1  SW_P12V_PVCCIN_CPU1_FLT      A  @S9S_MB_2U_LIB.S9S_MB_2U(SCH_1):SW_P12V_PVCCIN_CPU1_FLT
    2  GND                B  @S9S_MB_2U_LIB.S9S_MB_2U(SCH_1):GND

Q_CAP  I45  PC515_P1_6  [Q_CAP_C0805-22UF,16V,20%,X6S,CA]
    1  SW_P12V_PVCCIN_CPU1_FLT      A  @S9S_MB_2U_LIB.S9S_MB_2U(SCH_1):SW_P12V_PVCCIN_CPU1_FLT
    2  GND                B  @S9S_MB_2U_LIB.S9S_MB_2U(SCH_1):GND

Q_CAP  I56  PC516_P1_5  [Q_CAP_C0805-22UF,16V,20%,X6S,CA]
    1  SW_P12V_PVCCIN_CPU1_FLT      A  @S9S_MB_2U_LIB.S9S_MB_2U(SCH_1):SW_P12V_PVCCIN_CPU1_FLT
    2  GND                B  @S9S_MB_2U_LIB.S9S_MB_2U(SCH_1):GND

Q_CAP  I95  PC519_P1_6  [Q_CAP_0805-22UF,4V,20%,X6S,TMPA]
    1  PVCCIN_CPU1        A  @S9S_MB_2U_LIB.S9S_MB_2U(SCH_1):PVCCIN_CPU1
    2  GND                B  @S9S_MB_2U_LIB.S9S_MB_2U(SCH_1):GND

Q_CAP  I79  PC520_P1_5  [Q_CAP_0805-22UF,4V,20%,X6S,TMPA]
    1  PVCCIN_CPU1        A  @S9S_MB_2U_LIB.S9S_MB_2U(SCH_1):PVCCIN_CPU1
    2  GND                B  @S9S_MB_2U_LIB.S9S_MB_2U(SCH_1):GND

Q_CAP  I94  PC521_P1_6  [Q_CAP_0805-22UF,4V,20%,X6S,TMPA]
    1  PVCCIN_CPU1        A  @S9S_MB_2U_LIB.S9S_MB_2U(SCH_1):PVCCIN_CPU1
    2  GND                B  @S9S_MB_2U_LIB.S9S_MB_2U(SCH_1):GND

Q_CAP  I78  PC522_P1_5  [Q_CAP_0805-22UF,4V,20%,X6S,TMPA]
    1  PVCCIN_CPU1        A  @S9S_MB_2U_LIB.S9S_MB_2U(SCH_1):PVCCIN_CPU1
    2  GND                B  @S9S_MB_2U_LIB.S9S_MB_2U(SCH_1):GND

Q_CAP  I11  PC523  [Q_CAP_C0402-2.2UF,10V,10%,X6S,A]
    1  PVCCIN_CPU1_VDD4      A  @S9S_MB_2U_LIB.S9S_MB_2U(SCH_1):PVCCIN_CPU1_VDD4
    2  GND                B  @S9S_MB_2U_LIB.S9S_MB_2U(SCH_1):GND

Q_CAP  I26  PC524  [Q_CAP_C0402-2.2UF,10V,10%,X6S,A]
    1  PVCCIN_CPU1_VDD3      A  @S9S_MB_2U_LIB.S9S_MB_2U(SCH_1):PVCCIN_CPU1_VDD3
    2  GND                B  @S9S_MB_2U_LIB.S9S_MB_2U(SCH_1):GND

Q_CAP  I16  PC525_P1_4  [Q_CAP_C0402-2.2UF,10V,10%,X6S,A]
    1  PVCCIN_CPU1_PVCC      A  @S9S_MB_2U_LIB.S9S_MB_2U(SCH_1):PVCCIN_CPU1_PVCC
    2  GND                B  @S9S_MB_2U_LIB.S9S_MB_2U(SCH_1):GND

Q_CAP  I30  PC526_P1_3  [Q_CAP_C0402-2.2UF,10V,10%,X6S,A]
    1  PVCCIN_CPU1_PVCC      A  @S9S_MB_2U_LIB.S9S_MB_2U(SCH_1):PVCCIN_CPU1_PVCC
    2  GND                B  @S9S_MB_2U_LIB.S9S_MB_2U(SCH_1):GND

Q_CAP  I32  PC527_P1_4  [Q_CAP_0402-3300PF,50V,10%,X7R,A]
    1  SW_P12V_PVCCIN_CPU1_FLT      A  @S9S_MB_2U_LIB.S9S_MB_2U(SCH_1):SW_P12V_PVCCIN_CPU1_FLT
    2  GND                B  @S9S_MB_2U_LIB.S9S_MB_2U(SCH_1):GND

Q_CAP  I46  PC528_P1_3  [Q_CAP_0402-3300PF,50V,10%,X7R,A]
    1  SW_P12V_PVCCIN_CPU1_FLT      A  @S9S_MB_2U_LIB.S9S_MB_2U(SCH_1):SW_P12V_PVCCIN_CPU1_FLT
    2  GND                B  @S9S_MB_2U_LIB.S9S_MB_2U(SCH_1):GND

Q_CAP  I35  PC529_P1_4  [Q_CAP_C0402-1UF,16V,10%,X6S,CHA]
    1  SW_P12V_PVCCIN_CPU1_FLT      A  @S9S_MB_2U_LIB.S9S_MB_2U(SCH_1):SW_P12V_PVCCIN_CPU1_FLT
    2  GND                B  @S9S_MB_2U_LIB.S9S_MB_2U(SCH_1):GND

Q_CAP  I48  PC530_P1_3  [Q_CAP_C0402-1UF,16V,10%,X6S,CHA]
    1  SW_P12V_PVCCIN_CPU1_FLT      A  @S9S_MB_2U_LIB.S9S_MB_2U(SCH_1):SW_P12V_PVCCIN_CPU1_FLT
    2  GND                B  @S9S_MB_2U_LIB.S9S_MB_2U(SCH_1):GND

Q_CAP  I41  PC531  [Q_CAP_C0402-100NF,50V,10%,X7R,A]
    2  SW_PVCCIN_CPU1_BOOTR4      B  @S9S_MB_2U_LIB.S9S_MB_2U(SCH_1):SW_PVCCIN_CPU1_BOOTR4
    1  SW_PVCCIN_CPU1_BOOT4_R      A  @S9S_MB_2U_LIB.S9S_MB_2U(SCH_1):SW_PVCCIN_CPU1_BOOT4_R

Q_CAP  I52  PC532  [Q_CAP_C0402-100NF,50V,10%,X7R,A]
    2  SW_PVCCIN_CPU1_BOOTR3      B  @S9S_MB_2U_LIB.S9S_MB_2U(SCH_1):SW_PVCCIN_CPU1_BOOTR3
    1  SW_PVCCIN_CPU1_BOOT3_R      A  @S9S_MB_2U_LIB.S9S_MB_2U(SCH_1):SW_PVCCIN_CPU1_BOOT3_R

Q_CAP  I36  PC533_P1_4  [Q_CAP_C0805-22UF,16V,20%,X6S,CA]
    1  SW_P12V_PVCCIN_CPU1_FLT      A  @S9S_MB_2U_LIB.S9S_MB_2U(SCH_1):SW_P12V_PVCCIN_CPU1_FLT
    2  GND                B  @S9S_MB_2U_LIB.S9S_MB_2U(SCH_1):GND

Q_CAP  I49  PC534_P1_3  [Q_CAP_C0805-22UF,16V,20%,X6S,CA]
    1  SW_P12V_PVCCIN_CPU1_FLT      A  @S9S_MB_2U_LIB.S9S_MB_2U(SCH_1):SW_P12V_PVCCIN_CPU1_FLT
    2  GND                B  @S9S_MB_2U_LIB.S9S_MB_2U(SCH_1):GND

Q_CAP  I42  PC535_P1_4  [Q_CAP_C0805-22UF,16V,20%,X6S,CA]
    1  SW_P12V_PVCCIN_CPU1_FLT      A  @S9S_MB_2U_LIB.S9S_MB_2U(SCH_1):SW_P12V_PVCCIN_CPU1_FLT
    2  GND                B  @S9S_MB_2U_LIB.S9S_MB_2U(SCH_1):GND

Q_CAP  I53  PC536_P1_3  [Q_CAP_C0805-22UF,16V,20%,X6S,CA]
    1  SW_P12V_PVCCIN_CPU1_FLT      A  @S9S_MB_2U_LIB.S9S_MB_2U(SCH_1):SW_P12V_PVCCIN_CPU1_FLT
    2  GND                B  @S9S_MB_2U_LIB.S9S_MB_2U(SCH_1):GND

Q_CAP  I43  PC537_P1_4  [Q_CAP_C0805-22UF,16V,20%,X6S,CA]
    1  SW_P12V_PVCCIN_CPU1_FLT      A  @S9S_MB_2U_LIB.S9S_MB_2U(SCH_1):SW_P12V_PVCCIN_CPU1_FLT
    2  GND                B  @S9S_MB_2U_LIB.S9S_MB_2U(SCH_1):GND

Q_CAP  I54  PC538_P1_3  [Q_CAP_C0805-22UF,16V,20%,X6S,CA]
    1  SW_P12V_PVCCIN_CPU1_FLT      A  @S9S_MB_2U_LIB.S9S_MB_2U(SCH_1):SW_P12V_PVCCIN_CPU1_FLT
    2  GND                B  @S9S_MB_2U_LIB.S9S_MB_2U(SCH_1):GND

Q_CAP  I96  PC541_P1_4  [Q_CAP_0805-22UF,4V,20%,X6S,TMPA]
    1  PVCCIN_CPU1        A  @S9S_MB_2U_LIB.S9S_MB_2U(SCH_1):PVCCIN_CPU1
    2  GND                B  @S9S_MB_2U_LIB.S9S_MB_2U(SCH_1):GND

Q_CAP  I79  PC542_P1_3  [Q_CAP_0805-22UF,4V,20%,X6S,TMPA]
    1  PVCCIN_CPU1        A  @S9S_MB_2U_LIB.S9S_MB_2U(SCH_1):PVCCIN_CPU1
    2  GND                B  @S9S_MB_2U_LIB.S9S_MB_2U(SCH_1):GND

Q_CAP  I94  PC543_P1_4  [Q_CAP_0805-22UF,4V,20%,X6S,TMPA]
    1  PVCCIN_CPU1        A  @S9S_MB_2U_LIB.S9S_MB_2U(SCH_1):PVCCIN_CPU1
    2  GND                B  @S9S_MB_2U_LIB.S9S_MB_2U(SCH_1):GND

Q_CAP  I77  PC544_P1_3  [Q_CAP_0805-22UF,4V,20%,X6S,TMPA]
    1  PVCCIN_CPU1        A  @S9S_MB_2U_LIB.S9S_MB_2U(SCH_1):PVCCIN_CPU1
    2  GND                B  @S9S_MB_2U_LIB.S9S_MB_2U(SCH_1):GND

Q_CAP  I271  PC545  [Q_CAP_C0603-10UF,4V,20%,EMPTY,A]
    1  PVNN_TERM_CPU1      A  @S9S_MB_2U_LIB.S9S_MB_2U(SCH_1):PVNN_TERM_CPU1
    2  GND                B  @S9S_MB_2U_LIB.S9S_MB_2U(SCH_1):GND

Q_CAP  I273  PC546  [Q_CAP_C0402-100NF,50V,10%,X7R,A]
    1  PVNN_TERM_CPU1      A  @S9S_MB_2U_LIB.S9S_MB_2U(SCH_1):PVNN_TERM_CPU1
    2  GND                B  @S9S_MB_2U_LIB.S9S_MB_2U(SCH_1):GND

Q_CAP  I201  PC547  [Q_CAP_0402-0.1UF,25V,10%,EMPTYA]
    1  PVCCIN_CPU1_CSPIN      A  @S9S_MB_2U_LIB.S9S_MB_2U(SCH_1):PVCCIN_CPU1_CSPIN
    2  GND                B  @S9S_MB_2U_LIB.S9S_MB_2U(SCH_1):GND

Q_CAP  I209  PC548  [Q_CAP_0402-0.1UF,25V,10%,X7R,CA]
    1  PVCCIN_CPU1_VIN_CSNIN      A  @S9S_MB_2U_LIB.S9S_MB_2U(SCH_1):PVCCIN_CPU1_VIN_CSNIN
    2  GND                B  @S9S_MB_2U_LIB.S9S_MB_2U(SCH_1):GND

Q_CAP  I240  PC549  [Q_CAP_0402-3300PF,50V,10%,X7R,A]
    2  VSENSE_PVCCIN_CPU1_DN      B  @S9S_MB_2U_LIB.S9S_MB_2U(SCH_1):VSENSE_PVCCIN_CPU1_DN
    1  SH_PVCCIN_CPU1_R      A  @S9S_MB_2U_LIB.S9S_MB_2U(SCH_1):SH_PVCCIN_CPU1_R

Q_CAP  I242  PC550  [Q_CAP_0402-1000PF,50V,5%,X7R,TA]
    1  PVCCIN_CPU1_EN_R      A  @S9S_MB_2U_LIB.S9S_MB_2U(SCH_1):PVCCIN_CPU1_EN_R
    2  GND                B  @S9S_MB_2U_LIB.S9S_MB_2U(SCH_1):GND

Q_CAP  I244  PC551  [Q_CAP_0402-1000PF,50V,5%,EMPTYA]
    1  PWRGD_PVCCIN_CPU1_R      A  @S9S_MB_2U_LIB.S9S_MB_2U(SCH_1):PWRGD_PVCCIN_CPU1_R
    2  GND                B  @S9S_MB_2U_LIB.S9S_MB_2U(SCH_1):GND

Q_CAP  I254  PC552  [Q_CAP_C0402-100NF,50V,10%,EMPTA]
    1  PVCCIN_CPU1_VCC      A  @S9S_MB_2U_LIB.S9S_MB_2U(SCH_1):PVCCIN_CPU1_VCC
    2  GND                B  @S9S_MB_2U_LIB.S9S_MB_2U(SCH_1):GND

Q_CAP  I253  PC553  [Q_CAP_0402-4.7UF,6.3V,20%,X6S,A]
    1  PVCCIN_CPU1_VREF      A  @S9S_MB_2U_LIB.S9S_MB_2U(SCH_1):PVCCIN_CPU1_VREF
    2  GND                B  @S9S_MB_2U_LIB.S9S_MB_2U(SCH_1):GND

Q_CAP  I221  PC554  [Q_CAP_0402-470PF,50V,10%,X7R,TA]
    1  PVCCIN_CPU1_ATSEN      A  @S9S_MB_2U_LIB.S9S_MB_2U(SCH_1):PVCCIN_CPU1_ATSEN
    2  GND                B  @S9S_MB_2U_LIB.S9S_MB_2U(SCH_1):GND

Q_CAP  I258  PC555  [Q_CAP_C0402-1UF,16V,10%,X6S,CHA]
    1  PVCCIN_CPU1_VCC      A  @S9S_MB_2U_LIB.S9S_MB_2U(SCH_1):PVCCIN_CPU1_VCC
    2  GND                B  @S9S_MB_2U_LIB.S9S_MB_2U(SCH_1):GND

Q_CAP  I8   PC556  [Q_CAP_C0402-2.2UF,10V,10%,X6S,A]
    1  PVCCIN_CPU1_VDD2      A  @S9S_MB_2U_LIB.S9S_MB_2U(SCH_1):PVCCIN_CPU1_VDD2
    2  GND                B  @S9S_MB_2U_LIB.S9S_MB_2U(SCH_1):GND

Q_CAP  I29  PC557  [Q_CAP_C0402-2.2UF,10V,10%,X6S,A]
    1  PVCCIN_CPU1_VDD1      A  @S9S_MB_2U_LIB.S9S_MB_2U(SCH_1):PVCCIN_CPU1_VDD1
    2  GND                B  @S9S_MB_2U_LIB.S9S_MB_2U(SCH_1):GND

Q_CAP  I16  PC558_P1_2  [Q_CAP_C0402-2.2UF,10V,10%,X6S,A]
    1  PVCCIN_CPU1_PVCC      A  @S9S_MB_2U_LIB.S9S_MB_2U(SCH_1):PVCCIN_CPU1_PVCC
    2  GND                B  @S9S_MB_2U_LIB.S9S_MB_2U(SCH_1):GND

Q_CAP  I32  PC559_P1_1  [Q_CAP_C0402-2.2UF,10V,10%,X6S,A]
    1  PVCCIN_CPU1_PVCC      A  @S9S_MB_2U_LIB.S9S_MB_2U(SCH_1):PVCCIN_CPU1_PVCC
    2  GND                B  @S9S_MB_2U_LIB.S9S_MB_2U(SCH_1):GND

Q_CAP  I21  PC560_P1_2  [Q_CAP_0402-3300PF,50V,10%,X7R,A]
    1  SW_P12V_PVCCIN_CPU1_FLT      A  @S9S_MB_2U_LIB.S9S_MB_2U(SCH_1):SW_P12V_PVCCIN_CPU1_FLT
    2  GND                B  @S9S_MB_2U_LIB.S9S_MB_2U(SCH_1):GND

Q_CAP  I38  PC561_P1_1  [Q_CAP_0402-3300PF,50V,10%,X7R,A]
    1  SW_P12V_PVCCIN_CPU1_FLT      A  @S9S_MB_2U_LIB.S9S_MB_2U(SCH_1):SW_P12V_PVCCIN_CPU1_FLT
    2  GND                B  @S9S_MB_2U_LIB.S9S_MB_2U(SCH_1):GND

Q_CAP  I39  PC562_P1_2  [Q_CAP_C0402-1UF,16V,10%,X6S,CHA]
    1  SW_P12V_PVCCIN_CPU1_FLT      A  @S9S_MB_2U_LIB.S9S_MB_2U(SCH_1):SW_P12V_PVCCIN_CPU1_FLT
    2  GND                B  @S9S_MB_2U_LIB.S9S_MB_2U(SCH_1):GND

Q_CAP  I40  PC563_P1_1  [Q_CAP_C0402-1UF,16V,10%,X6S,CHA]
    1  SW_P12V_PVCCIN_CPU1_FLT      A  @S9S_MB_2U_LIB.S9S_MB_2U(SCH_1):SW_P12V_PVCCIN_CPU1_FLT
    2  GND                B  @S9S_MB_2U_LIB.S9S_MB_2U(SCH_1):GND

Q_CAP  I42  PC564  [Q_CAP_C0402-100NF,50V,10%,X7R,A]
    2  SW_PVCCIN_CPU1_BOOTR2      B  @S9S_MB_2U_LIB.S9S_MB_2U(SCH_1):SW_PVCCIN_CPU1_BOOTR2
    1  SW_PVCCIN_CPU1_BOOT2_R      A  @S9S_MB_2U_LIB.S9S_MB_2U(SCH_1):SW_PVCCIN_CPU1_BOOT2_R

Q_CAP  I60  PC565  [Q_CAP_C0402-100NF,50V,10%,X7R,A]
    2  SW_PVCCIN_CPU1_BOOTR1      B  @S9S_MB_2U_LIB.S9S_MB_2U(SCH_1):SW_PVCCIN_CPU1_BOOTR1
    1  SW_PVCCIN_CPU1_BOOT1_R      A  @S9S_MB_2U_LIB.S9S_MB_2U(SCH_1):SW_PVCCIN_CPU1_BOOT1_R

Q_CAPP  I4   PC566  [Q_CAPP_SMLF-100UF,16V,20%,OSCOA]
    1  SW_P3V3_AUX_FLT      A  @S9S_MB_2U_LIB.S9S_MB_2U(SCH_1):SW_P3V3_AUX_FLT
    2  GND                B  @S9S_MB_2U_LIB.S9S_MB_2U(SCH_1):GND

Q_CAP  I44  PC566_P1_2  [Q_CAP_C0805-22UF,16V,20%,X6S,CA]
    1  SW_P12V_PVCCIN_CPU1_FLT      A  @S9S_MB_2U_LIB.S9S_MB_2U(SCH_1):SW_P12V_PVCCIN_CPU1_FLT
    2  GND                B  @S9S_MB_2U_LIB.S9S_MB_2U(SCH_1):GND

Q_CAP  I5   PC567  [Q_CAP_C0805-22UF,16V,20%,X6S,CA]
    1  SW_P3V3_AUX_FLT      A  @S9S_MB_2U_LIB.S9S_MB_2U(SCH_1):SW_P3V3_AUX_FLT
    2  GND                B  @S9S_MB_2U_LIB.S9S_MB_2U(SCH_1):GND

Q_CAP  I61  PC567_P1_1  [Q_CAP_C0805-22UF,16V,20%,X6S,CA]
    1  SW_P12V_PVCCIN_CPU1_FLT      A  @S9S_MB_2U_LIB.S9S_MB_2U(SCH_1):SW_P12V_PVCCIN_CPU1_FLT
    2  GND                B  @S9S_MB_2U_LIB.S9S_MB_2U(SCH_1):GND

Q_CAP  I28  PC568  [Q_CAP_0402-0.22UF,16V,10%,X7R,A]
    2  SW_P3V3_AUX_BOOT_R      B  @S9S_MB_2U_LIB.S9S_MB_2U(SCH_1):SW_P3V3_AUX_BOOT_R
    1  SW_P3V3_AUX_BOOTR      A  @S9S_MB_2U_LIB.S9S_MB_2U(SCH_1):SW_P3V3_AUX_BOOTR

Q_CAP  I45  PC568_P1_2  [Q_CAP_C0805-22UF,16V,20%,X6S,CA]
    1  SW_P12V_PVCCIN_CPU1_FLT      A  @S9S_MB_2U_LIB.S9S_MB_2U(SCH_1):SW_P12V_PVCCIN_CPU1_FLT
    2  GND                B  @S9S_MB_2U_LIB.S9S_MB_2U(SCH_1):GND

Q_CAP  I35  PC569  [Q_CAP_0402-10PF,50V,1%,NPO,TMPA]
    1  P3V3_AUX_FB        A  @S9S_MB_2U_LIB.S9S_MB_2U(SCH_1):P3V3_AUX_FB
    2  P3V3_AUX           B  @S9S_MB_2U_LIB.S9S_MB_2U(SCH_1):P3V3_AUX

Q_CAP  I62  PC569_P1_1  [Q_CAP_C0805-22UF,16V,20%,X6S,CA]
    1  SW_P12V_PVCCIN_CPU1_FLT      A  @S9S_MB_2U_LIB.S9S_MB_2U(SCH_1):SW_P12V_PVCCIN_CPU1_FLT
    2  GND                B  @S9S_MB_2U_LIB.S9S_MB_2U(SCH_1):GND

Q_CAP  I18  PC570  [Q_CAP_C0805-22UF,16V,20%,X6S,CA]
    1  SW_P3V3_AUX_FLT      A  @S9S_MB_2U_LIB.S9S_MB_2U(SCH_1):SW_P3V3_AUX_FLT
    2  GND                B  @S9S_MB_2U_LIB.S9S_MB_2U(SCH_1):GND

Q_CAP  I46  PC570_P1_2  [Q_CAP_C0805-22UF,16V,20%,X6S,CA]
    1  SW_P12V_PVCCIN_CPU1_FLT      A  @S9S_MB_2U_LIB.S9S_MB_2U(SCH_1):SW_P12V_PVCCIN_CPU1_FLT
    2  GND                B  @S9S_MB_2U_LIB.S9S_MB_2U(SCH_1):GND

Q_CAP  I19  PC571  [Q_CAP_C0805-22UF,16V,20%,X6S,CA]
    1  SW_P3V3_AUX_FLT      A  @S9S_MB_2U_LIB.S9S_MB_2U(SCH_1):SW_P3V3_AUX_FLT
    2  GND                B  @S9S_MB_2U_LIB.S9S_MB_2U(SCH_1):GND

Q_CAP  I66  PC571_P1_1  [Q_CAP_C0805-22UF,16V,20%,X6S,CA]
    1  SW_P12V_PVCCIN_CPU1_FLT      A  @S9S_MB_2U_LIB.S9S_MB_2U(SCH_1):SW_P12V_PVCCIN_CPU1_FLT
    2  GND                B  @S9S_MB_2U_LIB.S9S_MB_2U(SCH_1):GND

Q_CAP  I64  PC572_P1_1  [Q_CAP_C0402-100NF,50V,10%,X7R,A]
    1  PVCCIN_CPU1        A  @S9S_MB_2U_LIB.S9S_MB_2U(SCH_1):PVCCIN_CPU1
    2  GND                B  @S9S_MB_2U_LIB.S9S_MB_2U(SCH_1):GND

Q_CAP  I65  PC574_P1_1  [Q_CAP_C0402-1UF,16V,10%,X6S,CHA]
    1  PVCCIN_CPU1        A  @S9S_MB_2U_LIB.S9S_MB_2U(SCH_1):PVCCIN_CPU1
    2  GND                B  @S9S_MB_2U_LIB.S9S_MB_2U(SCH_1):GND

Q_CAP  I100  PC575_P1_2  [Q_CAP_0805-22UF,4V,20%,X6S,TMPA]
    1  PVCCIN_CPU1        A  @S9S_MB_2U_LIB.S9S_MB_2U(SCH_1):PVCCIN_CPU1
    2  GND                B  @S9S_MB_2U_LIB.S9S_MB_2U(SCH_1):GND

Q_CAP  I20  PC576  [Q_CAP_C0805-22UF,16V,20%,X6S,CA]
    1  SW_P3V3_AUX_FLT      A  @S9S_MB_2U_LIB.S9S_MB_2U(SCH_1):SW_P3V3_AUX_FLT
    2  GND                B  @S9S_MB_2U_LIB.S9S_MB_2U(SCH_1):GND

Q_CAP  I68  PC576_P1_1  [Q_CAP_0805-22UF,4V,20%,X6S,TMPA]
    1  PVCCIN_CPU1        A  @S9S_MB_2U_LIB.S9S_MB_2U(SCH_1):PVCCIN_CPU1
    2  GND                B  @S9S_MB_2U_LIB.S9S_MB_2U(SCH_1):GND

Q_CAP  I21  PC577  [Q_CAP_0402-0.1UF,25V,10%,X7R,CA]
    1  SW_P3V3_AUX_FLT      A  @S9S_MB_2U_LIB.S9S_MB_2U(SCH_1):SW_P3V3_AUX_FLT
    2  GND                B  @S9S_MB_2U_LIB.S9S_MB_2U(SCH_1):GND

Q_CAP  I99  PC577_P1_2  [Q_CAP_0805-22UF,4V,20%,X6S,TMPA]
    1  PVCCIN_CPU1        A  @S9S_MB_2U_LIB.S9S_MB_2U(SCH_1):PVCCIN_CPU1
    2  GND                B  @S9S_MB_2U_LIB.S9S_MB_2U(SCH_1):GND

Q_CAP  I69  PC578_P1_1  [Q_CAP_0805-22UF,4V,20%,X6S,TMPA]
    1  PVCCIN_CPU1        A  @S9S_MB_2U_LIB.S9S_MB_2U(SCH_1):PVCCIN_CPU1
    2  GND                B  @S9S_MB_2U_LIB.S9S_MB_2U(SCH_1):GND

Q_CAPP  I73  PC579  [Q_CAPP_THLF-270UF,16V,20%,OSCOA]
    1  SW_P12V_PVCCIN_CPU1_FLT      A  @S9S_MB_2U_LIB.S9S_MB_2U(SCH_1):SW_P12V_PVCCIN_CPU1_FLT
    2  GND                B  @S9S_MB_2U_LIB.S9S_MB_2U(SCH_1):GND

Q_CAPP  I55  PC580  [Q_CAPP_THLF-560UF,2.5V,20%,OSCA]
    1  PVCCIN_CPU1        A  @S9S_MB_2U_LIB.S9S_MB_2U(SCH_1):PVCCIN_CPU1
    2  GND                B  @S9S_MB_2U_LIB.S9S_MB_2U(SCH_1):GND

Q_CAP  I7   PC581  [Q_CAP_C0603-4.7UF,16V,10%,X6S,A]
    1  P5V_AUX            A  @S9S_MB_2U_LIB.S9S_MB_2U(SCH_1):P5V_AUX
    2  GND                B  @S9S_MB_2U_LIB.S9S_MB_2U(SCH_1):GND

Q_CAPP  I74  PC582  [Q_CAPP_THLF-270UF,16V,20%,OSCOA]
    1  SW_P12V_PVCCIN_CPU1_FLT      A  @S9S_MB_2U_LIB.S9S_MB_2U(SCH_1):SW_P12V_PVCCIN_CPU1_FLT
    2  GND                B  @S9S_MB_2U_LIB.S9S_MB_2U(SCH_1):GND

Q_CAPP  I56  PC583  [Q_CAPP_THLF-560UF,2.5V,20%,OSCA]
    1  PVCCIN_CPU1        A  @S9S_MB_2U_LIB.S9S_MB_2U(SCH_1):PVCCIN_CPU1
    2  GND                B  @S9S_MB_2U_LIB.S9S_MB_2U(SCH_1):GND

Q_CAPP  I83  PC585  [Q_CAPP_THLF-270UF,16V,20%,OSCOA]
    1  SW_P12V_PVCCIN_CPU1_FLT      A  @S9S_MB_2U_LIB.S9S_MB_2U(SCH_1):SW_P12V_PVCCIN_CPU1_FLT
    2  GND                B  @S9S_MB_2U_LIB.S9S_MB_2U(SCH_1):GND

Q_CAPP  I79  PC586  [Q_CAPP_THLF-560UF,2.5V,20%,OSCA]
    1  PVCCIN_CPU1        A  @S9S_MB_2U_LIB.S9S_MB_2U(SCH_1):PVCCIN_CPU1
    2  GND                B  @S9S_MB_2U_LIB.S9S_MB_2U(SCH_1):GND

Q_CAPP  I75  PC587  [Q_CAPP_SMLF-470UF,2.5V,20%,EMPA]
    1  PVCCIN_CPU1        A  @S9S_MB_2U_LIB.S9S_MB_2U(SCH_1):PVCCIN_CPU1
    2  GND                B  @S9S_MB_2U_LIB.S9S_MB_2U(SCH_1):GND

Q_CAPP  I84  PC588  [Q_CAPP_THLF-270UF,16V,20%,OSCOA]
    1  SW_P12V_PVCCIN_CPU1_FLT      A  @S9S_MB_2U_LIB.S9S_MB_2U(SCH_1):SW_P12V_PVCCIN_CPU1_FLT
    2  GND                B  @S9S_MB_2U_LIB.S9S_MB_2U(SCH_1):GND

Q_CAPP  I81  PC589  [Q_CAPP_THLF-560UF,2.5V,20%,OSCA]
    1  PVCCIN_CPU1        A  @S9S_MB_2U_LIB.S9S_MB_2U(SCH_1):PVCCIN_CPU1
    2  GND                B  @S9S_MB_2U_LIB.S9S_MB_2U(SCH_1):GND

Q_CAPP  I77  PC590  [Q_CAPP_SMLF-470UF,2.5V,20%,EMPA]
    1  PVCCIN_CPU1        A  @S9S_MB_2U_LIB.S9S_MB_2U(SCH_1):PVCCIN_CPU1
    2  GND                B  @S9S_MB_2U_LIB.S9S_MB_2U(SCH_1):GND

Q_CAP  I15  PC591  [Q_CAP_C0603-2.2UF,16V,10%,X6S,A]
    1  P3V3_AUX_VCC       A  @S9S_MB_2U_LIB.S9S_MB_2U(SCH_1):P3V3_AUX_VCC
    2  GND                B  @S9S_MB_2U_LIB.S9S_MB_2U(SCH_1):GND

Q_CAP  I43  PC592  [Q_CAP_0402-1000PF,50V,5%,X7R,TA]
    1  PVCCFA_EHV_FIVRA_CPU0_EN_R      A  @S9S_MB_2U_LIB.S9S_MB_2U(SCH_1):PVCCFA_EHV_FIVRA_CPU0_EN_R
    2  GND                B  @S9S_MB_2U_LIB.S9S_MB_2U(SCH_1):GND

Q_CAP  I42  PC593  [Q_CAP_0402-1000PF,50V,5%,EMPTYA]
    1  PWRGD_PVCCFA_EHV_FIVRA_CPU0_R      A  @S9S_MB_2U_LIB.S9S_MB_2U(SCH_1):PWRGD_PVCCFA_EHV_FIVRA_CPU0_R
    2  GND                B  @S9S_MB_2U_LIB.S9S_MB_2U(SCH_1):GND

Q_CAP  I56  PC594  [Q_CAP_0402-3300PF,50V,10%,X7R,A]
    2  VSENSE_PVCCFA_EHV_FIVRA_CPU0_DN      B  @S9S_MB_2U_LIB.S9S_MB_2U(SCH_1):VSENSE_PVCCFA_EHV_FIVRA_CPU0_DN
    1  SH_PVCCFA_EHV_FIVRA_CPU0_R      A  @S9S_MB_2U_LIB.S9S_MB_2U(SCH_1):SH_PVCCFA_EHV_FIVRA_CPU0_R

Q_CAP  I23  PC600  [Q_CAP_C0402-2.2UF,10V,10%,X6S,A]
    1  PVCCFA_EHV_FIVRA_CPU0_VDD1      A  @S9S_MB_2U_LIB.S9S_MB_2U(SCH_1):PVCCFA_EHV_FIVRA_CPU0_VDD1
    2  GND                B  @S9S_MB_2U_LIB.S9S_MB_2U(SCH_1):GND

Q_CAP  I8   PC601  [Q_CAP_C0402-2.2UF,10V,10%,X6S,A]
    1  PVCCFA_EHV_FIVRA_CPU0_VDD2      A  @S9S_MB_2U_LIB.S9S_MB_2U(SCH_1):PVCCFA_EHV_FIVRA_CPU0_VDD2
    2  GND                B  @S9S_MB_2U_LIB.S9S_MB_2U(SCH_1):GND

Q_CAP  I49  PC602_P0_1  [Q_CAP_0402-3300PF,50V,10%,X7R,A]
    1  SW_P12V_PVCCFA_EHV_FIVRA_CPU0_R      A  @S9S_MB_2U_LIB.S9S_MB_2U(SCH_1):SW_P12V_PVCCFA_EHV_FIVRA_CPU0_R
    2  GND                B  @S9S_MB_2U_LIB.S9S_MB_2U(SCH_1):GND

Q_CAP  I38  PC603_P0_2  [Q_CAP_0402-3300PF,50V,10%,X7R,A]
    1  SW_P12V_PVCCFA_EHV_FIVRA_CPU0_L      A  @S9S_MB_2U_LIB.S9S_MB_2U(SCH_1):SW_P12V_PVCCFA_EHV_FIVRA_CPU0_L
    2  GND                B  @S9S_MB_2U_LIB.S9S_MB_2U(SCH_1):GND

Q_CAP  I50  PC604_P0_1  [Q_CAP_C0402-1UF,16V,10%,X6S,CHA]
    1  SW_P12V_PVCCFA_EHV_FIVRA_CPU0_R      A  @S9S_MB_2U_LIB.S9S_MB_2U(SCH_1):SW_P12V_PVCCFA_EHV_FIVRA_CPU0_R
    2  GND                B  @S9S_MB_2U_LIB.S9S_MB_2U(SCH_1):GND

Q_CAP  I39  PC605_P0_2  [Q_CAP_C0402-1UF,16V,10%,X6S,CHA]
    1  SW_P12V_PVCCFA_EHV_FIVRA_CPU0_L      A  @S9S_MB_2U_LIB.S9S_MB_2U(SCH_1):SW_P12V_PVCCFA_EHV_FIVRA_CPU0_L
    2  GND                B  @S9S_MB_2U_LIB.S9S_MB_2U(SCH_1):GND

Q_CAP  I54  PC606  [Q_CAP_C0402-100NF,50V,10%,X7R,A]
    2  SW_PVCCFA_EHV_FIVRA_CPU0_BOOTR1      B  @S9S_MB_2U_LIB.S9S_MB_2U(SCH_1):SW_PVCCFA_EHV_FIVRA_CPU0_BOOTR1
    1  SW_PVCCFA_EHV_FIVRA_CPU0_BOOT1_      A  @S9S_MB_2U_LIB.S9S_MB_2U(SCH_1):SW_PVCCFA_EHV_FIVRA_CPU0_BOOT1_R

Q_CAP  I43  PC607  [Q_CAP_C0402-100NF,50V,10%,X7R,A]
    2  SW_PVCCFA_EHV_FIVRA_CPU0_BOOTR2      B  @S9S_MB_2U_LIB.S9S_MB_2U(SCH_1):SW_PVCCFA_EHV_FIVRA_CPU0_BOOTR2
    1  SW_PVCCFA_EHV_FIVRA_CPU0_BOOT2_      A  @S9S_MB_2U_LIB.S9S_MB_2U(SCH_1):SW_PVCCFA_EHV_FIVRA_CPU0_BOOT2_R

Q_CAP  I52  PC608_P0_1  [Q_CAP_C0805-22UF,16V,20%,X6S,CA]
    1  SW_P12V_PVCCFA_EHV_FIVRA_CPU0_R      A  @S9S_MB_2U_LIB.S9S_MB_2U(SCH_1):SW_P12V_PVCCFA_EHV_FIVRA_CPU0_R
    2  GND                B  @S9S_MB_2U_LIB.S9S_MB_2U(SCH_1):GND

Q_CAP  I41  PC609_P0_2  [Q_CAP_C0805-22UF,16V,20%,X6S,CA]
    1  SW_P12V_PVCCFA_EHV_FIVRA_CPU0_L      A  @S9S_MB_2U_LIB.S9S_MB_2U(SCH_1):SW_P12V_PVCCFA_EHV_FIVRA_CPU0_L
    2  GND                B  @S9S_MB_2U_LIB.S9S_MB_2U(SCH_1):GND

Q_CAP  I56  PC610_P0_1  [Q_CAP_C0805-22UF,16V,20%,X6S,CA]
    1  SW_P12V_PVCCFA_EHV_FIVRA_CPU0_R      A  @S9S_MB_2U_LIB.S9S_MB_2U(SCH_1):SW_P12V_PVCCFA_EHV_FIVRA_CPU0_R
    2  GND                B  @S9S_MB_2U_LIB.S9S_MB_2U(SCH_1):GND

Q_CAP  I42  PC611_P0_2  [Q_CAP_C0805-22UF,16V,20%,X6S,CA]
    1  SW_P12V_PVCCFA_EHV_FIVRA_CPU0_L      A  @S9S_MB_2U_LIB.S9S_MB_2U(SCH_1):SW_P12V_PVCCFA_EHV_FIVRA_CPU0_L
    2  GND                B  @S9S_MB_2U_LIB.S9S_MB_2U(SCH_1):GND

Q_CAP  I70  PC612_P0_1  [Q_CAP_C0402-100NF,50V,10%,X7R,A]
    1  PVCCFA_EHV_FIVRA_CPU0      A  @S9S_MB_2U_LIB.S9S_MB_2U(SCH_1):PVCCFA_EHV_FIVRA_CPU0
    2  GND                B  @S9S_MB_2U_LIB.S9S_MB_2U(SCH_1):GND

Q_CAP  I59  PC613_P0_2  [Q_CAP_C0402-1UF,16V,10%,X6S,CHA]
    1  PVCCFA_EHV_FIVRA_CPU0      A  @S9S_MB_2U_LIB.S9S_MB_2U(SCH_1):PVCCFA_EHV_FIVRA_CPU0
    2  GND                B  @S9S_MB_2U_LIB.S9S_MB_2U(SCH_1):GND

Q_CAP  I72  PC615_P0_1  [Q_CAP_0805-22UF,4V,20%,X6S,TMPA]
    1  PVCCFA_EHV_FIVRA_CPU0      A  @S9S_MB_2U_LIB.S9S_MB_2U(SCH_1):PVCCFA_EHV_FIVRA_CPU0
    2  GND                B  @S9S_MB_2U_LIB.S9S_MB_2U(SCH_1):GND

Q_CAP  I60  PC616_P0_2  [Q_CAP_0805-22UF,4V,20%,X6S,TMPA]
    1  PVCCFA_EHV_FIVRA_CPU0      A  @S9S_MB_2U_LIB.S9S_MB_2U(SCH_1):PVCCFA_EHV_FIVRA_CPU0
    2  GND                B  @S9S_MB_2U_LIB.S9S_MB_2U(SCH_1):GND

Q_CAP  I73  PC617_P0_1  [Q_CAP_0805-22UF,4V,20%,X6S,TMPA]
    1  PVCCFA_EHV_FIVRA_CPU0      A  @S9S_MB_2U_LIB.S9S_MB_2U(SCH_1):PVCCFA_EHV_FIVRA_CPU0
    2  GND                B  @S9S_MB_2U_LIB.S9S_MB_2U(SCH_1):GND

Q_CAP  I61  PC618_P0_2  [Q_CAP_0805-22UF,4V,20%,X6S,TMPA]
    1  PVCCFA_EHV_FIVRA_CPU0      A  @S9S_MB_2U_LIB.S9S_MB_2U(SCH_1):PVCCFA_EHV_FIVRA_CPU0
    2  GND                B  @S9S_MB_2U_LIB.S9S_MB_2U(SCH_1):GND

Q_CAPP  I62  PC619  [Q_CAPP_THLF-560UF,2.5V,20%,OSCA]
    1  PVCCFA_EHV_FIVRA_CPU0      A  @S9S_MB_2U_LIB.S9S_MB_2U(SCH_1):PVCCFA_EHV_FIVRA_CPU0
    2  GND                B  @S9S_MB_2U_LIB.S9S_MB_2U(SCH_1):GND

Q_CAPP  I63  PC620  [Q_CAPP_THLF-560UF,2.5V,20%,OSCA]
    1  PVCCFA_EHV_FIVRA_CPU0      A  @S9S_MB_2U_LIB.S9S_MB_2U(SCH_1):PVCCFA_EHV_FIVRA_CPU0
    2  GND                B  @S9S_MB_2U_LIB.S9S_MB_2U(SCH_1):GND

Q_CAPP  I65  PC621  [Q_CAPP_THLF-560UF,2.5V,20%,EMPA]
    1  PVCCFA_EHV_FIVRA_CPU0      A  @S9S_MB_2U_LIB.S9S_MB_2U(SCH_1):PVCCFA_EHV_FIVRA_CPU0
    2  GND                B  @S9S_MB_2U_LIB.S9S_MB_2U(SCH_1):GND

Q_CAP  I281  PC621_P1_1  [Q_CAP_C0402-100NF,50V,10%,X7R,A]
    1  PVCCFA_EHV_FIVRA_CPU1      A  @S9S_MB_2U_LIB.S9S_MB_2U(SCH_1):PVCCFA_EHV_FIVRA_CPU1
    2  GND                B  @S9S_MB_2U_LIB.S9S_MB_2U(SCH_1):GND

Q_CAPP  I77  PC622  [Q_CAPP_THLF-270UF,16V,20%,OSCOA]
    1  SW_P12V_PVCCFA_EHV_FIVRA_CPU0_L      A  @S9S_MB_2U_LIB.S9S_MB_2U(SCH_1):SW_P12V_PVCCFA_EHV_FIVRA_CPU0_L
    2  GND                B  @S9S_MB_2U_LIB.S9S_MB_2U(SCH_1):GND

Q_CAPP  I66  PC623  [Q_CAPP_SMLF-470UF,2.5V,20%,EMPA]
    1  PVCCFA_EHV_FIVRA_CPU0      A  @S9S_MB_2U_LIB.S9S_MB_2U(SCH_1):PVCCFA_EHV_FIVRA_CPU0
    2  GND                B  @S9S_MB_2U_LIB.S9S_MB_2U(SCH_1):GND

Q_CAP  I13  PC624  [Q_CAP_0402-0.1UF,25V,10%,X7R,CA]
    1  PVCCD_HV_CPU0_ISENSE_P      A  @S9S_MB_2U_LIB.S9S_MB_2U(SCH_1):PVCCD_HV_CPU0_ISENSE_P
    2  GND                B  @S9S_MB_2U_LIB.S9S_MB_2U(SCH_1):GND

Q_CAP  I45  PC626  [Q_CAP_0402-1000PF,50V,5%,EMPTYA]
    1  PWRGD_PVCCD_HV_CPU0_R      A  @S9S_MB_2U_LIB.S9S_MB_2U(SCH_1):PWRGD_PVCCD_HV_CPU0_R
    2  GND                B  @S9S_MB_2U_LIB.S9S_MB_2U(SCH_1):GND

Q_CAP  I18  PC627  [Q_CAP_0402-3300PF,50V,10%,X7R,A]
    2  VSENSE_PVCCD_HV_CPU0_DN      B  @S9S_MB_2U_LIB.S9S_MB_2U(SCH_1):VSENSE_PVCCD_HV_CPU0_DN
    1  SH_PVCCD_HV_CPU0_R      A  @S9S_MB_2U_LIB.S9S_MB_2U(SCH_1):SH_PVCCD_HV_CPU0_R

Q_CAP  I48  PC628  [Q_CAP_0402-0.1UF,25V,10%,X7R,CA]
    1  PVCCD_HV_CPU0_ISENSE_N      A  @S9S_MB_2U_LIB.S9S_MB_2U(SCH_1):PVCCD_HV_CPU0_ISENSE_N
    2  GND                B  @S9S_MB_2U_LIB.S9S_MB_2U(SCH_1):GND

Q_CAP  I65  PC629  [Q_CAP_C0402-100NF,50V,10%,EMPTA]
    1  PVCCD_HV_CPU0_VCC      A  @S9S_MB_2U_LIB.S9S_MB_2U(SCH_1):PVCCD_HV_CPU0_VCC
    2  GND                B  @S9S_MB_2U_LIB.S9S_MB_2U(SCH_1):GND

Q_CAP  I63  PC630  [Q_CAP_0402-4.7UF,6.3V,20%,X6S,A]
    1  PVCCD_HV_CPU0_VREF      A  @S9S_MB_2U_LIB.S9S_MB_2U(SCH_1):PVCCD_HV_CPU0_VREF
    2  GND                B  @S9S_MB_2U_LIB.S9S_MB_2U(SCH_1):GND

Q_CAP  I55  PC631  [Q_CAP_0402-470PF,50V,10%,X7R,TA]
    1  PVCCD_HV_CPU0_ATSEN      A  @S9S_MB_2U_LIB.S9S_MB_2U(SCH_1):PVCCD_HV_CPU0_ATSEN
    2  GND                B  @S9S_MB_2U_LIB.S9S_MB_2U(SCH_1):GND

Q_CAP  I66  PC632  [Q_CAP_C0402-1UF,16V,10%,X6S,CHA]
    1  PVCCD_HV_CPU0_VCC      A  @S9S_MB_2U_LIB.S9S_MB_2U(SCH_1):PVCCD_HV_CPU0_VCC
    2  GND                B  @S9S_MB_2U_LIB.S9S_MB_2U(SCH_1):GND

Q_CAP  I332  PC633  [Q_CAP_C0402-2.2UF,10V,10%,X6S,A]
    1  PVCCD_HV_CPU0_VDD1      A  @S9S_MB_2U_LIB.S9S_MB_2U(SCH_1):PVCCD_HV_CPU0_VDD1
    2  GND                B  @S9S_MB_2U_LIB.S9S_MB_2U(SCH_1):GND

Q_CAP  I340  PC634  [Q_CAP_0402-3300PF,50V,10%,X7R,A]
    1  SW_P12V_PVCCINFAON_CPU0_FLT      A  @S9S_MB_2U_LIB.S9S_MB_2U(SCH_1):SW_P12V_PVCCINFAON_CPU0_FLT
    2  GND                B  @S9S_MB_2U_LIB.S9S_MB_2U(SCH_1):GND

Q_CAP  I357  PC635  [Q_CAP_C0402-1UF,16V,10%,X6S,CHA]
    1  SW_P12V_PVCCINFAON_CPU0_FLT      A  @S9S_MB_2U_LIB.S9S_MB_2U(SCH_1):SW_P12V_PVCCINFAON_CPU0_FLT
    2  GND                B  @S9S_MB_2U_LIB.S9S_MB_2U(SCH_1):GND

Q_CAP  I344  PC636  [Q_CAP_C0402-100NF,50V,10%,X7R,A]
    2  SW_PVCCD_HV_CPU0_BOOTR1      B  @S9S_MB_2U_LIB.S9S_MB_2U(SCH_1):SW_PVCCD_HV_CPU0_BOOTR1
    1  SW_PVCCD_HV_CPU0_BOOT1_R      A  @S9S_MB_2U_LIB.S9S_MB_2U(SCH_1):SW_PVCCD_HV_CPU0_BOOT1_R

Q_CAP  I358  PC637  [Q_CAP_C0805-22UF,16V,20%,X6S,CA]
    1  SW_P12V_PVCCINFAON_CPU0_FLT      A  @S9S_MB_2U_LIB.S9S_MB_2U(SCH_1):SW_P12V_PVCCINFAON_CPU0_FLT
    2  GND                B  @S9S_MB_2U_LIB.S9S_MB_2U(SCH_1):GND

Q_CAP  I359  PC638  [Q_CAP_C0805-22UF,16V,20%,X6S,CA]
    1  SW_P12V_PVCCINFAON_CPU0_FLT      A  @S9S_MB_2U_LIB.S9S_MB_2U(SCH_1):SW_P12V_PVCCINFAON_CPU0_FLT
    2  GND                B  @S9S_MB_2U_LIB.S9S_MB_2U(SCH_1):GND

Q_CAP  I346  PC639  [Q_CAP_C0402-100NF,50V,10%,X7R,A]
    1  PVCCD_HV_CPU0      A  @S9S_MB_2U_LIB.S9S_MB_2U(SCH_1):PVCCD_HV_CPU0
    2  GND                B  @S9S_MB_2U_LIB.S9S_MB_2U(SCH_1):GND

Q_CAP  I352  PC641  [Q_CAP_0805-22UF,4V,20%,X6S,TMPA]
    1  PVCCD_HV_CPU0      A  @S9S_MB_2U_LIB.S9S_MB_2U(SCH_1):PVCCD_HV_CPU0
    2  GND                B  @S9S_MB_2U_LIB.S9S_MB_2U(SCH_1):GND

Q_CAP  I353  PC642  [Q_CAP_0805-22UF,4V,20%,X6S,TMPA]
    1  PVCCD_HV_CPU0      A  @S9S_MB_2U_LIB.S9S_MB_2U(SCH_1):PVCCD_HV_CPU0
    2  GND                B  @S9S_MB_2U_LIB.S9S_MB_2U(SCH_1):GND

Q_CAP  I7   PC644  [Q_CAP_C0402-1UF,25V,10%,X6S,CHA]
    1  PVPP_HBM_CPU1_VCC      A  @S9S_MB_2U_LIB.S9S_MB_2U(SCH_1):PVPP_HBM_CPU1_VCC
    2  GND                B  @S9S_MB_2U_LIB.S9S_MB_2U(SCH_1):GND

Q_CAP  I85  PC720_P0_1  [Q_CAP_C0805-22UF,16V,20%,X6S,CA]
    1  SW_P12V_PVCCFA_EHV_FIVRA_CPU0_R      A  @S9S_MB_2U_LIB.S9S_MB_2U(SCH_1):SW_P12V_PVCCFA_EHV_FIVRA_CPU0_R
    2  GND                B  @S9S_MB_2U_LIB.S9S_MB_2U(SCH_1):GND

Q_CAP  I86  PC721_P0_2  [Q_CAP_C0805-22UF,16V,20%,X6S,CA]
    1  SW_P12V_PVCCFA_EHV_FIVRA_CPU0_L      A  @S9S_MB_2U_LIB.S9S_MB_2U(SCH_1):SW_P12V_PVCCFA_EHV_FIVRA_CPU0_L
    2  GND                B  @S9S_MB_2U_LIB.S9S_MB_2U(SCH_1):GND

Q_CAP  I78  PC722_P0_3  [Q_CAP_C0805-22UF,16V,20%,EMPTYA]
    1  SW_P12V_PVCCFA_EHV_FIVRA_CPU0_R      A  @S9S_MB_2U_LIB.S9S_MB_2U(SCH_1):SW_P12V_PVCCFA_EHV_FIVRA_CPU0_R
    2  GND                B  @S9S_MB_2U_LIB.S9S_MB_2U(SCH_1):GND

Q_CAP  I79  PC723_P0_4  [Q_CAP_C0805-22UF,16V,20%,EMPTYA]
    1  SW_P12V_PVCCFA_EHV_FIVRA_CPU0_L      A  @S9S_MB_2U_LIB.S9S_MB_2U(SCH_1):SW_P12V_PVCCFA_EHV_FIVRA_CPU0_L
    2  GND                B  @S9S_MB_2U_LIB.S9S_MB_2U(SCH_1):GND

Q_CAP  I285  PC724_P1_1  [Q_CAP_C0805-22UF,16V,20%,X6S,CA]
    1  SW_P12V_PVCCFA_EHV_FIVRA_CPU1_R      A  @S9S_MB_2U_LIB.S9S_MB_2U(SCH_1):SW_P12V_PVCCFA_EHV_FIVRA_CPU1_R
    2  GND                B  @S9S_MB_2U_LIB.S9S_MB_2U(SCH_1):GND

Q_CAP  I286  PC725_P1_2  [Q_CAP_C0805-22UF,16V,20%,X6S,CA]
    1  SW_P12V_PVCCFA_EHV_FIVRA_CPU1_L      A  @S9S_MB_2U_LIB.S9S_MB_2U(SCH_1):SW_P12V_PVCCFA_EHV_FIVRA_CPU1_L
    2  GND                B  @S9S_MB_2U_LIB.S9S_MB_2U(SCH_1):GND

Q_CAP  I83  PC726_P1_3  [Q_CAP_C0805-22UF,16V,20%,X6S,CA]
    1  SW_P12V_PVCCFA_EHV_FIVRA_CPU1_R      A  @S9S_MB_2U_LIB.S9S_MB_2U(SCH_1):SW_P12V_PVCCFA_EHV_FIVRA_CPU1_R
    2  GND                B  @S9S_MB_2U_LIB.S9S_MB_2U(SCH_1):GND

Q_CAP  I84  PC727_P1_4  [Q_CAP_C0805-22UF,16V,20%,X6S,CA]
    1  SW_P12V_PVCCFA_EHV_FIVRA_CPU1_L      A  @S9S_MB_2U_LIB.S9S_MB_2U(SCH_1):SW_P12V_PVCCFA_EHV_FIVRA_CPU1_L
    2  GND                B  @S9S_MB_2U_LIB.S9S_MB_2U(SCH_1):GND

Q_CAP  I49  PC813  [Q_CAP_C0402-1UF,16V,10%,X6S,CHA]
    2  PVCCD_HV_CPU0_ISENSE_P      B  @S9S_MB_2U_LIB.S9S_MB_2U(SCH_1):PVCCD_HV_CPU0_ISENSE_P
    1  PVCCD_HV_CPU0_ISENSE_N      A  @S9S_MB_2U_LIB.S9S_MB_2U(SCH_1):PVCCD_HV_CPU0_ISENSE_N

Q_CAP  I241  PC814  [Q_CAP_C0402-1UF,16V,10%,X6S,CHA]
    2  PVCCD_HV_CPU1_ISENSE_P      B  @S9S_MB_2U_LIB.S9S_MB_2U(SCH_1):PVCCD_HV_CPU1_ISENSE_P
    1  PVCCD_HV_CPU1_ISENSE_N      A  @S9S_MB_2U_LIB.S9S_MB_2U(SCH_1):PVCCD_HV_CPU1_ISENSE_N

Q_CAP  I44  PC831  [Q_CAP_C0805-22UF,16V,20%,EMPTYA]
    1  SW_P12V_PVCCIN_CPU0_FLT      A  @S9S_MB_2U_LIB.S9S_MB_2U(SCH_1):SW_P12V_PVCCIN_CPU0_FLT
    2  GND                B  @S9S_MB_2U_LIB.S9S_MB_2U(SCH_1):GND

Q_CAP  I20  PC1171  [Q_CAP_C0402-2.2UF,10V,10%,EMPTA]
    1  PVCCFA_EHV_FIVRA_CPU0_VDD3      A  @S9S_MB_2U_LIB.S9S_MB_2U(SCH_1):PVCCFA_EHV_FIVRA_CPU0_VDD3
    2  GND                B  @S9S_MB_2U_LIB.S9S_MB_2U(SCH_1):GND

Q_CAP  I9   PC1172  [Q_CAP_C0402-2.2UF,10V,10%,EMPTA]
    1  PVCCFA_EHV_FIVRA_CPU0_VDD4      A  @S9S_MB_2U_LIB.S9S_MB_2U(SCH_1):PVCCFA_EHV_FIVRA_CPU0_VDD4
    2  GND                B  @S9S_MB_2U_LIB.S9S_MB_2U(SCH_1):GND

Q_CAP  I117  PC1173  [Q_CAP_C0402-1UF,16V,10%,X6S,CHA]
    1  PVCCIN_CPU0_VREF      A  @S9S_MB_2U_LIB.S9S_MB_2U(SCH_1):PVCCIN_CPU0_VREF
    2  GND                B  @S9S_MB_2U_LIB.S9S_MB_2U(SCH_1):GND

Q_CAP  I43  PC1173_P0_3  [Q_CAP_0402-3300PF,50V,10%,EMPTA]
    1  SW_P12V_PVCCFA_EHV_FIVRA_CPU0_R      A  @S9S_MB_2U_LIB.S9S_MB_2U(SCH_1):SW_P12V_PVCCFA_EHV_FIVRA_CPU0_R
    2  GND                B  @S9S_MB_2U_LIB.S9S_MB_2U(SCH_1):GND

Q_CAP  I31  PC1174_P0_4  [Q_CAP_0402-3300PF,50V,10%,EMPTA]
    1  SW_P12V_PVCCFA_EHV_FIVRA_CPU0_L      A  @S9S_MB_2U_LIB.S9S_MB_2U(SCH_1):SW_P12V_PVCCFA_EHV_FIVRA_CPU0_L
    2  GND                B  @S9S_MB_2U_LIB.S9S_MB_2U(SCH_1):GND

Q_CAP  I44  PC1175_P0_3  [Q_CAP_C0402-1UF,16V,10%,EMPTY,A]
    1  SW_P12V_PVCCFA_EHV_FIVRA_CPU0_R      A  @S9S_MB_2U_LIB.S9S_MB_2U(SCH_1):SW_P12V_PVCCFA_EHV_FIVRA_CPU0_R
    2  GND                B  @S9S_MB_2U_LIB.S9S_MB_2U(SCH_1):GND

Q_CAP  I32  PC1176_P0_4  [Q_CAP_C0402-1UF,16V,10%,EMPTY,A]
    1  SW_P12V_PVCCFA_EHV_FIVRA_CPU0_L      A  @S9S_MB_2U_LIB.S9S_MB_2U(SCH_1):SW_P12V_PVCCFA_EHV_FIVRA_CPU0_L
    2  GND                B  @S9S_MB_2U_LIB.S9S_MB_2U(SCH_1):GND

Q_CAP  I48  PC1177  [Q_CAP_C0402-100NF,50V,10%,EMPTA]
    2  SW_PVCCFA_EHV_FIVRA_CPU0_BOOTR3      B  @S9S_MB_2U_LIB.S9S_MB_2U(SCH_1):SW_PVCCFA_EHV_FIVRA_CPU0_BOOTR3
    1  SW_PVCCFA_EHV_FIVRA_CPU0_BOOT3_      A  @S9S_MB_2U_LIB.S9S_MB_2U(SCH_1):SW_PVCCFA_EHV_FIVRA_CPU0_BOOT3_R

Q_CAP  I36  PC1178  [Q_CAP_C0402-100NF,50V,10%,EMPTA]
    2  SW_PVCCFA_EHV_FIVRA_CPU0_BOOTR4      B  @S9S_MB_2U_LIB.S9S_MB_2U(SCH_1):SW_PVCCFA_EHV_FIVRA_CPU0_BOOTR4
    1  SW_PVCCFA_EHV_FIVRA_CPU0_BOOT4_      A  @S9S_MB_2U_LIB.S9S_MB_2U(SCH_1):SW_PVCCFA_EHV_FIVRA_CPU0_BOOT4_R

Q_CAP  I46  PC1179_P0_3  [Q_CAP_C0805-22UF,16V,20%,EMPTYA]
    1  SW_P12V_PVCCFA_EHV_FIVRA_CPU0_R      A  @S9S_MB_2U_LIB.S9S_MB_2U(SCH_1):SW_P12V_PVCCFA_EHV_FIVRA_CPU0_R
    2  GND                B  @S9S_MB_2U_LIB.S9S_MB_2U(SCH_1):GND

Q_CAP  I34  PC1180_P0_4  [Q_CAP_C0805-22UF,16V,20%,EMPTYA]
    1  SW_P12V_PVCCFA_EHV_FIVRA_CPU0_L      A  @S9S_MB_2U_LIB.S9S_MB_2U(SCH_1):SW_P12V_PVCCFA_EHV_FIVRA_CPU0_L
    2  GND                B  @S9S_MB_2U_LIB.S9S_MB_2U(SCH_1):GND

Q_CAP  I50  PC1181_P0_3  [Q_CAP_C0805-22UF,16V,20%,EMPTYA]
    1  SW_P12V_PVCCFA_EHV_FIVRA_CPU0_R      A  @S9S_MB_2U_LIB.S9S_MB_2U(SCH_1):SW_P12V_PVCCFA_EHV_FIVRA_CPU0_R
    2  GND                B  @S9S_MB_2U_LIB.S9S_MB_2U(SCH_1):GND

Q_CAP  I35  PC1182_P0_4  [Q_CAP_C0805-22UF,16V,20%,EMPTYA]
    1  SW_P12V_PVCCFA_EHV_FIVRA_CPU0_L      A  @S9S_MB_2U_LIB.S9S_MB_2U(SCH_1):SW_P12V_PVCCFA_EHV_FIVRA_CPU0_L
    2  GND                B  @S9S_MB_2U_LIB.S9S_MB_2U(SCH_1):GND

Q_CAPP  I56  PC1183  [Q_CAPP_THLF-560UF,2.5V,20%,OSCA]
    1  PVCCFA_EHV_FIVRA_CPU0      A  @S9S_MB_2U_LIB.S9S_MB_2U(SCH_1):PVCCFA_EHV_FIVRA_CPU0
    2  GND                B  @S9S_MB_2U_LIB.S9S_MB_2U(SCH_1):GND

Q_CAP  I65  PC1183_P0_3  [Q_CAP_C0402-1UF,16V,10%,EMPTY,A]
    1  PVCCFA_EHV_FIVRA_CPU0      A  @S9S_MB_2U_LIB.S9S_MB_2U(SCH_1):PVCCFA_EHV_FIVRA_CPU0
    2  GND                B  @S9S_MB_2U_LIB.S9S_MB_2U(SCH_1):GND

Q_CAP  I53  PC1183_P0_4  [Q_CAP_C0402-100NF,50V,10%,EMPTA]
    1  PVCCFA_EHV_FIVRA_CPU0      A  @S9S_MB_2U_LIB.S9S_MB_2U(SCH_1):PVCCFA_EHV_FIVRA_CPU0
    2  GND                B  @S9S_MB_2U_LIB.S9S_MB_2U(SCH_1):GND

Q_CAPP  I57  PC1185  [Q_CAPP_THLF-560UF,2.5V,20%,OSCA]
    1  PVCCFA_EHV_FIVRA_CPU0      A  @S9S_MB_2U_LIB.S9S_MB_2U(SCH_1):PVCCFA_EHV_FIVRA_CPU0
    2  GND                B  @S9S_MB_2U_LIB.S9S_MB_2U(SCH_1):GND

Q_CAP  I67  PC1185_P0_3  [Q_CAP_0805-22UF,4V,20%,EMPTY,TA]
    1  PVCCFA_EHV_FIVRA_CPU0      A  @S9S_MB_2U_LIB.S9S_MB_2U(SCH_1):PVCCFA_EHV_FIVRA_CPU0
    2  GND                B  @S9S_MB_2U_LIB.S9S_MB_2U(SCH_1):GND

Q_CAPP  I60  PC1186  [Q_CAPP_THLF-560UF,2.5V,20%,EMPA]
    1  PVCCFA_EHV_FIVRA_CPU0      A  @S9S_MB_2U_LIB.S9S_MB_2U(SCH_1):PVCCFA_EHV_FIVRA_CPU0
    2  GND                B  @S9S_MB_2U_LIB.S9S_MB_2U(SCH_1):GND

Q_CAP  I54  PC1186_P0_4  [Q_CAP_0805-22UF,4V,20%,EMPTY,TA]
    1  PVCCFA_EHV_FIVRA_CPU0      A  @S9S_MB_2U_LIB.S9S_MB_2U(SCH_1):PVCCFA_EHV_FIVRA_CPU0
    2  GND                B  @S9S_MB_2U_LIB.S9S_MB_2U(SCH_1):GND

Q_CAPP  I61  PC1187  [Q_CAPP_SMLF-470UF,2.5V,20%,EMPA]
    1  PVCCFA_EHV_FIVRA_CPU0      A  @S9S_MB_2U_LIB.S9S_MB_2U(SCH_1):PVCCFA_EHV_FIVRA_CPU0
    2  GND                B  @S9S_MB_2U_LIB.S9S_MB_2U(SCH_1):GND

Q_CAP  I68  PC1187_P0_3  [Q_CAP_0805-22UF,4V,20%,EMPTY,TA]
    1  PVCCFA_EHV_FIVRA_CPU0      A  @S9S_MB_2U_LIB.S9S_MB_2U(SCH_1):PVCCFA_EHV_FIVRA_CPU0
    2  GND                B  @S9S_MB_2U_LIB.S9S_MB_2U(SCH_1):GND

Q_CAP  I55  PC1188_P0_4  [Q_CAP_0805-22UF,4V,20%,EMPTY,TA]
    1  PVCCFA_EHV_FIVRA_CPU0      A  @S9S_MB_2U_LIB.S9S_MB_2U(SCH_1):PVCCFA_EHV_FIVRA_CPU0
    2  GND                B  @S9S_MB_2U_LIB.S9S_MB_2U(SCH_1):GND

Q_CAPP  I73  PC1189  [Q_CAPP_THLF-270UF,16V,20%,OSCOA]
    1  SW_P12V_PVCCFA_EHV_FIVRA_CPU0_R      A  @S9S_MB_2U_LIB.S9S_MB_2U(SCH_1):SW_P12V_PVCCFA_EHV_FIVRA_CPU0_R
    2  GND                B  @S9S_MB_2U_LIB.S9S_MB_2U(SCH_1):GND

Q_CAP  I20  PC1191  [Q_CAP_C0402-2.2UF,10V,10%,X6S,A]
    1  PVCCFA_EHV_FIVRA_CPU1_VDD3      A  @S9S_MB_2U_LIB.S9S_MB_2U(SCH_1):PVCCFA_EHV_FIVRA_CPU1_VDD3
    2  GND                B  @S9S_MB_2U_LIB.S9S_MB_2U(SCH_1):GND

Q_CAP  I9   PC1192  [Q_CAP_C0402-2.2UF,10V,10%,X6S,A]
    1  PVCCFA_EHV_FIVRA_CPU1_VDD4      A  @S9S_MB_2U_LIB.S9S_MB_2U(SCH_1):PVCCFA_EHV_FIVRA_CPU1_VDD4
    2  GND                B  @S9S_MB_2U_LIB.S9S_MB_2U(SCH_1):GND

Q_CAP  I81  PC1193  [Q_CAP_C0402-1UF,16V,10%,X6S,CHA]
    1  PVCCINFAON_CPU1_VREF      A  @S9S_MB_2U_LIB.S9S_MB_2U(SCH_1):PVCCINFAON_CPU1_VREF
    2  GND                B  @S9S_MB_2U_LIB.S9S_MB_2U(SCH_1):GND

Q_CAP  I44  PC1193_P1_3  [Q_CAP_0402-3300PF,50V,10%,X7R,A]
    1  SW_P12V_PVCCFA_EHV_FIVRA_CPU1_R      A  @S9S_MB_2U_LIB.S9S_MB_2U(SCH_1):SW_P12V_PVCCFA_EHV_FIVRA_CPU1_R
    2  GND                B  @S9S_MB_2U_LIB.S9S_MB_2U(SCH_1):GND

Q_CAP  I255  PC1194  [Q_CAP_C0402-1UF,16V,10%,X6S,CHA]
    1  PVCCIN_CPU1_VREF      A  @S9S_MB_2U_LIB.S9S_MB_2U(SCH_1):PVCCIN_CPU1_VREF
    2  GND                B  @S9S_MB_2U_LIB.S9S_MB_2U(SCH_1):GND

Q_CAP  I33  PC1194_P1_4  [Q_CAP_0402-3300PF,50V,10%,X7R,A]
    1  SW_P12V_PVCCFA_EHV_FIVRA_CPU1_L      A  @S9S_MB_2U_LIB.S9S_MB_2U(SCH_1):SW_P12V_PVCCFA_EHV_FIVRA_CPU1_L
    2  GND                B  @S9S_MB_2U_LIB.S9S_MB_2U(SCH_1):GND

Q_CAP  I45  PC1195_P1_3  [Q_CAP_C0402-1UF,16V,10%,X6S,CHA]
    1  SW_P12V_PVCCFA_EHV_FIVRA_CPU1_R      A  @S9S_MB_2U_LIB.S9S_MB_2U(SCH_1):SW_P12V_PVCCFA_EHV_FIVRA_CPU1_R
    2  GND                B  @S9S_MB_2U_LIB.S9S_MB_2U(SCH_1):GND

Q_CAP  I64  PC1196  [Q_CAP_C0402-1UF,16V,10%,X6S,CHA]
    1  PVCCD_HV_CPU0_VREF      A  @S9S_MB_2U_LIB.S9S_MB_2U(SCH_1):PVCCD_HV_CPU0_VREF
    2  GND                B  @S9S_MB_2U_LIB.S9S_MB_2U(SCH_1):GND

Q_CAP  I35  PC1196_P1_4  [Q_CAP_C0402-1UF,16V,10%,X6S,CHA]
    1  SW_P12V_PVCCFA_EHV_FIVRA_CPU1_L      A  @S9S_MB_2U_LIB.S9S_MB_2U(SCH_1):SW_P12V_PVCCFA_EHV_FIVRA_CPU1_L
    2  GND                B  @S9S_MB_2U_LIB.S9S_MB_2U(SCH_1):GND

Q_CAP  I48  PC1197  [Q_CAP_C0402-100NF,50V,10%,X7R,A]
    2  SW_PVCCFA_EHV_FIVRA_CPU1_BOOTR3      B  @S9S_MB_2U_LIB.S9S_MB_2U(SCH_1):SW_PVCCFA_EHV_FIVRA_CPU1_BOOTR3
    1  SW_PVCCFA_EHV_FIVRA_CPU1_BOOT3_      A  @S9S_MB_2U_LIB.S9S_MB_2U(SCH_1):SW_PVCCFA_EHV_FIVRA_CPU1_BOOT3_R

Q_CAP  I31  PC1198  [Q_CAP_C0402-100NF,50V,10%,X7R,A]
    2  SW_PVCCFA_EHV_FIVRA_CPU1_BOOTR4      B  @S9S_MB_2U_LIB.S9S_MB_2U(SCH_1):SW_PVCCFA_EHV_FIVRA_CPU1_BOOTR4
    1  SW_PVCCFA_EHV_FIVRA_CPU1_BOOT4_      A  @S9S_MB_2U_LIB.S9S_MB_2U(SCH_1):SW_PVCCFA_EHV_FIVRA_CPU1_BOOT4_R

Q_CAP  I46  PC1199_P1_3  [Q_CAP_C0805-22UF,16V,20%,X6S,CA]
    1  SW_P12V_PVCCFA_EHV_FIVRA_CPU1_R      A  @S9S_MB_2U_LIB.S9S_MB_2U(SCH_1):SW_P12V_PVCCFA_EHV_FIVRA_CPU1_R
    2  GND                B  @S9S_MB_2U_LIB.S9S_MB_2U(SCH_1):GND

Q_CAP  I36  PC1200_P1_4  [Q_CAP_C0805-22UF,16V,20%,X6S,CA]
    1  SW_P12V_PVCCFA_EHV_FIVRA_CPU1_L      A  @S9S_MB_2U_LIB.S9S_MB_2U(SCH_1):SW_P12V_PVCCFA_EHV_FIVRA_CPU1_L
    2  GND                B  @S9S_MB_2U_LIB.S9S_MB_2U(SCH_1):GND

Q_CAPP  I55  PC1201  [Q_CAPP_THLF-560UF,2.5V,20%,OSCA]
    1  PVCCFA_EHV_FIVRA_CPU1      A  @S9S_MB_2U_LIB.S9S_MB_2U(SCH_1):PVCCFA_EHV_FIVRA_CPU1
    2  GND                B  @S9S_MB_2U_LIB.S9S_MB_2U(SCH_1):GND

Q_CAP  I51  PC1201_P1_3  [Q_CAP_C0805-22UF,16V,20%,X6S,CA]
    1  SW_P12V_PVCCFA_EHV_FIVRA_CPU1_R      A  @S9S_MB_2U_LIB.S9S_MB_2U(SCH_1):SW_P12V_PVCCFA_EHV_FIVRA_CPU1_R
    2  GND                B  @S9S_MB_2U_LIB.S9S_MB_2U(SCH_1):GND

Q_CAP  I37  PC1202_P1_4  [Q_CAP_C0805-22UF,16V,20%,X6S,CA]
    1  SW_P12V_PVCCFA_EHV_FIVRA_CPU1_L      A  @S9S_MB_2U_LIB.S9S_MB_2U(SCH_1):SW_P12V_PVCCFA_EHV_FIVRA_CPU1_L
    2  GND                B  @S9S_MB_2U_LIB.S9S_MB_2U(SCH_1):GND

Q_CAPP  I56  PC1203  [Q_CAPP_THLF-560UF,2.5V,20%,OSCA]
    1  PVCCFA_EHV_FIVRA_CPU1      A  @S9S_MB_2U_LIB.S9S_MB_2U(SCH_1):PVCCFA_EHV_FIVRA_CPU1
    2  GND                B  @S9S_MB_2U_LIB.S9S_MB_2U(SCH_1):GND

Q_CAP  I80  PC1203_P1_4  [Q_CAP_C0402-100NF,50V,10%,X7R,A]
    1  PVCCFA_EHV_FIVRA_CPU1      A  @S9S_MB_2U_LIB.S9S_MB_2U(SCH_1):PVCCFA_EHV_FIVRA_CPU1
    2  GND                B  @S9S_MB_2U_LIB.S9S_MB_2U(SCH_1):GND

Q_CAPP  I59  PC1204  [Q_CAPP_THLF-560UF,2.5V,20%,OSCA]
    1  PVCCFA_EHV_FIVRA_CPU1      A  @S9S_MB_2U_LIB.S9S_MB_2U(SCH_1):PVCCFA_EHV_FIVRA_CPU1
    2  GND                B  @S9S_MB_2U_LIB.S9S_MB_2U(SCH_1):GND

Q_CAP  I66  PC1204_P1_3  [Q_CAP_C0402-1UF,16V,10%,X6S,CHA]
    1  PVCCFA_EHV_FIVRA_CPU1      A  @S9S_MB_2U_LIB.S9S_MB_2U(SCH_1):PVCCFA_EHV_FIVRA_CPU1
    2  GND                B  @S9S_MB_2U_LIB.S9S_MB_2U(SCH_1):GND

Q_CAPP  I61  PC1205  [Q_CAPP_SMLF-470UF,2.5V,20%,EMPA]
    1  PVCCFA_EHV_FIVRA_CPU1      A  @S9S_MB_2U_LIB.S9S_MB_2U(SCH_1):PVCCFA_EHV_FIVRA_CPU1
    2  GND                B  @S9S_MB_2U_LIB.S9S_MB_2U(SCH_1):GND

Q_CAP  I188  PC1206  [Q_CAP_0805-22UF,4V,20%,X6S,TMPA]
    1  PVNN_MAIN_CPU0      A  @S9S_MB_2U_LIB.S9S_MB_2U(SCH_1):PVNN_MAIN_CPU0
    2  GND                B  @S9S_MB_2U_LIB.S9S_MB_2U(SCH_1):GND

Q_CAP  I67  PC1206_P1_3  [Q_CAP_0805-22UF,4V,20%,X6S,TMPA]
    1  PVCCFA_EHV_FIVRA_CPU1      A  @S9S_MB_2U_LIB.S9S_MB_2U(SCH_1):PVCCFA_EHV_FIVRA_CPU1
    2  GND                B  @S9S_MB_2U_LIB.S9S_MB_2U(SCH_1):GND

Q_CAP  I196  PC1207  [Q_CAP_0805-22UF,4V,20%,X6S,TMPA]
    1  PVNN_MAIN_CPU1      A  @S9S_MB_2U_LIB.S9S_MB_2U(SCH_1):PVNN_MAIN_CPU1
    2  GND                B  @S9S_MB_2U_LIB.S9S_MB_2U(SCH_1):GND

Q_CAP  I75  PC1207_P1_4  [Q_CAP_0805-22UF,4V,20%,X6S,TMPA]
    1  PVCCFA_EHV_FIVRA_CPU1      A  @S9S_MB_2U_LIB.S9S_MB_2U(SCH_1):PVCCFA_EHV_FIVRA_CPU1
    2  GND                B  @S9S_MB_2U_LIB.S9S_MB_2U(SCH_1):GND

Q_CAP  I68  PC1208_P1_3  [Q_CAP_0805-22UF,4V,20%,X6S,TMPA]
    1  PVCCFA_EHV_FIVRA_CPU1      A  @S9S_MB_2U_LIB.S9S_MB_2U(SCH_1):PVCCFA_EHV_FIVRA_CPU1
    2  GND                B  @S9S_MB_2U_LIB.S9S_MB_2U(SCH_1):GND

Q_CAP  I54  PC1209_P1_4  [Q_CAP_0805-22UF,4V,20%,X6S,TMPA]
    1  PVCCFA_EHV_FIVRA_CPU1      A  @S9S_MB_2U_LIB.S9S_MB_2U(SCH_1):PVCCFA_EHV_FIVRA_CPU1
    2  GND                B  @S9S_MB_2U_LIB.S9S_MB_2U(SCH_1):GND

Q_CAPP  I73  PC1210  [Q_CAPP_THLF-270UF,16V,20%,OSCOA]
    1  SW_P12V_PVCCFA_EHV_FIVRA_CPU1_R      A  @S9S_MB_2U_LIB.S9S_MB_2U(SCH_1):SW_P12V_PVCCFA_EHV_FIVRA_CPU1_R
    2  GND                B  @S9S_MB_2U_LIB.S9S_MB_2U(SCH_1):GND

Q_CAP  I48  PC1211_P0_1  [Q_CAP_C0402-2.2UF,10V,10%,X6S,A]
    1  PVCCFA_EHV_FIVRA_CPU0_PVCC1      A  @S9S_MB_2U_LIB.S9S_MB_2U(SCH_1):PVCCFA_EHV_FIVRA_CPU0_PVCC1
    2  GND                B  @S9S_MB_2U_LIB.S9S_MB_2U(SCH_1):GND

Q_CAP  I33  PC1212_P0_2  [Q_CAP_C0402-2.2UF,10V,10%,X6S,A]
    1  PVCCFA_EHV_FIVRA_CPU0_PVCC2      A  @S9S_MB_2U_LIB.S9S_MB_2U(SCH_1):PVCCFA_EHV_FIVRA_CPU0_PVCC2
    2  GND                B  @S9S_MB_2U_LIB.S9S_MB_2U(SCH_1):GND

Q_CAP  I42  PC1213_P0_3  [Q_CAP_C0402-2.2UF,10V,10%,EMPTA]
    1  PVCCFA_EHV_FIVRA_CPU0_PVCC1      A  @S9S_MB_2U_LIB.S9S_MB_2U(SCH_1):PVCCFA_EHV_FIVRA_CPU0_PVCC1
    2  GND                B  @S9S_MB_2U_LIB.S9S_MB_2U(SCH_1):GND

Q_CAP  I26  PC1214_P0_4  [Q_CAP_C0402-2.2UF,10V,10%,EMPTA]
    1  PVCCFA_EHV_FIVRA_CPU0_PVCC2      A  @S9S_MB_2U_LIB.S9S_MB_2U(SCH_1):PVCCFA_EHV_FIVRA_CPU0_PVCC2
    2  GND                B  @S9S_MB_2U_LIB.S9S_MB_2U(SCH_1):GND

Q_CAPP  I5   PC1215  [Q_CAPP_SMLF-100UF,16V,20%,OSCOA]
    1  SW_P12V_AUX_P1V05_PCH_AUX_FLT      A  @S9S_MB_2U_LIB.S9S_MB_2U(SCH_1):SW_P12V_AUX_P1V05_PCH_AUX_FLT
    2  GND                B  @S9S_MB_2U_LIB.S9S_MB_2U(SCH_1):GND

Q_CAP  I24  PC1216  [Q_CAP_C0805-22UF,16V,20%,X6S,CA]
    1  SW_P12V_AUX_P1V05_PCH_AUX_FLT      A  @S9S_MB_2U_LIB.S9S_MB_2U(SCH_1):SW_P12V_AUX_P1V05_PCH_AUX_FLT
    2  GND                B  @S9S_MB_2U_LIB.S9S_MB_2U(SCH_1):GND

Q_CAP  I28  PC1217  [Q_CAP_C0805-22UF,16V,20%,X6S,CA]
    1  SW_P12V_AUX_P1V05_PCH_AUX_FLT      A  @S9S_MB_2U_LIB.S9S_MB_2U(SCH_1):SW_P12V_AUX_P1V05_PCH_AUX_FLT
    2  GND                B  @S9S_MB_2U_LIB.S9S_MB_2U(SCH_1):GND

Q_CAP  I32  PC1218  [Q_CAP_C0805-22UF,16V,20%,X6S,CA]
    1  SW_P12V_AUX_P1V05_PCH_AUX_FLT      A  @S9S_MB_2U_LIB.S9S_MB_2U(SCH_1):SW_P12V_AUX_P1V05_PCH_AUX_FLT
    2  GND                B  @S9S_MB_2U_LIB.S9S_MB_2U(SCH_1):GND

Q_CAP  I33  PC1219  [Q_CAP_0402-0.1UF,25V,10%,X7R,CA]
    1  SW_P12V_AUX_P1V05_PCH_AUX_FLT      A  @S9S_MB_2U_LIB.S9S_MB_2U(SCH_1):SW_P12V_AUX_P1V05_PCH_AUX_FLT
    2  GND                B  @S9S_MB_2U_LIB.S9S_MB_2U(SCH_1):GND

Q_CAP  I36  PC1221  [Q_CAP_0402-0.1UF,25V,10%,X7R,CA]
    2  SH_P1V05_PCH_AUX_N      B  @S9S_MB_2U_LIB.S9S_MB_2U(SCH_1):SH_P1V05_PCH_AUX_N
    1  P1V05_PCH_AUX_REF      A  @S9S_MB_2U_LIB.S9S_MB_2U(SCH_1):P1V05_PCH_AUX_REF

Q_CAP  I37  PC1222  [Q_CAP_0402-0.22UF,16V,10%,X7R,A]
    2  SW_P1V05_PCH_AUX_SW      B  @S9S_MB_2U_LIB.S9S_MB_2U(SCH_1):SW_P1V05_PCH_AUX_SW
    1  SW_P1V05_PCH_AUX_BST      A  @S9S_MB_2U_LIB.S9S_MB_2U(SCH_1):SW_P1V05_PCH_AUX_BST

Q_CAP  I42  PC1223  [Q_CAP_C0402-470PF,50V,5%,NPO,CA]
    2  SH_P1V05_PCH_AUX_P      B  @S9S_MB_2U_LIB.S9S_MB_2U(SCH_1):SH_P1V05_PCH_AUX_P
    1  P1V05_PCH_AUX_FB      A  @S9S_MB_2U_LIB.S9S_MB_2U(SCH_1):P1V05_PCH_AUX_FB

Q_CAP  I45  PC1224  [Q_CAP_0402-0.1UF,25V,10%,X7R,CA]
    1  P1V05_PCH_AUX      A  @S9S_MB_2U_LIB.S9S_MB_2U(SCH_1):P1V05_PCH_AUX
    2  GND                B  @S9S_MB_2U_LIB.S9S_MB_2U(SCH_1):GND

Q_CAP  I47  PC1225  [Q_CAP_0805-47UF,4V,20%,X6S,CH6A]
    1  P1V05_PCH_AUX      A  @S9S_MB_2U_LIB.S9S_MB_2U(SCH_1):P1V05_PCH_AUX
    2  GND                B  @S9S_MB_2U_LIB.S9S_MB_2U(SCH_1):GND

Q_CAP  I48  PC1226  [Q_CAP_0805-47UF,4V,20%,X6S,CH6A]
    1  P1V05_PCH_AUX      A  @S9S_MB_2U_LIB.S9S_MB_2U(SCH_1):P1V05_PCH_AUX
    2  GND                B  @S9S_MB_2U_LIB.S9S_MB_2U(SCH_1):GND

Q_CAPP  I16  PC1227  [Q_CAPP_THLF-560UF,2.5V,20%,OSCA]
    1  P1V05_PCH_AUX      A  @S9S_MB_2U_LIB.S9S_MB_2U(SCH_1):P1V05_PCH_AUX
    2  GND                B  @S9S_MB_2U_LIB.S9S_MB_2U(SCH_1):GND

Q_CAPP  I52  PC1229  [Q_CAPP_SMLF-470UF,2V,20%,EMPTYA]
    1  P1V05_PCH_AUX      A  @S9S_MB_2U_LIB.S9S_MB_2U(SCH_1):P1V05_PCH_AUX
    2  GND                B  @S9S_MB_2U_LIB.S9S_MB_2U(SCH_1):GND

Q_CAPP  I18  PC1230  [Q_CAPP_THLF-560UF,2.5V,20%,OSCA]
    1  P1V05_PCH_AUX      A  @S9S_MB_2U_LIB.S9S_MB_2U(SCH_1):P1V05_PCH_AUX
    2  GND                B  @S9S_MB_2U_LIB.S9S_MB_2U(SCH_1):GND

Q_CAP  I28  PC1232  [Q_CAP_C0805-10UF,16V,10%,X6S,CA]
    1  SW_P1V8_PCH_AUX_FLT      A  @S9S_MB_2U_LIB.S9S_MB_2U(SCH_1):SW_P1V8_PCH_AUX_FLT
    2  GND                B  @S9S_MB_2U_LIB.S9S_MB_2U(SCH_1):GND

Q_CAP  I30  PC1233  [Q_CAP_C0805-10UF,16V,10%,X6S,CA]
    1  SW_P1V8_PCH_AUX_FLT      A  @S9S_MB_2U_LIB.S9S_MB_2U(SCH_1):SW_P1V8_PCH_AUX_FLT
    2  GND                B  @S9S_MB_2U_LIB.S9S_MB_2U(SCH_1):GND

Q_CAP  I31  PC1234  [Q_CAP_C0402-100NF,50V,10%,X7R,A]
    1  SW_P1V8_PCH_AUX_FLT      A  @S9S_MB_2U_LIB.S9S_MB_2U(SCH_1):SW_P1V8_PCH_AUX_FLT
    2  GND                B  @S9S_MB_2U_LIB.S9S_MB_2U(SCH_1):GND

Q_CAP  I32  PC1235  [Q_CAP_0402-0.22UF,16V,10%,X7R,A]
    2  SW_P1V8_PCH_AUX_SW      B  @S9S_MB_2U_LIB.S9S_MB_2U(SCH_1):SW_P1V8_PCH_AUX_SW
    1  SW_P1V8_PCH_AUX_BST      A  @S9S_MB_2U_LIB.S9S_MB_2U(SCH_1):SW_P1V8_PCH_AUX_BST

Q_CAP  I23  PC1236  [Q_CAP_C0402-100NF,50V,10%,X7R,A]
    1  P1V8_PCH_AUX       A  @S9S_MB_2U_LIB.S9S_MB_2U(SCH_1):P1V8_PCH_AUX
    2  GND                B  @S9S_MB_2U_LIB.S9S_MB_2U(SCH_1):GND

Q_CAP  I25  PC1237  [Q_CAP_0805-22UF,4V,20%,X6S,TMPA]
    1  P1V8_PCH_AUX       A  @S9S_MB_2U_LIB.S9S_MB_2U(SCH_1):P1V8_PCH_AUX
    2  GND                B  @S9S_MB_2U_LIB.S9S_MB_2U(SCH_1):GND

Q_CAP  I37  PC1238  [Q_CAP_0805-22UF,4V,20%,X6S,TMPA]
    1  P1V8_PCH_AUX       A  @S9S_MB_2U_LIB.S9S_MB_2U(SCH_1):P1V8_PCH_AUX
    2  GND                B  @S9S_MB_2U_LIB.S9S_MB_2U(SCH_1):GND

Q_CAP  I38  PC1239  [Q_CAP_0805-22UF,4V,20%,X6S,TMPA]
    1  P1V8_PCH_AUX       A  @S9S_MB_2U_LIB.S9S_MB_2U(SCH_1):P1V8_PCH_AUX
    2  GND                B  @S9S_MB_2U_LIB.S9S_MB_2U(SCH_1):GND

Q_CAP  I39  PC1240  [Q_CAP_0805-22UF,4V,20%,X6S,TMPA]
    1  P1V8_PCH_AUX       A  @S9S_MB_2U_LIB.S9S_MB_2U(SCH_1):P1V8_PCH_AUX
    2  GND                B  @S9S_MB_2U_LIB.S9S_MB_2U(SCH_1):GND

Q_CAP  I41  PC1241  [Q_CAP_0805-22UF,4V,20%,X6S,TMPA]
    1  P1V8_PCH_AUX       A  @S9S_MB_2U_LIB.S9S_MB_2U(SCH_1):P1V8_PCH_AUX
    2  GND                B  @S9S_MB_2U_LIB.S9S_MB_2U(SCH_1):GND

Q_CAP  I234  PC1242_P1_1  [Q_CAP_C0402-2.2UF,10V,10%,X6S,A]
    1  PVCCFA_EHV_FIVRA_CPU1_PVCC1      A  @S9S_MB_2U_LIB.S9S_MB_2U(SCH_1):PVCCFA_EHV_FIVRA_CPU1_PVCC1
    2  GND                B  @S9S_MB_2U_LIB.S9S_MB_2U(SCH_1):GND

Q_CAP  I217  PC1243_P1_2  [Q_CAP_C0402-2.2UF,10V,10%,X6S,A]
    1  PVCCFA_EHV_FIVRA_CPU1_PVCC2      A  @S9S_MB_2U_LIB.S9S_MB_2U(SCH_1):PVCCFA_EHV_FIVRA_CPU1_PVCC2
    2  GND                B  @S9S_MB_2U_LIB.S9S_MB_2U(SCH_1):GND

Q_CAP  I42  PC1244_P1_3  [Q_CAP_C0402-2.2UF,10V,10%,X6S,A]
    1  PVCCFA_EHV_FIVRA_CPU1_PVCC1      A  @S9S_MB_2U_LIB.S9S_MB_2U(SCH_1):PVCCFA_EHV_FIVRA_CPU1_PVCC1
    2  GND                B  @S9S_MB_2U_LIB.S9S_MB_2U(SCH_1):GND

Q_CAP  I26  PC1245_P1_4  [Q_CAP_C0402-2.2UF,10V,10%,X6S,A]
    1  PVCCFA_EHV_FIVRA_CPU1_PVCC2      A  @S9S_MB_2U_LIB.S9S_MB_2U(SCH_1):PVCCFA_EHV_FIVRA_CPU1_PVCC2
    2  GND                B  @S9S_MB_2U_LIB.S9S_MB_2U(SCH_1):GND

Q_CAP  I10  PC1247  [Q_CAP_C0805-22UF,16V,20%,EMPTYA]
    1  SW_P12V_PVCCIN_CPU0_FLT      A  @S9S_MB_2U_LIB.S9S_MB_2U(SCH_1):SW_P12V_PVCCIN_CPU0_FLT
    2  GND                B  @S9S_MB_2U_LIB.S9S_MB_2U(SCH_1):GND

Q_CAP  I17  PC1248  [Q_CAP_C0805-22UF,16V,20%,EMPTYA]
    1  SW_P12V_PVCCIN_CPU0_FLT      A  @S9S_MB_2U_LIB.S9S_MB_2U(SCH_1):SW_P12V_PVCCIN_CPU0_FLT
    2  GND                B  @S9S_MB_2U_LIB.S9S_MB_2U(SCH_1):GND

Q_CAP  I18  PC1249  [Q_CAP_0402-0.1UF,25V,10%,EMPTYA]
    1  SW_P12V_PVCCIN_CPU0_FLT      A  @S9S_MB_2U_LIB.S9S_MB_2U(SCH_1):SW_P12V_PVCCIN_CPU0_FLT
    2  GND                B  @S9S_MB_2U_LIB.S9S_MB_2U(SCH_1):GND

Q_CAP  I46  PC1251  [Q_CAP_0402-0.1UF,25V,10%,EMPTYA]
    2  SH_PVPP_HBM_CPU0_N      B  @S9S_MB_2U_LIB.S9S_MB_2U(SCH_1):SH_PVPP_HBM_CPU0_N
    1  PVPP_HBM_CPU0_REF      A  @S9S_MB_2U_LIB.S9S_MB_2U(SCH_1):PVPP_HBM_CPU0_REF

Q_CAP  I23  PC1252  [Q_CAP_0402-0.22UF,16V,10%,EMPTA]
    2  SW_PVPP_HBM_CPU0_SW      B  @S9S_MB_2U_LIB.S9S_MB_2U(SCH_1):SW_PVPP_HBM_CPU0_SW
    1  SW_PVPP_HBM_CPU0_BST      A  @S9S_MB_2U_LIB.S9S_MB_2U(SCH_1):SW_PVPP_HBM_CPU0_BST

Q_CAP  I52  PC1253  [Q_CAP_0402-100PF,50V,5%,EMPTY,A]
    2  SH_PVPP_HBM_CPU0_P      B  @S9S_MB_2U_LIB.S9S_MB_2U(SCH_1):SH_PVPP_HBM_CPU0_P
    1  PVPP_HBM_CPU0_FB      A  @S9S_MB_2U_LIB.S9S_MB_2U(SCH_1):PVPP_HBM_CPU0_FB

Q_CAP  I34  PC1254  [Q_CAP_0402-0.1UF,25V,10%,EMPTYA]
    1  PVPP_HBM_CPU0      A  @S9S_MB_2U_LIB.S9S_MB_2U(SCH_1):PVPP_HBM_CPU0
    2  GND                B  @S9S_MB_2U_LIB.S9S_MB_2U(SCH_1):GND

Q_CAP  I37  PC1255  [Q_CAP_0805-22UF,4V,20%,EMPTY,TA]
    1  PVPP_HBM_CPU0      A  @S9S_MB_2U_LIB.S9S_MB_2U(SCH_1):PVPP_HBM_CPU0
    2  GND                B  @S9S_MB_2U_LIB.S9S_MB_2U(SCH_1):GND

Q_CAP  I38  PC1256  [Q_CAP_0805-22UF,4V,20%,EMPTY,TA]
    1  PVPP_HBM_CPU0      A  @S9S_MB_2U_LIB.S9S_MB_2U(SCH_1):PVPP_HBM_CPU0
    2  GND                B  @S9S_MB_2U_LIB.S9S_MB_2U(SCH_1):GND

Q_CAP  I39  PC1257  [Q_CAP_0805-22UF,4V,20%,EMPTY,TA]
    1  PVPP_HBM_CPU0      A  @S9S_MB_2U_LIB.S9S_MB_2U(SCH_1):PVPP_HBM_CPU0
    2  GND                B  @S9S_MB_2U_LIB.S9S_MB_2U(SCH_1):GND

Q_CAPP  I42  PC1258  [Q_CAPP_THLF-560UF,6.3V,20%,EMPA]
    1  PVPP_HBM_CPU0      A  @S9S_MB_2U_LIB.S9S_MB_2U(SCH_1):PVPP_HBM_CPU0
    2  GND                B  @S9S_MB_2U_LIB.S9S_MB_2U(SCH_1):GND

Q_CAP  I4   PC1259  [Q_CAP_C0805-22UF,16V,20%,X6S,CA]
    1  SW_P12V_PVCCIN_CPU1_FLT      A  @S9S_MB_2U_LIB.S9S_MB_2U(SCH_1):SW_P12V_PVCCIN_CPU1_FLT
    2  GND                B  @S9S_MB_2U_LIB.S9S_MB_2U(SCH_1):GND

Q_CAP  I19  PC1260  [Q_CAP_C0805-22UF,16V,20%,X6S,CA]
    1  SW_P12V_PVCCIN_CPU1_FLT      A  @S9S_MB_2U_LIB.S9S_MB_2U(SCH_1):SW_P12V_PVCCIN_CPU1_FLT
    2  GND                B  @S9S_MB_2U_LIB.S9S_MB_2U(SCH_1):GND

Q_CAP  I20  PC1261  [Q_CAP_C0805-22UF,16V,20%,X6S,CA]
    1  SW_P12V_PVCCIN_CPU1_FLT      A  @S9S_MB_2U_LIB.S9S_MB_2U(SCH_1):SW_P12V_PVCCIN_CPU1_FLT
    2  GND                B  @S9S_MB_2U_LIB.S9S_MB_2U(SCH_1):GND

Q_CAP  I21  PC1262  [Q_CAP_0402-0.1UF,25V,10%,X7R,CA]
    1  SW_P12V_PVCCIN_CPU1_FLT      A  @S9S_MB_2U_LIB.S9S_MB_2U(SCH_1):SW_P12V_PVCCIN_CPU1_FLT
    2  GND                B  @S9S_MB_2U_LIB.S9S_MB_2U(SCH_1):GND

Q_CAP  I48  PC1264  [Q_CAP_0402-0.1UF,25V,10%,X7R,CA]
    2  SH_PVPP_HBM_CPU1_N      B  @S9S_MB_2U_LIB.S9S_MB_2U(SCH_1):SH_PVPP_HBM_CPU1_N
    1  PVPP_HBM_CPU1_REF      A  @S9S_MB_2U_LIB.S9S_MB_2U(SCH_1):PVPP_HBM_CPU1_REF

Q_CAP  I22  PC1265  [Q_CAP_0402-0.22UF,16V,10%,X7R,A]
    2  SW_PVPP_HBM_CPU1_SW      B  @S9S_MB_2U_LIB.S9S_MB_2U(SCH_1):SW_PVPP_HBM_CPU1_SW
    1  SW_PVPP_HBM_CPU1_BST      A  @S9S_MB_2U_LIB.S9S_MB_2U(SCH_1):SW_PVPP_HBM_CPU1_BST

Q_CAP  I52  PC1266  [Q_CAP_0402-100PF,50V,5%,NPO,CHA]
    2  SH_PVPP_HBM_CPU1_P      B  @S9S_MB_2U_LIB.S9S_MB_2U(SCH_1):SH_PVPP_HBM_CPU1_P
    1  PVPP_HBM_CPU1_FB      A  @S9S_MB_2U_LIB.S9S_MB_2U(SCH_1):PVPP_HBM_CPU1_FB

Q_CAP  I30  PC1267  [Q_CAP_0402-0.1UF,25V,10%,X7R,CA]
    1  PVPP_HBM_CPU1      A  @S9S_MB_2U_LIB.S9S_MB_2U(SCH_1):PVPP_HBM_CPU1
    2  GND                B  @S9S_MB_2U_LIB.S9S_MB_2U(SCH_1):GND

Q_CAP  I31  PC1268  [Q_CAP_0805-22UF,4V,20%,X6S,TMPA]
    1  PVPP_HBM_CPU1      A  @S9S_MB_2U_LIB.S9S_MB_2U(SCH_1):PVPP_HBM_CPU1
    2  GND                B  @S9S_MB_2U_LIB.S9S_MB_2U(SCH_1):GND

Q_CAP  I32  PC1269  [Q_CAP_0805-22UF,4V,20%,X6S,TMPA]
    1  PVPP_HBM_CPU1      A  @S9S_MB_2U_LIB.S9S_MB_2U(SCH_1):PVPP_HBM_CPU1
    2  GND                B  @S9S_MB_2U_LIB.S9S_MB_2U(SCH_1):GND

Q_CAP  I35  PC1270  [Q_CAP_0805-22UF,4V,20%,X6S,TMPA]
    1  PVPP_HBM_CPU1      A  @S9S_MB_2U_LIB.S9S_MB_2U(SCH_1):PVPP_HBM_CPU1
    2  GND                B  @S9S_MB_2U_LIB.S9S_MB_2U(SCH_1):GND

Q_CAP  I56  PC1271  [Q_CAP_0402-470PF,50V,10%,X7R,TA]
    1  PVCCFA_EHV_CPU0_BTSEN      A  @S9S_MB_2U_LIB.S9S_MB_2U(SCH_1):PVCCFA_EHV_CPU0_BTSEN
    2  GND                B  @S9S_MB_2U_LIB.S9S_MB_2U(SCH_1):GND

Q_CAP  I164  PC1272  [Q_CAP_C0805-22UF,16V,20%,X6S,CA]
    1  SW_P12V_PVCCINFAON_CPU0_FLT      A  @S9S_MB_2U_LIB.S9S_MB_2U(SCH_1):SW_P12V_PVCCINFAON_CPU0_FLT
    2  GND                B  @S9S_MB_2U_LIB.S9S_MB_2U(SCH_1):GND

Q_CAP  I165  PC1273  [Q_CAP_C0805-22UF,16V,20%,X6S,CA]
    1  SW_P12V_PVCCINFAON_CPU0_FLT      A  @S9S_MB_2U_LIB.S9S_MB_2U(SCH_1):SW_P12V_PVCCINFAON_CPU0_FLT
    2  GND                B  @S9S_MB_2U_LIB.S9S_MB_2U(SCH_1):GND

Q_CAP  I166  PC1274  [Q_CAP_C0402-100NF,50V,10%,X7R,A]
    1  SW_P12V_PVCCINFAON_CPU0_FLT      A  @S9S_MB_2U_LIB.S9S_MB_2U(SCH_1):SW_P12V_PVCCINFAON_CPU0_FLT
    2  GND                B  @S9S_MB_2U_LIB.S9S_MB_2U(SCH_1):GND

Q_CAP  I176  PC1275  [Q_CAP_0402-0.22UF,16V,10%,X7R,A]
    2  SW_PVNN_MAIN_CPU0_SW      B  @S9S_MB_2U_LIB.S9S_MB_2U(SCH_1):SW_PVNN_MAIN_CPU0_SW
    1  SW_PVNN_MAIN_CPU0_BST      A  @S9S_MB_2U_LIB.S9S_MB_2U(SCH_1):SW_PVNN_MAIN_CPU0_BST

Q_CAP  I183  PC1276  [Q_CAP_C0402-100NF,50V,10%,X7R,A]
    1  PVNN_MAIN_CPU0      A  @S9S_MB_2U_LIB.S9S_MB_2U(SCH_1):PVNN_MAIN_CPU0
    2  GND                B  @S9S_MB_2U_LIB.S9S_MB_2U(SCH_1):GND

Q_CAP  I184  PC1277  [Q_CAP_0805-22UF,4V,20%,X6S,TMPA]
    1  PVNN_MAIN_CPU0      A  @S9S_MB_2U_LIB.S9S_MB_2U(SCH_1):PVNN_MAIN_CPU0
    2  GND                B  @S9S_MB_2U_LIB.S9S_MB_2U(SCH_1):GND

Q_CAP  I185  PC1278  [Q_CAP_0805-22UF,4V,20%,X6S,TMPA]
    1  PVNN_MAIN_CPU0      A  @S9S_MB_2U_LIB.S9S_MB_2U(SCH_1):PVNN_MAIN_CPU0
    2  GND                B  @S9S_MB_2U_LIB.S9S_MB_2U(SCH_1):GND

Q_CAP  I186  PC1279  [Q_CAP_0805-22UF,4V,20%,X6S,TMPA]
    1  PVNN_MAIN_CPU0      A  @S9S_MB_2U_LIB.S9S_MB_2U(SCH_1):PVNN_MAIN_CPU0
    2  GND                B  @S9S_MB_2U_LIB.S9S_MB_2U(SCH_1):GND

Q_CAP  I169  PC1280  [Q_CAP_C0805-22UF,16V,20%,X6S,CA]
    1  SW_P12V_PVCCINFAON_CPU1_FLT      A  @S9S_MB_2U_LIB.S9S_MB_2U(SCH_1):SW_P12V_PVCCINFAON_CPU1_FLT
    2  GND                B  @S9S_MB_2U_LIB.S9S_MB_2U(SCH_1):GND

Q_CAP  I170  PC1281  [Q_CAP_C0805-22UF,16V,20%,X6S,CA]
    1  SW_P12V_PVCCINFAON_CPU1_FLT      A  @S9S_MB_2U_LIB.S9S_MB_2U(SCH_1):SW_P12V_PVCCINFAON_CPU1_FLT
    2  GND                B  @S9S_MB_2U_LIB.S9S_MB_2U(SCH_1):GND

Q_CAP  I175  PC1282  [Q_CAP_C0402-100NF,50V,10%,X7R,A]
    1  SW_P12V_PVCCINFAON_CPU1_FLT      A  @S9S_MB_2U_LIB.S9S_MB_2U(SCH_1):SW_P12V_PVCCINFAON_CPU1_FLT
    2  GND                B  @S9S_MB_2U_LIB.S9S_MB_2U(SCH_1):GND

Q_CAP  I181  PC1283  [Q_CAP_0402-0.22UF,16V,10%,X7R,A]
    2  SW_PVNN_MAIN_CPU1_SW      B  @S9S_MB_2U_LIB.S9S_MB_2U(SCH_1):SW_PVNN_MAIN_CPU1_SW
    1  SW_PVNN_MAIN_CPU1_BST      A  @S9S_MB_2U_LIB.S9S_MB_2U(SCH_1):SW_PVNN_MAIN_CPU1_BST

Q_CAP  I184  PC1284  [Q_CAP_C0402-100NF,50V,10%,X7R,A]
    1  PVNN_MAIN_CPU1      A  @S9S_MB_2U_LIB.S9S_MB_2U(SCH_1):PVNN_MAIN_CPU1
    2  GND                B  @S9S_MB_2U_LIB.S9S_MB_2U(SCH_1):GND

Q_CAP  I192  PC1285  [Q_CAP_0805-22UF,4V,20%,X6S,TMPA]
    1  PVNN_MAIN_CPU1      A  @S9S_MB_2U_LIB.S9S_MB_2U(SCH_1):PVNN_MAIN_CPU1
    2  GND                B  @S9S_MB_2U_LIB.S9S_MB_2U(SCH_1):GND

Q_CAP  I193  PC1286  [Q_CAP_0805-22UF,4V,20%,X6S,TMPA]
    1  PVNN_MAIN_CPU1      A  @S9S_MB_2U_LIB.S9S_MB_2U(SCH_1):PVNN_MAIN_CPU1
    2  GND                B  @S9S_MB_2U_LIB.S9S_MB_2U(SCH_1):GND

Q_CAP  I194  PC1287  [Q_CAP_0805-22UF,4V,20%,X6S,TMPA]
    1  PVNN_MAIN_CPU1      A  @S9S_MB_2U_LIB.S9S_MB_2U(SCH_1):PVNN_MAIN_CPU1
    2  GND                B  @S9S_MB_2U_LIB.S9S_MB_2U(SCH_1):GND

Q_CAP  I256  PC1289  [Q_CAP_C0402-1UF,16V,10%,X6S,CHA]
    1  PVCCD_HV_CPU1_VREF      A  @S9S_MB_2U_LIB.S9S_MB_2U(SCH_1):PVCCD_HV_CPU1_VREF
    2  GND                B  @S9S_MB_2U_LIB.S9S_MB_2U(SCH_1):GND

Q_CAP  I68  PC1292  [Q_CAP_0402-470PF,50V,10%,X7R,TA]
    1  PVCCFA_EHV_CPU1_BTSEN      A  @S9S_MB_2U_LIB.S9S_MB_2U(SCH_1):PVCCFA_EHV_CPU1_BTSEN
    2  GND                B  @S9S_MB_2U_LIB.S9S_MB_2U(SCH_1):GND

Q_CAP  I210  PC1336  [Q_CAP_C0402-10UF,6.3V,20%,X6S,A]
    1  PVNN_TERM_CPU1      A  @S9S_MB_2U_LIB.S9S_MB_2U(SCH_1):PVNN_TERM_CPU1
    2  GND                B  @S9S_MB_2U_LIB.S9S_MB_2U(SCH_1):GND

Q_CAP  I215  PC1337  [Q_CAP_0402-0.1UF,25V,10%,X7R,CA]
    1  PVNN_TERM_CPU1      A  @S9S_MB_2U_LIB.S9S_MB_2U(SCH_1):PVNN_TERM_CPU1
    2  GND                B  @S9S_MB_2U_LIB.S9S_MB_2U(SCH_1):GND

Q_CAP  I10  PC1338  [Q_CAP_0402-0.1UF,25V,10%,X7R,CA]
    2  PVCCIN_CPU1_VREF      B  @S9S_MB_2U_LIB.S9S_MB_2U(SCH_1):PVCCIN_CPU1_VREF
    1  GND                A  @S9S_MB_2U_LIB.S9S_MB_2U(SCH_1):GND

Q_CAP  I30  PC1339  [Q_CAP_0402-0.1UF,25V,10%,X7R,CA]
    2  PVCCIN_CPU1_VREF      B  @S9S_MB_2U_LIB.S9S_MB_2U(SCH_1):PVCCIN_CPU1_VREF
    1  GND                A  @S9S_MB_2U_LIB.S9S_MB_2U(SCH_1):GND

Q_CAP  I13  PC1340  [Q_CAP_0402-0.1UF,25V,10%,X7R,CA]
    2  PVCCIN_CPU0_VREF      B  @S9S_MB_2U_LIB.S9S_MB_2U(SCH_1):PVCCIN_CPU0_VREF
    1  GND                A  @S9S_MB_2U_LIB.S9S_MB_2U(SCH_1):GND

Q_CAP  I29  PC1341  [Q_CAP_0402-0.1UF,25V,10%,X7R,CA]
    2  PVCCIN_CPU0_VREF      B  @S9S_MB_2U_LIB.S9S_MB_2U(SCH_1):PVCCIN_CPU0_VREF
    1  GND                A  @S9S_MB_2U_LIB.S9S_MB_2U(SCH_1):GND

Q_CAP  I8   PC1342  [Q_CAP_0402-0.1UF,25V,10%,X7R,CA]
    2  PVCCIN_CPU0_VREF      B  @S9S_MB_2U_LIB.S9S_MB_2U(SCH_1):PVCCIN_CPU0_VREF
    1  GND                A  @S9S_MB_2U_LIB.S9S_MB_2U(SCH_1):GND

Q_CAP  I27  PC1343  [Q_CAP_0402-0.1UF,25V,10%,X7R,CA]
    2  PVCCIN_CPU0_VREF      B  @S9S_MB_2U_LIB.S9S_MB_2U(SCH_1):PVCCIN_CPU0_VREF
    1  GND                A  @S9S_MB_2U_LIB.S9S_MB_2U(SCH_1):GND

Q_CAP  I16  PC1344  [Q_CAP_0402-0.1UF,25V,10%,X7R,CA]
    2  PVCCIN_CPU0_VREF      B  @S9S_MB_2U_LIB.S9S_MB_2U(SCH_1):PVCCIN_CPU0_VREF
    1  GND                A  @S9S_MB_2U_LIB.S9S_MB_2U(SCH_1):GND

Q_CAP  I28  PC1345  [Q_CAP_0402-0.1UF,25V,10%,X7R,CA]
    2  PVCCIN_CPU0_VREF      B  @S9S_MB_2U_LIB.S9S_MB_2U(SCH_1):PVCCIN_CPU0_VREF
    1  GND                A  @S9S_MB_2U_LIB.S9S_MB_2U(SCH_1):GND

Q_CAP  I152  PC1346  [Q_CAP_0402-0.1UF,25V,10%,X7R,CA]
    2  PVCCINFAON_CPU0_VREF      B  @S9S_MB_2U_LIB.S9S_MB_2U(SCH_1):PVCCINFAON_CPU0_VREF
    1  GND                A  @S9S_MB_2U_LIB.S9S_MB_2U(SCH_1):GND

Q_CAP  I163  PC1347  [Q_CAP_0402-0.1UF,25V,10%,X7R,CA]
    2  PVCCINFAON_CPU0_VREF      B  @S9S_MB_2U_LIB.S9S_MB_2U(SCH_1):PVCCINFAON_CPU0_VREF
    1  GND                A  @S9S_MB_2U_LIB.S9S_MB_2U(SCH_1):GND

Q_CAP  I7   PC1348  [Q_CAP_0402-0.1UF,25V,10%,X7R,CA]
    2  PVCCINFAON_CPU0_VREF      B  @S9S_MB_2U_LIB.S9S_MB_2U(SCH_1):PVCCINFAON_CPU0_VREF
    1  GND                A  @S9S_MB_2U_LIB.S9S_MB_2U(SCH_1):GND

Q_CAP  I46  PC1349  [Q_CAP_0402-0.1UF,25V,10%,X7R,CA]
    2  PVCCIN_CPU0_VREF      B  @S9S_MB_2U_LIB.S9S_MB_2U(SCH_1):PVCCIN_CPU0_VREF
    1  GND                A  @S9S_MB_2U_LIB.S9S_MB_2U(SCH_1):GND

Q_CAP  I29  PC1350  [Q_CAP_0402-0.1UF,25V,10%,X7R,CA]
    2  PVCCIN_CPU0_VREF      B  @S9S_MB_2U_LIB.S9S_MB_2U(SCH_1):PVCCIN_CPU0_VREF
    1  GND                A  @S9S_MB_2U_LIB.S9S_MB_2U(SCH_1):GND

Q_CAP  I39  PC1351  [Q_CAP_0402-0.1UF,25V,10%,EMPTYA]
    2  PVCCIN_CPU0_VREF      B  @S9S_MB_2U_LIB.S9S_MB_2U(SCH_1):PVCCIN_CPU0_VREF
    1  GND                A  @S9S_MB_2U_LIB.S9S_MB_2U(SCH_1):GND

Q_CAP  I23  PC1352  [Q_CAP_0402-0.1UF,25V,10%,EMPTYA]
    2  PVCCIN_CPU0_VREF      B  @S9S_MB_2U_LIB.S9S_MB_2U(SCH_1):PVCCIN_CPU0_VREF
    1  GND                A  @S9S_MB_2U_LIB.S9S_MB_2U(SCH_1):GND

Q_CAP  I330  PC1354  [Q_CAP_0402-0.1UF,25V,10%,X7R,CA]
    2  PVCCD_HV_CPU0_VREF      B  @S9S_MB_2U_LIB.S9S_MB_2U(SCH_1):PVCCD_HV_CPU0_VREF
    1  GND                A  @S9S_MB_2U_LIB.S9S_MB_2U(SCH_1):GND

Q_CAP  I10  PC1355  [Q_CAP_0402-0.1UF,25V,10%,X7R,CA]
    2  PVCCIN_CPU0_VREF      B  @S9S_MB_2U_LIB.S9S_MB_2U(SCH_1):PVCCIN_CPU0_VREF
    1  GND                A  @S9S_MB_2U_LIB.S9S_MB_2U(SCH_1):GND

Q_CAP  I33  PC1356  [Q_CAP_0402-0.1UF,25V,10%,X7R,CA]
    2  PVCCIN_CPU0_VREF      B  @S9S_MB_2U_LIB.S9S_MB_2U(SCH_1):PVCCIN_CPU0_VREF
    1  GND                A  @S9S_MB_2U_LIB.S9S_MB_2U(SCH_1):GND

Q_CAP  I8   PC1358  [Q_CAP_0402-0.1UF,25V,10%,X7R,CA]
    2  PVCCIN_CPU1_VREF      B  @S9S_MB_2U_LIB.S9S_MB_2U(SCH_1):PVCCIN_CPU1_VREF
    1  GND                A  @S9S_MB_2U_LIB.S9S_MB_2U(SCH_1):GND

Q_CAP  I23  PC1359  [Q_CAP_0402-0.1UF,25V,10%,X7R,CA]
    2  PVCCIN_CPU1_VREF      B  @S9S_MB_2U_LIB.S9S_MB_2U(SCH_1):PVCCIN_CPU1_VREF
    1  GND                A  @S9S_MB_2U_LIB.S9S_MB_2U(SCH_1):GND

Q_CAP  I28  PC1360  [Q_CAP_0402-0.1UF,25V,10%,X7R,CA]
    2  PVCCIN_CPU1_VREF      B  @S9S_MB_2U_LIB.S9S_MB_2U(SCH_1):PVCCIN_CPU1_VREF
    1  GND                A  @S9S_MB_2U_LIB.S9S_MB_2U(SCH_1):GND

Q_CAP  I31  PC1361  [Q_CAP_0402-0.1UF,25V,10%,X7R,CA]
    2  PVCCIN_CPU1_VREF      B  @S9S_MB_2U_LIB.S9S_MB_2U(SCH_1):PVCCIN_CPU1_VREF
    1  GND                A  @S9S_MB_2U_LIB.S9S_MB_2U(SCH_1):GND

Q_CAP  I8   PC1362  [Q_CAP_0402-0.1UF,25V,10%,X7R,CA]
    2  PVCCIN_CPU1_VREF      B  @S9S_MB_2U_LIB.S9S_MB_2U(SCH_1):PVCCIN_CPU1_VREF
    1  GND                A  @S9S_MB_2U_LIB.S9S_MB_2U(SCH_1):GND

Q_CAP  I31  PC1363  [Q_CAP_0402-0.1UF,25V,10%,X7R,CA]
    2  PVCCIN_CPU1_VREF      B  @S9S_MB_2U_LIB.S9S_MB_2U(SCH_1):PVCCIN_CPU1_VREF
    1  GND                A  @S9S_MB_2U_LIB.S9S_MB_2U(SCH_1):GND

Q_CAP  I24  PC1364  [Q_CAP_0402-0.1UF,25V,10%,X7R,CA]
    2  PVCCINFAON_CPU1_VREF      B  @S9S_MB_2U_LIB.S9S_MB_2U(SCH_1):PVCCINFAON_CPU1_VREF
    1  GND                A  @S9S_MB_2U_LIB.S9S_MB_2U(SCH_1):GND

Q_CAP  I11  PC1365  [Q_CAP_0402-0.1UF,25V,10%,X7R,CA]
    2  PVCCINFAON_CPU1_VREF      B  @S9S_MB_2U_LIB.S9S_MB_2U(SCH_1):PVCCINFAON_CPU1_VREF
    1  GND                A  @S9S_MB_2U_LIB.S9S_MB_2U(SCH_1):GND

Q_CAP  I8   PC1366  [Q_CAP_0402-0.1UF,25V,10%,X7R,CA]
    2  PVCCINFAON_CPU1_VREF      B  @S9S_MB_2U_LIB.S9S_MB_2U(SCH_1):PVCCINFAON_CPU1_VREF
    1  GND                A  @S9S_MB_2U_LIB.S9S_MB_2U(SCH_1):GND

Q_CAP  I231  PC1367  [Q_CAP_0402-0.1UF,25V,10%,X7R,CA]
    2  PVCCIN_CPU1_VREF      B  @S9S_MB_2U_LIB.S9S_MB_2U(SCH_1):PVCCIN_CPU1_VREF
    1  GND                A  @S9S_MB_2U_LIB.S9S_MB_2U(SCH_1):GND

Q_CAP  I209  PC1368  [Q_CAP_0402-0.1UF,25V,10%,X7R,CA]
    2  PVCCIN_CPU1_VREF      B  @S9S_MB_2U_LIB.S9S_MB_2U(SCH_1):PVCCIN_CPU1_VREF
    1  GND                A  @S9S_MB_2U_LIB.S9S_MB_2U(SCH_1):GND

Q_CAP  I40  PC1369  [Q_CAP_0402-0.1UF,25V,10%,X7R,CA]
    2  PVCCIN_CPU1_VREF      B  @S9S_MB_2U_LIB.S9S_MB_2U(SCH_1):PVCCIN_CPU1_VREF
    1  GND                A  @S9S_MB_2U_LIB.S9S_MB_2U(SCH_1):GND

Q_CAP  I23  PC1370  [Q_CAP_0402-0.1UF,25V,10%,X7R,CA]
    2  PVCCIN_CPU1_VREF      B  @S9S_MB_2U_LIB.S9S_MB_2U(SCH_1):PVCCIN_CPU1_VREF
    1  GND                A  @S9S_MB_2U_LIB.S9S_MB_2U(SCH_1):GND

Q_CAP  I8   PC1371  [Q_CAP_0402-0.1UF,25V,10%,X7R,CA]
    2  PVCCD_HV_CPU1_VREF      B  @S9S_MB_2U_LIB.S9S_MB_2U(SCH_1):PVCCD_HV_CPU1_VREF
    1  GND                A  @S9S_MB_2U_LIB.S9S_MB_2U(SCH_1):GND

Q_CAP  I90  PC1372  [Q_CAP_C0402-1UF,16V,10%,X6S,CHA]
    1  PVCCINFAON_CPU0_VREF      A  @S9S_MB_2U_LIB.S9S_MB_2U(SCH_1):PVCCINFAON_CPU0_VREF
    2  GND                B  @S9S_MB_2U_LIB.S9S_MB_2U(SCH_1):GND

Q_CAPP  I201  PC1573  [Q_CAPP_SMLF-330UF,2V,35%,SPCAPA]
    1  PVCCINFAON_CPU0      A  @S9S_MB_2U_LIB.S9S_MB_2U(SCH_1):PVCCINFAON_CPU0
    2  GND                B  @S9S_MB_2U_LIB.S9S_MB_2U(SCH_1):GND

Q_CAPP  I199  PC1574  [Q_CAPP_THLF-560UF,2.5V,20%,OSCA]
    1  PVCCINFAON_CPU0      A  @S9S_MB_2U_LIB.S9S_MB_2U(SCH_1):PVCCINFAON_CPU0
    2  GND                B  @S9S_MB_2U_LIB.S9S_MB_2U(SCH_1):GND

Q_CAPP  I202  PC1575  [Q_CAPP_SMLF-330UF,2V,35%,SPCAPA]
    1  PVCCINFAON_CPU0      A  @S9S_MB_2U_LIB.S9S_MB_2U(SCH_1):PVCCINFAON_CPU0
    2  GND                B  @S9S_MB_2U_LIB.S9S_MB_2U(SCH_1):GND

Q_CAPP  I200  PC1576  [Q_CAPP_THLF-560UF,2.5V,20%,OSCA]
    1  PVCCINFAON_CPU0      A  @S9S_MB_2U_LIB.S9S_MB_2U(SCH_1):PVCCINFAON_CPU0
    2  GND                B  @S9S_MB_2U_LIB.S9S_MB_2U(SCH_1):GND

Q_CAPP  I215  PC1579  [Q_CAPP_THLF-560UF,2.5V,20%,OSCA]
    1  PVCCINFAON_CPU0      A  @S9S_MB_2U_LIB.S9S_MB_2U(SCH_1):PVCCINFAON_CPU0
    2  GND                B  @S9S_MB_2U_LIB.S9S_MB_2U(SCH_1):GND

Q_CAPP  I48  PC1588  [Q_CAPP_SMLF-330UF,2V,35%,SPCAPA]
    1  PVCCINFAON_CPU1      A  @S9S_MB_2U_LIB.S9S_MB_2U(SCH_1):PVCCINFAON_CPU1
    2  GND                B  @S9S_MB_2U_LIB.S9S_MB_2U(SCH_1):GND

Q_CAPP  I47  PC1593  [Q_CAPP_THLF-560UF,2.5V,20%,OSCA]
    1  PVCCINFAON_CPU1      A  @S9S_MB_2U_LIB.S9S_MB_2U(SCH_1):PVCCINFAON_CPU1
    2  GND                B  @S9S_MB_2U_LIB.S9S_MB_2U(SCH_1):GND

Q_CAPP  I68  PC1594  [Q_CAPP_SMLF-330UF,2V,35%,SPCAPA]
    1  PVCCINFAON_CPU1      A  @S9S_MB_2U_LIB.S9S_MB_2U(SCH_1):PVCCINFAON_CPU1
    2  GND                B  @S9S_MB_2U_LIB.S9S_MB_2U(SCH_1):GND

Q_CAPP  I67  PC1595  [Q_CAPP_THLF-560UF,2.5V,20%,OSCA]
    1  PVCCINFAON_CPU1      A  @S9S_MB_2U_LIB.S9S_MB_2U(SCH_1):PVCCINFAON_CPU1
    2  GND                B  @S9S_MB_2U_LIB.S9S_MB_2U(SCH_1):GND

Q_CAPP  I69  PC1596  [Q_CAPP_THLF-560UF,2.5V,20%,OSCA]
    1  PVCCINFAON_CPU1      A  @S9S_MB_2U_LIB.S9S_MB_2U(SCH_1):PVCCINFAON_CPU1
    2  GND                B  @S9S_MB_2U_LIB.S9S_MB_2U(SCH_1):GND

Q_CAP  I4   PC1642  [Q_CAP_C0402-1UF,25V,10%,X6S,CHA]
    1  P1V8_PCH_AUX_VCC      A  @S9S_MB_2U_LIB.S9S_MB_2U(SCH_1):P1V8_PCH_AUX_VCC
    2  GND                B  @S9S_MB_2U_LIB.S9S_MB_2U(SCH_1):GND

Q_CAPP  I349  PC1644  [Q_CAPP_THLF-560UF,2.5V,20%,OSCA]
    1  PVCCD_HV_CPU0      A  @S9S_MB_2U_LIB.S9S_MB_2U(SCH_1):PVCCD_HV_CPU0
    2  GND                B  @S9S_MB_2U_LIB.S9S_MB_2U(SCH_1):GND

Q_CAPP  I350  PC1645  [Q_CAPP_THLF-560UF,2.5V,20%,OSCA]
    1  PVCCD_HV_CPU0      A  @S9S_MB_2U_LIB.S9S_MB_2U(SCH_1):PVCCD_HV_CPU0
    2  GND                B  @S9S_MB_2U_LIB.S9S_MB_2U(SCH_1):GND

Q_CAPP  I36  PC1771  [Q_CAPP_THLF-560UF,6.3V,20%,OSCA]
    1  PVPP_HBM_CPU1      A  @S9S_MB_2U_LIB.S9S_MB_2U(SCH_1):PVPP_HBM_CPU1
    2  GND                B  @S9S_MB_2U_LIB.S9S_MB_2U(SCH_1):GND

Q_CAPP  I33  PC1845  [Q_CAPP_SMLF-220UF,6.3V,20%,ALUA]
    1  P5V_AUX            A  @S9S_MB_2U_LIB.S9S_MB_2U(SCH_1):P5V_AUX
    2  GND                B  @S9S_MB_2U_LIB.S9S_MB_2U(SCH_1):GND

Q_CAP  I18  PC1846  [Q_CAP_0402-0.1UF,25V,10%,X7R,CA]
    1  SW_P5V_AUX_FLT      A  @S9S_MB_2U_LIB.S9S_MB_2U(SCH_1):SW_P5V_AUX_FLT
    2  GND                B  @S9S_MB_2U_LIB.S9S_MB_2U(SCH_1):GND

Q_CAP  I26  PC1847  [Q_CAP_0402-0.22UF,16V,10%,X7R,A]
    2  SW_P5V_AUX_SW      B  @S9S_MB_2U_LIB.S9S_MB_2U(SCH_1):SW_P5V_AUX_SW
    1  SW_P5V_AUX_BST      A  @S9S_MB_2U_LIB.S9S_MB_2U(SCH_1):SW_P5V_AUX_BST

Q_CAP  I8   PC1848  [Q_CAP_C0402-1UF,25V,10%,X6S,CHA]
    1  P5V_AUX_VCC        A  @S9S_MB_2U_LIB.S9S_MB_2U(SCH_1):P5V_AUX_VCC
    2  GND                B  @S9S_MB_2U_LIB.S9S_MB_2U(SCH_1):GND

Q_CAP  I12  PC1849  [Q_CAP_C0805-22UF,16V,20%,X6S,CA]
    1  SW_P5V_AUX_FLT      A  @S9S_MB_2U_LIB.S9S_MB_2U(SCH_1):SW_P5V_AUX_FLT
    2  GND                B  @S9S_MB_2U_LIB.S9S_MB_2U(SCH_1):GND

Q_CAP  I14  PC1850  [Q_CAP_C0805-22UF,16V,20%,X6S,CA]
    1  SW_P5V_AUX_FLT      A  @S9S_MB_2U_LIB.S9S_MB_2U(SCH_1):SW_P5V_AUX_FLT
    2  GND                B  @S9S_MB_2U_LIB.S9S_MB_2U(SCH_1):GND

Q_CAP  I37  PC1852  [Q_CAP_0402-0.1UF,25V,10%,X7R,CA]
    1  P5V_AUX            A  @S9S_MB_2U_LIB.S9S_MB_2U(SCH_1):P5V_AUX
    2  GND                B  @S9S_MB_2U_LIB.S9S_MB_2U(SCH_1):GND

Q_CAP  I22  PC1853  [Q_CAP_0402-0.1UF,25V,10%,X7R,CA]
    1  P5V_AUX_REF        A  @S9S_MB_2U_LIB.S9S_MB_2U(SCH_1):P5V_AUX_REF
    2  GND                B  @S9S_MB_2U_LIB.S9S_MB_2U(SCH_1):GND

Q_CAP  I34  PC1855  [Q_CAP_C0805-22UF,10V,20%,X6S,CA]
    1  P5V_AUX            A  @S9S_MB_2U_LIB.S9S_MB_2U(SCH_1):P5V_AUX
    2  GND                B  @S9S_MB_2U_LIB.S9S_MB_2U(SCH_1):GND

Q_CAP  I35  PC1856  [Q_CAP_C0805-22UF,10V,20%,X6S,CA]
    1  P5V_AUX            A  @S9S_MB_2U_LIB.S9S_MB_2U(SCH_1):P5V_AUX
    2  GND                B  @S9S_MB_2U_LIB.S9S_MB_2U(SCH_1):GND

Q_CAPP  I38  PC1866  [Q_CAPP_THLF-560UF,6.3V,20%,OSCA]
    1  P3V3_AUX           A  @S9S_MB_2U_LIB.S9S_MB_2U(SCH_1):P3V3_AUX
    2  GND                B  @S9S_MB_2U_LIB.S9S_MB_2U(SCH_1):GND

Q_CAPP  I39  PC1867  [Q_CAPP_THLF-560UF,6.3V,20%,OSCA]
    1  P3V3_AUX           A  @S9S_MB_2U_LIB.S9S_MB_2U(SCH_1):P3V3_AUX
    2  GND                B  @S9S_MB_2U_LIB.S9S_MB_2U(SCH_1):GND

Q_CAP  I40  PC1868  [Q_CAP_C0805-22UF,10V,20%,X6S,CA]
    1  P3V3_AUX           A  @S9S_MB_2U_LIB.S9S_MB_2U(SCH_1):P3V3_AUX
    2  GND                B  @S9S_MB_2U_LIB.S9S_MB_2U(SCH_1):GND

Q_CAP  I45  PC1869  [Q_CAP_0402-0.1UF,25V,10%,X7R,CA]
    1  P3V3_AUX           A  @S9S_MB_2U_LIB.S9S_MB_2U(SCH_1):P3V3_AUX
    2  GND                B  @S9S_MB_2U_LIB.S9S_MB_2U(SCH_1):GND

Q_CAP  I10  PC1870  [Q_CAP_0402-0.1UF,25V,10%,EMPTYA]
    1  P5V_AUX_EN         A  @S9S_MB_2U_LIB.S9S_MB_2U(SCH_1):P5V_AUX_EN
    2  GND                B  @S9S_MB_2U_LIB.S9S_MB_2U(SCH_1):GND

Q_CAP  I31  PC1877  [Q_CAP_0402-47PF,50V,5%,NPO,TMPA]
    1  P5V_AUX_FB         A  @S9S_MB_2U_LIB.S9S_MB_2U(SCH_1):P5V_AUX_FB
    2  P5V_AUX            B  @S9S_MB_2U_LIB.S9S_MB_2U(SCH_1):P5V_AUX

Q_CAP  I17  PC1898  [Q_CAP_C0805-22UF,16V,20%,X6S,CA]
    1  SW_P5V_AUX_FLT      A  @S9S_MB_2U_LIB.S9S_MB_2U(SCH_1):SW_P5V_AUX_FLT
    2  GND                B  @S9S_MB_2U_LIB.S9S_MB_2U(SCH_1):GND

Q_CAPP  I28  PC1900  [Q_CAPP_SMLF-470UF,2.5V,20%,SPCA]
    1  PVCCFA_EHV_CPU0      A  @S9S_MB_2U_LIB.S9S_MB_2U(SCH_1):PVCCFA_EHV_CPU0
    2  GND                B  @S9S_MB_2U_LIB.S9S_MB_2U(SCH_1):GND

Q_CAPP  I348  PC1910  [Q_CAPP_SMLF-330UF,2V,35%,SPCAPA]
    1  PVCCD_HV_CPU0      A  @S9S_MB_2U_LIB.S9S_MB_2U(SCH_1):PVCCD_HV_CPU0
    2  GND                B  @S9S_MB_2U_LIB.S9S_MB_2U(SCH_1):GND

Q_CAPP  I54  PC1920  [Q_CAPP_SMLF-470UF,2.5V,20%,EMPA]
    1  PVCCIN_CPU0        A  @S9S_MB_2U_LIB.S9S_MB_2U(SCH_1):PVCCIN_CPU0
    2  GND                B  @S9S_MB_2U_LIB.S9S_MB_2U(SCH_1):GND

Q_CAPP  I33  PC1930  [Q_CAPP_SMLF-470UF,2.5V,20%,SPCA]
    1  PVCCFA_EHV_CPU1      A  @S9S_MB_2U_LIB.S9S_MB_2U(SCH_1):PVCCFA_EHV_CPU1
    2  GND                B  @S9S_MB_2U_LIB.S9S_MB_2U(SCH_1):GND

Q_CAPP  I37  PC1940  [Q_CAPP_SMLF-330UF,2V,35%,SPCAPA]
    1  PVCCD_HV_CPU1      A  @S9S_MB_2U_LIB.S9S_MB_2U(SCH_1):PVCCD_HV_CPU1
    2  GND                B  @S9S_MB_2U_LIB.S9S_MB_2U(SCH_1):GND

Q_CAPP  I53  PC1990  [Q_CAPP_SMLF-470UF,2.5V,20%,EMPA]
    1  PVCCIN_CPU1        A  @S9S_MB_2U_LIB.S9S_MB_2U(SCH_1):PVCCIN_CPU1
    2  GND                B  @S9S_MB_2U_LIB.S9S_MB_2U(SCH_1):GND

Q_CAP  I35  PC2000  [Q_CAP_0402-0.022UF,16V,10%,X7RA]
    1  P1V05_PCH_AUX_REF      A  @S9S_MB_2U_LIB.S9S_MB_2U(SCH_1):P1V05_PCH_AUX_REF
    2  GND                B  @S9S_MB_2U_LIB.S9S_MB_2U(SCH_1):GND

Q_CAP  I48  PC2001  [Q_CAP_0402-0.022UF,16V,10%,EMPA]
    1  PVPP_HBM_CPU0_REF      A  @S9S_MB_2U_LIB.S9S_MB_2U(SCH_1):PVPP_HBM_CPU0_REF
    2  GND                B  @S9S_MB_2U_LIB.S9S_MB_2U(SCH_1):GND

Q_CAP  I47  PC2002  [Q_CAP_0402-0.022UF,16V,10%,X7RA]
    1  PVPP_HBM_CPU1_REF      A  @S9S_MB_2U_LIB.S9S_MB_2U(SCH_1):PVPP_HBM_CPU1_REF
    2  GND                B  @S9S_MB_2U_LIB.S9S_MB_2U(SCH_1):GND

Q_CAPP  I63  PC2170  [Q_CAPP_SMLF-470UF,2.5V,20%,EMPA]
    1  PVCCFA_EHV_FIVRA_CPU0      A  @S9S_MB_2U_LIB.S9S_MB_2U(SCH_1):PVCCFA_EHV_FIVRA_CPU0
    2  GND                B  @S9S_MB_2U_LIB.S9S_MB_2U(SCH_1):GND

Q_CAPP  I272  PC2171  [Q_CAPP_SMLF-470UF,2.5V,20%,EMPA]
    1  PVCCFA_EHV_FIVRA_CPU1      A  @S9S_MB_2U_LIB.S9S_MB_2U(SCH_1):PVCCFA_EHV_FIVRA_CPU1
    2  GND                B  @S9S_MB_2U_LIB.S9S_MB_2U(SCH_1):GND

Q_CAPP  I63  PC2172  [Q_CAPP_SMLF-470UF,2.5V,20%,SPCA]
    1  PVCCFA_EHV_FIVRA_CPU1      A  @S9S_MB_2U_LIB.S9S_MB_2U(SCH_1):PVCCFA_EHV_FIVRA_CPU1
    2  GND                B  @S9S_MB_2U_LIB.S9S_MB_2U(SCH_1):GND

Q_CAPP  I27  PC2180  [Q_CAPP_THLF-560UF,2.5V,20%,OSCA]
    1  PVCCFA_EHV_CPU0      A  @S9S_MB_2U_LIB.S9S_MB_2U(SCH_1):PVCCFA_EHV_CPU0
    2  GND                B  @S9S_MB_2U_LIB.S9S_MB_2U(SCH_1):GND

Q_CAPP  I32  PC2199  [Q_CAPP_THLF-560UF,2.5V,20%,OSCA]
    1  PVCCFA_EHV_CPU1      A  @S9S_MB_2U_LIB.S9S_MB_2U(SCH_1):PVCCFA_EHV_CPU1
    2  GND                B  @S9S_MB_2U_LIB.S9S_MB_2U(SCH_1):GND

Q_CAP  I159  PC2221  [Q_CAP_C0402-1UF,25V,10%,X6S,CHA]
    1  PVNN_MAIN_CPU0_VCC      A  @S9S_MB_2U_LIB.S9S_MB_2U(SCH_1):PVNN_MAIN_CPU0_VCC
    2  GND                B  @S9S_MB_2U_LIB.S9S_MB_2U(SCH_1):GND

Q_CAP  I174  PC2222  [Q_CAP_C0402-1UF,25V,10%,X6S,CHA]
    1  PVNN_MAIN_CPU1_VCC      A  @S9S_MB_2U_LIB.S9S_MB_2U(SCH_1):PVNN_MAIN_CPU1_VCC
    2  GND                B  @S9S_MB_2U_LIB.S9S_MB_2U(SCH_1):GND

Q_CAP  I36  PC2287  [Q_CAP_0402-0.01UF,25V,10%,X7R,A]
    1  PWRGD_P1V8_PCH_AUX      A  @S9S_MB_2U_LIB.S9S_MB_2U(SCH_1):PWRGD_P1V8_PCH_AUX
    2  GND                B  @S9S_MB_2U_LIB.S9S_MB_2U(SCH_1):GND

Q_CAPP  I53  PC2336  [Q_CAPP_SMLF-470UF,2.5V,20%,EMPA]
    1  PVCCIN_CPU0        A  @S9S_MB_2U_LIB.S9S_MB_2U(SCH_1):PVCCIN_CPU0
    2  GND                B  @S9S_MB_2U_LIB.S9S_MB_2U(SCH_1):GND

Q_CAP  I2   PC2643  [Q_CAP_C0402-1UF,25V,10%,EMPTY,A]
    1  PVPP_HBM_CPU0_VCC      A  @S9S_MB_2U_LIB.S9S_MB_2U(SCH_1):PVPP_HBM_CPU0_VCC
    2  GND                B  @S9S_MB_2U_LIB.S9S_MB_2U(SCH_1):GND

Q_CAPP  I68  PC2645  [Q_CAPP_SMLF-470UF,2.5V,20%,EMPA]
    1  PVCCFA_EHV_FIVRA_CPU0      A  @S9S_MB_2U_LIB.S9S_MB_2U(SCH_1):PVCCFA_EHV_FIVRA_CPU0
    2  GND                B  @S9S_MB_2U_LIB.S9S_MB_2U(SCH_1):GND

Q_SHORT  I15  PJ45   [Q_SHORT_SM-EMPTY,SHORT6]
    1  VSENSE_PVCCINFAON_CPU0_DP      1  @S9S_MB_2U_LIB.S9S_MB_2U(SCH_1):VSENSE_PVCCINFAON_CPU0_DP
    2  SH_PVCCINFAON_CPU0      2  @S9S_MB_2U_LIB.S9S_MB_2U(SCH_1):SH_PVCCINFAON_CPU0

Q_SHORT  I9   PJ46   [Q_SHORT_SM-EMPTY,SHORT6]
    1  VSENSE_PVCCFA_EHV_CPU0_DP      1  @S9S_MB_2U_LIB.S9S_MB_2U(SCH_1):VSENSE_PVCCFA_EHV_CPU0_DP
    2  SH_PVCCFA_EHV_CPU0      2  @S9S_MB_2U_LIB.S9S_MB_2U(SCH_1):SH_PVCCFA_EHV_CPU0

Q_SHORT  I30  PJ47   [Q_SHORT_SM-EMPTY,SHORT6]
    1  VSENSE_PVCCIN_CPU0_DP      1  @S9S_MB_2U_LIB.S9S_MB_2U(SCH_1):VSENSE_PVCCIN_CPU0_DP
    2  SH_PVCCIN_CPU0      2  @S9S_MB_2U_LIB.S9S_MB_2U(SCH_1):SH_PVCCIN_CPU0

Q_SHORT  I207  PJ48   [Q_SHORT_SM-EMPTY,SHORT6]
    1  VSENSE_PVCCD_HV_CPU1_DP      1  @S9S_MB_2U_LIB.S9S_MB_2U(SCH_1):VSENSE_PVCCD_HV_CPU1_DP
    2  SH_PVCCD_HV_CPU1      2  @S9S_MB_2U_LIB.S9S_MB_2U(SCH_1):SH_PVCCD_HV_CPU1

Q_SHORT  I174  PJ49   [Q_SHORT_SM-EMPTY,SHORT6]
    1  VSENSE_PVCCFA_EHV_FIVRA_CPU1_DP      1  @S9S_MB_2U_LIB.S9S_MB_2U(SCH_1):VSENSE_PVCCFA_EHV_FIVRA_CPU1_DP
    2  SH_PVCCFA_EHV_FIVRA_CPU1      2  @S9S_MB_2U_LIB.S9S_MB_2U(SCH_1):SH_PVCCFA_EHV_FIVRA_CPU1

Q_SHORT  I33  PJ50   [Q_SHORT_SM-EMPTY,SHORT6]
    1  VSENSE_PVCCINFAON_CPU1_DP      1  @S9S_MB_2U_LIB.S9S_MB_2U(SCH_1):VSENSE_PVCCINFAON_CPU1_DP
    2  SH_PVCCINFAON_CPU1      2  @S9S_MB_2U_LIB.S9S_MB_2U(SCH_1):SH_PVCCINFAON_CPU1

Q_SHORT  I20  PJ51   [Q_SHORT_SM-EMPTY,SHORT6]
    1  VSENSE_PVCCFA_EHV_CPU1_DP      1  @S9S_MB_2U_LIB.S9S_MB_2U(SCH_1):VSENSE_PVCCFA_EHV_CPU1_DP
    2  SH_PVCCFA_EHV_CPU1      2  @S9S_MB_2U_LIB.S9S_MB_2U(SCH_1):SH_PVCCFA_EHV_CPU1

Q_SHORT  I187  PJ52   [Q_SHORT_SM-EMPTY,SHORT6]
    1  VSENSE_PVCCIN_CPU1_DP      1  @S9S_MB_2U_LIB.S9S_MB_2U(SCH_1):VSENSE_PVCCIN_CPU1_DP
    2  SH_PVCCIN_CPU1      2  @S9S_MB_2U_LIB.S9S_MB_2U(SCH_1):SH_PVCCIN_CPU1

Q_SHORT  I19  PJ53   [Q_SHORT_SM-EMPTY,SHORT6]
    1  VSENSE_PVCCFA_EHV_FIVRA_CPU0_DP      1  @S9S_MB_2U_LIB.S9S_MB_2U(SCH_1):VSENSE_PVCCFA_EHV_FIVRA_CPU0_DP
    2  SH_PVCCFA_EHV_FIVRA_CPU0      2  @S9S_MB_2U_LIB.S9S_MB_2U(SCH_1):SH_PVCCFA_EHV_FIVRA_CPU0

Q_SHORT  I79  PJ54   [Q_SHORT_SM-EMPTY,SHORT6]
    1  VSENSE_PVCCD_HV_CPU0_DP      1  @S9S_MB_2U_LIB.S9S_MB_2U(SCH_1):VSENSE_PVCCD_HV_CPU0_DP
    2  SH_PVCCD_HV_CPU0      2  @S9S_MB_2U_LIB.S9S_MB_2U(SCH_1):SH_PVCCD_HV_CPU0

Q_SHORT  I46  PJ62   [Q_SHORT_SM-EMPTY,SHORT6]
    1  SH_P1V05_PCH_AUX_P      1  @S9S_MB_2U_LIB.S9S_MB_2U(SCH_1):SH_P1V05_PCH_AUX_P
    2  P1V05_PCH_AUX      2  @S9S_MB_2U_LIB.S9S_MB_2U(SCH_1):P1V05_PCH_AUX

Q_SHORT  I15  PJ63   [Q_SHORT_SM-EMPTY,SHORT6]
    1  SH_P1V05_PCH_AUX_N      1  @S9S_MB_2U_LIB.S9S_MB_2U(SCH_1):SH_P1V05_PCH_AUX_N
    2  GND                2  @S9S_MB_2U_LIB.S9S_MB_2U(SCH_1):GND

Q_SHORT  I57  PJ64   [Q_SHORT_SM-EMPTY,SHORT6]
    1  SH_PVPP_HBM_CPU0_P      1  @S9S_MB_2U_LIB.S9S_MB_2U(SCH_1):SH_PVPP_HBM_CPU0_P
    2  PVPP_HBM_CPU0      2  @S9S_MB_2U_LIB.S9S_MB_2U(SCH_1):PVPP_HBM_CPU0

Q_SHORT  I54  PJ65   [Q_SHORT_SM-EMPTY,SHORT6]
    1  SH_PVPP_HBM_CPU0_N      1  @S9S_MB_2U_LIB.S9S_MB_2U(SCH_1):SH_PVPP_HBM_CPU0_N
    2  GND                2  @S9S_MB_2U_LIB.S9S_MB_2U(SCH_1):GND

Q_SHORT  I56  PJ66   [Q_SHORT_SM-EMPTY,SHORT6]
    1  SH_PVPP_HBM_CPU1_P      1  @S9S_MB_2U_LIB.S9S_MB_2U(SCH_1):SH_PVPP_HBM_CPU1_P
    2  PVPP_HBM_CPU1      2  @S9S_MB_2U_LIB.S9S_MB_2U(SCH_1):PVPP_HBM_CPU1

Q_SHORT  I55  PJ67   [Q_SHORT_SM-EMPTY,SHORT6]
    1  SH_PVPP_HBM_CPU1_N      1  @S9S_MB_2U_LIB.S9S_MB_2U(SCH_1):SH_PVPP_HBM_CPU1_N
    2  GND                2  @S9S_MB_2U_LIB.S9S_MB_2U(SCH_1):GND

Q_INDUCTOR  I75  PL2    [Q_INDUCTOR_SMLF-130NH/106A,EMPA]
    1  SW_PVCCFA_EHV_FIVRA_CPU0_SW3      1  @S9S_MB_2U_LIB.S9S_MB_2U(SCH_1):SW_PVCCFA_EHV_FIVRA_CPU0_SW3
    2  PVCCFA_EHV_FIVRA_CPU0      2  @S9S_MB_2U_LIB.S9S_MB_2U(SCH_1):PVCCFA_EHV_FIVRA_CPU0

Q_INDUCTOR  I23  PL3    [Q_INDUCTOR_SMLF-300NH/33A,IND,A]
    1  SW_PVCCFA_EHV_CPU0_SW1      1  @S9S_MB_2U_LIB.S9S_MB_2U(SCH_1):SW_PVCCFA_EHV_CPU0_SW1
    2  PVCCFA_EHV_CPU0      2  @S9S_MB_2U_LIB.S9S_MB_2U(SCH_1):PVCCFA_EHV_CPU0

Q_INDUCTOR  I207  PL4    [Q_INDUCTOR_SMLF-120NH/94A,IND,A]
    1  SW_PVCCINFAON_CPU0_SW1      1  @S9S_MB_2U_LIB.S9S_MB_2U(SCH_1):SW_PVCCINFAON_CPU0_SW1
    2  PVCCINFAON_CPU0      2  @S9S_MB_2U_LIB.S9S_MB_2U(SCH_1):PVCCINFAON_CPU0

Q_INDUCTOR  I184  PL5    [Q_INDUCTOR_SMLF-120NH/94A,IND,A]
    1  SW_PVCCINFAON_CPU0_SW2      1  @S9S_MB_2U_LIB.S9S_MB_2U(SCH_1):SW_PVCCINFAON_CPU0_SW2
    2  PVCCINFAON_CPU0      2  @S9S_MB_2U_LIB.S9S_MB_2U(SCH_1):PVCCINFAON_CPU0

Q_INDUCTOR  I211  PL6    [Q_INDUCTOR_SMLF-100NH/16A,IND,A]
    2  SW_P12V_PVCCINFAON_CPU0_FLT      2  @S9S_MB_2U_LIB.S9S_MB_2U(SCH_1):SW_P12V_PVCCINFAON_CPU0_FLT
    1  P12V_AUX           1  @S9S_MB_2U_LIB.S9S_MB_2U(SCH_1):P12V_AUX

Q_INDUCTOR4P_14  I117  PL7    [Q_INDUCTOR4P_14-150NH,SMLF,INDA]
    1  SW_PVCCIN_CPU0_SW8      1  @S9S_MB_2U_LIB.S9S_MB_2U(SCH_1):SW_PVCCIN_CPU0_SW8
    4  PVCCIN_CPU0        4  @S9S_MB_2U_LIB.S9S_MB_2U(SCH_1):PVCCIN_CPU0
    2  IND_P0_CPL8        2  @S9S_MB_2U_LIB.S9S_MB_2U(SCH_1):IND_P0_CPL8
    3  GND                3  @S9S_MB_2U_LIB.S9S_MB_2U(SCH_1):GND

Q_INDUCTOR4P_14  I81  PL8    [Q_INDUCTOR4P_14-150NH,SMLF,INDA]
    1  SW_PVCCIN_CPU0_SW7      1  @S9S_MB_2U_LIB.S9S_MB_2U(SCH_1):SW_PVCCIN_CPU0_SW7
    4  PVCCIN_CPU0        4  @S9S_MB_2U_LIB.S9S_MB_2U(SCH_1):PVCCIN_CPU0
    2  IND_P0_CPL7        2  @S9S_MB_2U_LIB.S9S_MB_2U(SCH_1):IND_P0_CPL7
    3  IND_P0_CPL6        3  @S9S_MB_2U_LIB.S9S_MB_2U(SCH_1):IND_P0_CPL6

Q_INDUCTOR4P_14  I90  PL9    [Q_INDUCTOR4P_14-150NH,SMLF,INDA]
    1  SW_PVCCIN_CPU0_SW6      1  @S9S_MB_2U_LIB.S9S_MB_2U(SCH_1):SW_PVCCIN_CPU0_SW6
    4  PVCCIN_CPU0        4  @S9S_MB_2U_LIB.S9S_MB_2U(SCH_1):PVCCIN_CPU0
    2  IND_P0_CPL6        2  @S9S_MB_2U_LIB.S9S_MB_2U(SCH_1):IND_P0_CPL6
    3  IND_P0_CPL1        3  @S9S_MB_2U_LIB.S9S_MB_2U(SCH_1):IND_P0_CPL1

Q_INDUCTOR4P_14  I74  PL10   [Q_INDUCTOR4P_14-150NH,SMLF,INDA]
    1  SW_PVCCIN_CPU0_SW5      1  @S9S_MB_2U_LIB.S9S_MB_2U(SCH_1):SW_PVCCIN_CPU0_SW5
    4  PVCCIN_CPU0        4  @S9S_MB_2U_LIB.S9S_MB_2U(SCH_1):PVCCIN_CPU0
    3  IND_P0_CPL8        3  @S9S_MB_2U_LIB.S9S_MB_2U(SCH_1):IND_P0_CPL8
    2  IND_P0_CPL5        2  @S9S_MB_2U_LIB.S9S_MB_2U(SCH_1):IND_P0_CPL5

Q_INDUCTOR4P_14  I90  PL11   [Q_INDUCTOR4P_14-150NH,SMLF,INDA]
    1  SW_PVCCIN_CPU0_SW4      1  @S9S_MB_2U_LIB.S9S_MB_2U(SCH_1):SW_PVCCIN_CPU0_SW4
    4  PVCCIN_CPU0        4  @S9S_MB_2U_LIB.S9S_MB_2U(SCH_1):PVCCIN_CPU0
    3  IND_P0_CPL5        3  @S9S_MB_2U_LIB.S9S_MB_2U(SCH_1):IND_P0_CPL5
    2  IND_P0_CPL4        2  @S9S_MB_2U_LIB.S9S_MB_2U(SCH_1):IND_P0_CPL4

Q_INDUCTOR  I76  PL12   [Q_INDUCTOR_SMLF-130NH/106A,INDA]
    1  SW_PVCCFA_EHV_FIVRA_CPU1_SW3      1  @S9S_MB_2U_LIB.S9S_MB_2U(SCH_1):SW_PVCCFA_EHV_FIVRA_CPU1_SW3
    2  PVCCFA_EHV_FIVRA_CPU1      2  @S9S_MB_2U_LIB.S9S_MB_2U(SCH_1):PVCCFA_EHV_FIVRA_CPU1

Q_INDUCTOR4P_14  I122  PL13   [Q_INDUCTOR4P_14-150NH,SMLF,INDA]
    1  SW_PVCCIN_CPU0_SW2      1  @S9S_MB_2U_LIB.S9S_MB_2U(SCH_1):SW_PVCCIN_CPU0_SW2
    4  PVCCIN_CPU0        4  @S9S_MB_2U_LIB.S9S_MB_2U(SCH_1):PVCCIN_CPU0
    3  IND_P0_CPL3        3  @S9S_MB_2U_LIB.S9S_MB_2U(SCH_1):IND_P0_CPL3
    2  IND_P0_CPL2        2  @S9S_MB_2U_LIB.S9S_MB_2U(SCH_1):IND_P0_CPL2

Q_INDUCTOR  I69  PL14   [Q_INDUCTOR_SMLF-100NH/16A,IND,A]
    2  SW_P12V_PVCCFA_EHV_FIVRA_CPU1_R      2  @S9S_MB_2U_LIB.S9S_MB_2U(SCH_1):SW_P12V_PVCCFA_EHV_FIVRA_CPU1_R
    1  P12V_AUX           1  @S9S_MB_2U_LIB.S9S_MB_2U(SCH_1):P12V_AUX

Q_INDUCTOR  I75  PL15   [Q_INDUCTOR_SMLF-50NH/148A,IND,A]
    2  SW_P12V_PVCCIN_CPU0_FLT      2  @S9S_MB_2U_LIB.S9S_MB_2U(SCH_1):SW_P12V_PVCCIN_CPU0_FLT
    1  P12V_AUX           1  @S9S_MB_2U_LIB.S9S_MB_2U(SCH_1):P12V_AUX

Q_INDUCTOR  I26  PL16   [Q_INDUCTOR_SMLF-BLM18SN220TN1DA]
    2  SW_P1V8_PCH_AUX_FLT      2  @S9S_MB_2U_LIB.S9S_MB_2U(SCH_1):SW_P1V8_PCH_AUX_FLT
    1  P12V_AUX           1  @S9S_MB_2U_LIB.S9S_MB_2U(SCH_1):P12V_AUX

Q_INDUCTOR  I26  PL17   [Q_INDUCTOR_SMLF-120NH/94A,IND,A]
    1  SW_PVCCD_HV_CPU1_SW1      1  @S9S_MB_2U_LIB.S9S_MB_2U(SCH_1):SW_PVCCD_HV_CPU1_SW1
    2  PVCCD_HV_CPU1      2  @S9S_MB_2U_LIB.S9S_MB_2U(SCH_1):PVCCD_HV_CPU1

Q_INDUCTOR  I279  PL18   [Q_INDUCTOR_SMLF-130NH/106A,INDA]
    1  SW_PVCCFA_EHV_FIVRA_CPU1_SW1      1  @S9S_MB_2U_LIB.S9S_MB_2U(SCH_1):SW_PVCCFA_EHV_FIVRA_CPU1_SW1
    2  PVCCFA_EHV_FIVRA_CPU1      2  @S9S_MB_2U_LIB.S9S_MB_2U(SCH_1):PVCCFA_EHV_FIVRA_CPU1

Q_INDUCTOR  I280  PL19   [Q_INDUCTOR_SMLF-130NH/106A,INDA]
    1  SW_PVCCFA_EHV_FIVRA_CPU1_SW2      1  @S9S_MB_2U_LIB.S9S_MB_2U(SCH_1):SW_PVCCFA_EHV_FIVRA_CPU1_SW2
    2  PVCCFA_EHV_FIVRA_CPU1      2  @S9S_MB_2U_LIB.S9S_MB_2U(SCH_1):PVCCFA_EHV_FIVRA_CPU1

Q_INDUCTOR  I23  PL20   [Q_INDUCTOR_SMLF-300NH/33A,IND,A]
    1  SW_PVCCFA_EHV_CPU1_SW1      1  @S9S_MB_2U_LIB.S9S_MB_2U(SCH_1):SW_PVCCFA_EHV_CPU1_SW1
    2  PVCCFA_EHV_CPU1      2  @S9S_MB_2U_LIB.S9S_MB_2U(SCH_1):PVCCFA_EHV_CPU1

Q_INDUCTOR  I55  PL21   [Q_INDUCTOR_SMLF-120NH/94A,IND,A]
    1  SW_PVCCINFAON_CPU1_SW1      1  @S9S_MB_2U_LIB.S9S_MB_2U(SCH_1):SW_PVCCINFAON_CPU1_SW1
    2  PVCCINFAON_CPU1      2  @S9S_MB_2U_LIB.S9S_MB_2U(SCH_1):PVCCINFAON_CPU1

Q_INDUCTOR  I33  PL22   [Q_INDUCTOR_SMLF-120NH/94A,IND,A]
    1  SW_PVCCINFAON_CPU1_SW2      1  @S9S_MB_2U_LIB.S9S_MB_2U(SCH_1):SW_PVCCINFAON_CPU1_SW2
    2  PVCCINFAON_CPU1      2  @S9S_MB_2U_LIB.S9S_MB_2U(SCH_1):PVCCINFAON_CPU1

Q_INDUCTOR  I65  PL23   [Q_INDUCTOR_SMLF-100NH/16A,IND,A]
    2  SW_P12V_PVCCINFAON_CPU1_FLT      2  @S9S_MB_2U_LIB.S9S_MB_2U(SCH_1):SW_P12V_PVCCINFAON_CPU1_FLT
    1  P12V_AUX           1  @S9S_MB_2U_LIB.S9S_MB_2U(SCH_1):P12V_AUX

Q_INDUCTOR4P_14  I95  PL24   [Q_INDUCTOR4P_14-150NH,SMLF,INDA]
    1  SW_PVCCIN_CPU1_SW8      1  @S9S_MB_2U_LIB.S9S_MB_2U(SCH_1):SW_PVCCIN_CPU1_SW8
    4  PVCCIN_CPU1        4  @S9S_MB_2U_LIB.S9S_MB_2U(SCH_1):PVCCIN_CPU1
    2  IND_P1_CPL8        2  @S9S_MB_2U_LIB.S9S_MB_2U(SCH_1):IND_P1_CPL8
    3  IND_P1_CPL5        3  @S9S_MB_2U_LIB.S9S_MB_2U(SCH_1):IND_P1_CPL5

Q_INDUCTOR4P_14  I76  PL25   [Q_INDUCTOR4P_14-150NH,SMLF,INDA]
    1  SW_PVCCIN_CPU1_SW7      1  @S9S_MB_2U_LIB.S9S_MB_2U(SCH_1):SW_PVCCIN_CPU1_SW7
    4  PVCCIN_CPU1        4  @S9S_MB_2U_LIB.S9S_MB_2U(SCH_1):PVCCIN_CPU1
    2  IND_P1_CPL7        2  @S9S_MB_2U_LIB.S9S_MB_2U(SCH_1):IND_P1_CPL7
    3  GND                3  @S9S_MB_2U_LIB.S9S_MB_2U(SCH_1):GND

Q_INDUCTOR4P_14  I90  PL26   [Q_INDUCTOR4P_14-150NH,SMLF,INDA]
    1  SW_PVCCIN_CPU1_SW6      1  @S9S_MB_2U_LIB.S9S_MB_2U(SCH_1):SW_PVCCIN_CPU1_SW6
    4  PVCCIN_CPU1        4  @S9S_MB_2U_LIB.S9S_MB_2U(SCH_1):PVCCIN_CPU1
    3  IND_P1_CPL7        3  @S9S_MB_2U_LIB.S9S_MB_2U(SCH_1):IND_P1_CPL7
    2  IND_P1_CPL6        2  @S9S_MB_2U_LIB.S9S_MB_2U(SCH_1):IND_P1_CPL6

Q_INDUCTOR4P_14  I73  PL27   [Q_INDUCTOR4P_14-150NH,SMLF,INDA]
    1  SW_PVCCIN_CPU1_SW5      1  @S9S_MB_2U_LIB.S9S_MB_2U(SCH_1):SW_PVCCIN_CPU1_SW5
    4  PVCCIN_CPU1        4  @S9S_MB_2U_LIB.S9S_MB_2U(SCH_1):PVCCIN_CPU1
    2  IND_P1_CPL5        2  @S9S_MB_2U_LIB.S9S_MB_2U(SCH_1):IND_P1_CPL5
    3  IND_P1_CPL4        3  @S9S_MB_2U_LIB.S9S_MB_2U(SCH_1):IND_P1_CPL4

Q_INDUCTOR4P_14  I90  PL28   [Q_INDUCTOR4P_14-150NH,SMLF,INDA]
    1  SW_PVCCIN_CPU1_SW4      1  @S9S_MB_2U_LIB.S9S_MB_2U(SCH_1):SW_PVCCIN_CPU1_SW4
    4  PVCCIN_CPU1        4  @S9S_MB_2U_LIB.S9S_MB_2U(SCH_1):PVCCIN_CPU1
    2  IND_P1_CPL4        2  @S9S_MB_2U_LIB.S9S_MB_2U(SCH_1):IND_P1_CPL4
    3  IND_P1_CPL3        3  @S9S_MB_2U_LIB.S9S_MB_2U(SCH_1):IND_P1_CPL3

Q_INDUCTOR4P_14  I74  PL29   [Q_INDUCTOR4P_14-150NH,SMLF,INDA]
    1  SW_PVCCIN_CPU1_SW3      1  @S9S_MB_2U_LIB.S9S_MB_2U(SCH_1):SW_PVCCIN_CPU1_SW3
    4  PVCCIN_CPU1        4  @S9S_MB_2U_LIB.S9S_MB_2U(SCH_1):PVCCIN_CPU1
    2  IND_P1_CPL3        2  @S9S_MB_2U_LIB.S9S_MB_2U(SCH_1):IND_P1_CPL3
    3  IND_P1_CPL2        3  @S9S_MB_2U_LIB.S9S_MB_2U(SCH_1):IND_P1_CPL2

Q_INDUCTOR4P_14  I103  PL30   [Q_INDUCTOR4P_14-150NH,SMLF,INDA]
    1  SW_PVCCIN_CPU1_SW2      1  @S9S_MB_2U_LIB.S9S_MB_2U(SCH_1):SW_PVCCIN_CPU1_SW2
    4  PVCCIN_CPU1        4  @S9S_MB_2U_LIB.S9S_MB_2U(SCH_1):PVCCIN_CPU1
    2  IND_P1_CPL2        2  @S9S_MB_2U_LIB.S9S_MB_2U(SCH_1):IND_P1_CPL2
    3  IND_P1_CPL1        3  @S9S_MB_2U_LIB.S9S_MB_2U(SCH_1):IND_P1_CPL1

Q_INDUCTOR4P_14  I89  PL31   [Q_INDUCTOR4P_14-150NH,SMLF,INDA]
    1  SW_PVCCIN_CPU1_SW1      1  @S9S_MB_2U_LIB.S9S_MB_2U(SCH_1):SW_PVCCIN_CPU1_SW1
    4  PVCCIN_CPU1        4  @S9S_MB_2U_LIB.S9S_MB_2U(SCH_1):PVCCIN_CPU1
    3  IND_P1_CPL6        3  @S9S_MB_2U_LIB.S9S_MB_2U(SCH_1):IND_P1_CPL6
    2  IND_P1_CPL1        2  @S9S_MB_2U_LIB.S9S_MB_2U(SCH_1):IND_P1_CPL1

Q_INDUCTOR  I71  PL32   [Q_INDUCTOR_SMLF-50NH/148A,IND,A]
    2  SW_P12V_PVCCIN_CPU1_FLT      2  @S9S_MB_2U_LIB.S9S_MB_2U(SCH_1):SW_P12V_PVCCIN_CPU1_FLT
    1  P12V_AUX           1  @S9S_MB_2U_LIB.S9S_MB_2U(SCH_1):P12V_AUX

Q_INDUCTOR  I81  PL33   [Q_INDUCTOR_SMLF-130NH/106A,INDA]
    1  SW_PVCCFA_EHV_FIVRA_CPU0_SW1      1  @S9S_MB_2U_LIB.S9S_MB_2U(SCH_1):SW_PVCCFA_EHV_FIVRA_CPU0_SW1
    2  PVCCFA_EHV_FIVRA_CPU0      2  @S9S_MB_2U_LIB.S9S_MB_2U(SCH_1):PVCCFA_EHV_FIVRA_CPU0

Q_INDUCTOR  I82  PL34   [Q_INDUCTOR_SMLF-130NH/106A,INDA]
    1  SW_PVCCFA_EHV_FIVRA_CPU0_SW2      1  @S9S_MB_2U_LIB.S9S_MB_2U(SCH_1):SW_PVCCFA_EHV_FIVRA_CPU0_SW2
    2  PVCCFA_EHV_FIVRA_CPU0      2  @S9S_MB_2U_LIB.S9S_MB_2U(SCH_1):PVCCFA_EHV_FIVRA_CPU0

Q_INDUCTOR  I345  PL35   [Q_INDUCTOR_SMLF-120NH/94A,IND,A]
    1  SW_PVCCD_HV_CPU0_SW1      1  @S9S_MB_2U_LIB.S9S_MB_2U(SCH_1):SW_PVCCD_HV_CPU0_SW1
    2  PVCCD_HV_CPU0      2  @S9S_MB_2U_LIB.S9S_MB_2U(SCH_1):PVCCD_HV_CPU0

Q_INDUCTOR  I266  PL43   [Q_INDUCTOR_SMLF-100NH/16A,IND,A]
    2  SW_P12V_PVCCFA_EHV_FIVRA_CPU1_L      2  @S9S_MB_2U_LIB.S9S_MB_2U(SCH_1):SW_P12V_PVCCFA_EHV_FIVRA_CPU1_L
    1  P12V_AUX           1  @S9S_MB_2U_LIB.S9S_MB_2U(SCH_1):P12V_AUX

Q_INDUCTOR  I74  PL44   [Q_INDUCTOR_SMLF-100NH/16A,IND,A]
    2  SW_P12V_PVCCFA_EHV_FIVRA_CPU0_L      2  @S9S_MB_2U_LIB.S9S_MB_2U(SCH_1):SW_P12V_PVCCFA_EHV_FIVRA_CPU0_L
    1  P12V_AUX           1  @S9S_MB_2U_LIB.S9S_MB_2U(SCH_1):P12V_AUX

Q_INDUCTOR  I3   PL45   [Q_INDUCTOR_SMLF-100NH/16A,IND,A]
    2  SW_P3V3_AUX_FLT      2  @S9S_MB_2U_LIB.S9S_MB_2U(SCH_1):SW_P3V3_AUX_FLT
    1  P12V_AUX           1  @S9S_MB_2U_LIB.S9S_MB_2U(SCH_1):P12V_AUX

Q_INDUCTOR  I5   PL64   [Q_INDUCTOR_SMLF-BLM18SN220TN1DA]
    2  SW_P5V_AUX_FLT      2  @S9S_MB_2U_LIB.S9S_MB_2U(SCH_1):SW_P5V_AUX_FLT
    1  P12V_AUX           1  @S9S_MB_2U_LIB.S9S_MB_2U(SCH_1):P12V_AUX

Q_INDUCTOR  I29  PL65   [Q_INDUCTOR_SMLF-3.3UH/10A,IND,A]
    1  SW_P5V_AUX_SW      1  @S9S_MB_2U_LIB.S9S_MB_2U(SCH_1):SW_P5V_AUX_SW
    2  P5V_AUX            2  @S9S_MB_2U_LIB.S9S_MB_2U(SCH_1):P5V_AUX

Q_INDUCTOR  I37  PL66   [Q_INDUCTOR_SMLF-1.5UH/53A,IND,A]
    1  SW_P3V3_AUX_SW      1  @S9S_MB_2U_LIB.S9S_MB_2U(SCH_1):SW_P3V3_AUX_SW
    2  P3V3_AUX           2  @S9S_MB_2U_LIB.S9S_MB_2U(SCH_1):P3V3_AUX

Q_INDUCTOR  I69  PL101  [Q_INDUCTOR_SMLF-100NH/16A,IND,A]
    2  SW_P12V_PVCCFA_EHV_FIVRA_CPU0_R      2  @S9S_MB_2U_LIB.S9S_MB_2U(SCH_1):SW_P12V_PVCCFA_EHV_FIVRA_CPU0_R
    1  P12V_AUX           1  @S9S_MB_2U_LIB.S9S_MB_2U(SCH_1):P12V_AUX

Q_INDUCTOR  I110  PL105  [Q_INDUCTOR_SMLF-120NH/76A,IND,A]
    1  IND_P0_CPL7        1  @S9S_MB_2U_LIB.S9S_MB_2U(SCH_1):IND_P0_CPL7
    2  GND                2  @S9S_MB_2U_LIB.S9S_MB_2U(SCH_1):GND

Q_INDUCTOR  I107  PL106  [Q_INDUCTOR_SMLF-120NH/76A,IND,A]
    1  IND_P1_CPL8        1  @S9S_MB_2U_LIB.S9S_MB_2U(SCH_1):IND_P1_CPL8
    2  GND                2  @S9S_MB_2U_LIB.S9S_MB_2U(SCH_1):GND

Q_INDUCTOR  I2   PL110  [Q_INDUCTOR_SMLF-100NH/16A,IND,A]
    2  SW_P12V_AUX_P1V05_PCH_AUX_FLT      2  @S9S_MB_2U_LIB.S9S_MB_2U(SCH_1):SW_P12V_AUX_P1V05_PCH_AUX_FLT
    1  P12V_AUX           1  @S9S_MB_2U_LIB.S9S_MB_2U(SCH_1):P12V_AUX

Q_INDUCTOR4P_14  I74  PL112  [Q_INDUCTOR4P_14-150NH,SMLF,INDA]
    1  SW_PVCCIN_CPU0_SW3      1  @S9S_MB_2U_LIB.S9S_MB_2U(SCH_1):SW_PVCCIN_CPU0_SW3
    4  PVCCIN_CPU0        4  @S9S_MB_2U_LIB.S9S_MB_2U(SCH_1):PVCCIN_CPU0
    3  IND_P0_CPL4        3  @S9S_MB_2U_LIB.S9S_MB_2U(SCH_1):IND_P0_CPL4
    2  IND_P0_CPL3        2  @S9S_MB_2U_LIB.S9S_MB_2U(SCH_1):IND_P0_CPL3

Q_INDUCTOR  I77  PL113  [Q_INDUCTOR_SMLF-130NH/106A,INDA]
    1  SW_PVCCFA_EHV_FIVRA_CPU1_SW4      1  @S9S_MB_2U_LIB.S9S_MB_2U(SCH_1):SW_PVCCFA_EHV_FIVRA_CPU1_SW4
    2  PVCCFA_EHV_FIVRA_CPU1      2  @S9S_MB_2U_LIB.S9S_MB_2U(SCH_1):PVCCFA_EHV_FIVRA_CPU1

Q_INDUCTOR4P_14  I104  PL114  [Q_INDUCTOR4P_14-150NH,SMLF,INDA]
    1  SW_PVCCIN_CPU0_SW1      1  @S9S_MB_2U_LIB.S9S_MB_2U(SCH_1):SW_PVCCIN_CPU0_SW1
    4  PVCCIN_CPU0        4  @S9S_MB_2U_LIB.S9S_MB_2U(SCH_1):PVCCIN_CPU0
    3  IND_P0_CPL2        3  @S9S_MB_2U_LIB.S9S_MB_2U(SCH_1):IND_P0_CPL2
    2  IND_P0_CPL1        2  @S9S_MB_2U_LIB.S9S_MB_2U(SCH_1):IND_P0_CPL1

Q_INDUCTOR  I24  PL118  [Q_INDUCTOR_SMLF-1UH,EMPTY,CV-1A]
    1  SW_PVPP_HBM_CPU0_SW      1  @S9S_MB_2U_LIB.S9S_MB_2U(SCH_1):SW_PVPP_HBM_CPU0_SW
    2  PVPP_HBM_CPU0      2  @S9S_MB_2U_LIB.S9S_MB_2U(SCH_1):PVPP_HBM_CPU0

Q_INDUCTOR  I41  PL119  [Q_INDUCTOR_SMLF-1UH,IND,CV-10BA]
    1  SW_PVPP_HBM_CPU1_SW      1  @S9S_MB_2U_LIB.S9S_MB_2U(SCH_1):SW_PVPP_HBM_CPU1_SW
    2  PVPP_HBM_CPU1      2  @S9S_MB_2U_LIB.S9S_MB_2U(SCH_1):PVPP_HBM_CPU1

Q_INDUCTOR  I180  PL120  [Q_INDUCTOR_SMLF-1UH,IND,CV-10BA]
    1  SW_PVNN_MAIN_CPU0_SW      1  @S9S_MB_2U_LIB.S9S_MB_2U(SCH_1):SW_PVNN_MAIN_CPU0_SW
    2  PVNN_MAIN_CPU0      2  @S9S_MB_2U_LIB.S9S_MB_2U(SCH_1):PVNN_MAIN_CPU0

Q_INDUCTOR  I182  PL121  [Q_INDUCTOR_SMLF-1UH,IND,CV-10BA]
    1  SW_PVNN_MAIN_CPU1_SW      1  @S9S_MB_2U_LIB.S9S_MB_2U(SCH_1):SW_PVNN_MAIN_CPU1_SW
    2  PVNN_MAIN_CPU1      2  @S9S_MB_2U_LIB.S9S_MB_2U(SCH_1):PVNN_MAIN_CPU1

Q_INDUCTOR  I43  PL150  [Q_INDUCTOR_SMLF-300NH/33A,IND,A]
    1  SW_P1V05_PCH_AUX_SW      1  @S9S_MB_2U_LIB.S9S_MB_2U(SCH_1):SW_P1V05_PCH_AUX_SW
    2  P1V05_PCH_AUX      2  @S9S_MB_2U_LIB.S9S_MB_2U(SCH_1):P1V05_PCH_AUX

Q_INDUCTOR  I22  PL170  [Q_INDUCTOR_SMLF-1UH,IND,CV-10BA]
    1  SW_P1V8_PCH_AUX_SW      1  @S9S_MB_2U_LIB.S9S_MB_2U(SCH_1):SW_P1V8_PCH_AUX_SW
    2  P1V8_PCH_AUX       2  @S9S_MB_2U_LIB.S9S_MB_2U(SCH_1):P1V8_PCH_AUX

Q_INDUCTOR  I30  PL210  [Q_INDUCTOR_SMLF-130NH/106A,EMPA]
    1  SW_PVCCFA_EHV_FIVRA_CPU0_SW4      1  @S9S_MB_2U_LIB.S9S_MB_2U(SCH_1):SW_PVCCFA_EHV_FIVRA_CPU0_SW4
    2  PVCCFA_EHV_FIVRA_CPU0      2  @S9S_MB_2U_LIB.S9S_MB_2U(SCH_1):PVCCFA_EHV_FIVRA_CPU0

MOSFET_NCH_1D3S  I91  PQ1    [MOSFET_NCH_1D3S-PSMNR58-30YLH,A]
    4  VR_P5V_EN_D_R      4  @S9S_MB_2U_LIB.S9S_MB_2U(SCH_1):VR_P5V_EN_D_R
    5  P5V_AUX            5  @S9S_MB_2U_LIB.S9S_MB_2U(SCH_1):P5V_AUX
    3  P5V                3  @S9S_MB_2U_LIB.S9S_MB_2U(SCH_1):P5V
    2  P5V                2  @S9S_MB_2U_LIB.S9S_MB_2U(SCH_1):P5V
    1  P5V                1  @S9S_MB_2U_LIB.S9S_MB_2U(SCH_1):P5V

MOSFET_NCH_1D3S  I90  PQ2    [MOSFET_NCH_1D3S-PSMNR58-30YLH,A]
    4  VR_P3V3_EN_D_R      4  @S9S_MB_2U_LIB.S9S_MB_2U(SCH_1):VR_P3V3_EN_D_R
    5  P3V3_AUX           5  @S9S_MB_2U_LIB.S9S_MB_2U(SCH_1):P3V3_AUX
    3  P3V3               3  @S9S_MB_2U_LIB.S9S_MB_2U(SCH_1):P3V3
    2  P3V3               2  @S9S_MB_2U_LIB.S9S_MB_2U(SCH_1):P3V3
    1  P3V3               1  @S9S_MB_2U_LIB.S9S_MB_2U(SCH_1):P3V3

Q_RES  I172  PR50   [Q_RES_0402LF-12.4K,1%,1/16W,CHA]
    1  PVNN_MAIN_CPU0_FB_RC      A  @S9S_MB_2U_LIB.S9S_MB_2U(SCH_1):PVNN_MAIN_CPU0_FB_RC
    2  GND                B  @S9S_MB_2U_LIB.S9S_MB_2U(SCH_1):GND

Q_RES  I180  PR51   [Q_RES_0402LF-12.4K,1%,1/16W,CHA]
    1  PVNN_MAIN_CPU1_FB_RC      A  @S9S_MB_2U_LIB.S9S_MB_2U(SCH_1):PVNN_MAIN_CPU1_FB_RC
    2  GND                B  @S9S_MB_2U_LIB.S9S_MB_2U(SCH_1):GND

Q_RES  I31  PR73   [Q_RES_0402LF-10K,5%,1/16W,CHIPA]
    2  PWRGD_P3V3_AUX      B  @S9S_MB_2U_LIB.S9S_MB_2U(SCH_1):PWRGD_P3V3_AUX
    1  P3V3_AUX           A  @S9S_MB_2U_LIB.S9S_MB_2U(SCH_1):P3V3_AUX

Q_RES  I16  PR89   [Q_RES_0402LF-15K,1%,1/16W,CHIPA]
    1  P5V_AUX_CS         A  @S9S_MB_2U_LIB.S9S_MB_2U(SCH_1):P5V_AUX_CS
    2  GND                B  @S9S_MB_2U_LIB.S9S_MB_2U(SCH_1):GND

Q_RES  I27  PR90   [Q_RES_0402LF-10K,5%,1/16W,CHIPA]
    2  PWRGD_P5V_AUX      B  @S9S_MB_2U_LIB.S9S_MB_2U(SCH_1):PWRGD_P5V_AUX
    1  P5V_AUX_VCC        A  @S9S_MB_2U_LIB.S9S_MB_2U(SCH_1):P5V_AUX_VCC

Q_RES  I25  PR91   [Q_RES_0402LF-11.8K,1%,1/16W,CHA]
    1  P5V_AUX_FB         A  @S9S_MB_2U_LIB.S9S_MB_2U(SCH_1):P5V_AUX_FB
    2  GND                B  @S9S_MB_2U_LIB.S9S_MB_2U(SCH_1):GND

Q_RES  I32  PR92   [Q_RES_0402LF-86.6K,1%,1/16W,CHA]
    1  P5V_AUX_FB         A  @S9S_MB_2U_LIB.S9S_MB_2U(SCH_1):P5V_AUX_FB
    2  P5V_AUX            B  @S9S_MB_2U_LIB.S9S_MB_2U(SCH_1):P5V_AUX

Q_RES  I14  PR97   [Q_RES_0402LF-2.2,1%,1/16W,CHIPA]
    2  PVCCFA_EHV_CPU0_VDD1      B  @S9S_MB_2U_LIB.S9S_MB_2U(SCH_1):PVCCFA_EHV_CPU0_VDD1
    1  PVCCFA_EHV_CPU0_PVCC      A  @S9S_MB_2U_LIB.S9S_MB_2U(SCH_1):PVCCFA_EHV_CPU0_PVCC

Q_RES  I175  PR101  [Q_RES_0402LF-2.2,1%,1/16W,CHIPA]
    2  PVCCINFAON_CPU0_VDD1      B  @S9S_MB_2U_LIB.S9S_MB_2U(SCH_1):PVCCINFAON_CPU0_VDD1
    1  PVCCINFAON_CPU0_PVCC      A  @S9S_MB_2U_LIB.S9S_MB_2U(SCH_1):PVCCINFAON_CPU0_PVCC

Q_RES  I158  PR102  [Q_RES_0402LF-2.2,1%,1/16W,CHIPA]
    2  PVCCINFAON_CPU0_VDD2      B  @S9S_MB_2U_LIB.S9S_MB_2U(SCH_1):PVCCINFAON_CPU0_VDD2
    1  PVCCINFAON_CPU0_PVCC      A  @S9S_MB_2U_LIB.S9S_MB_2U(SCH_1):PVCCINFAON_CPU0_PVCC

Q_RES  I3   PR105  [Q_RES_0402LF-28K,1%,1/16W,EMPTA]
    1  PVCCINFAON_CPU0_VREF      A  @S9S_MB_2U_LIB.S9S_MB_2U(SCH_1):PVCCINFAON_CPU0_VREF
    2  PVCCINFAON_CPU0_ADDR      B  @S9S_MB_2U_LIB.S9S_MB_2U(SCH_1):PVCCINFAON_CPU0_ADDR

Q_RES  I25  PR106  [Q_RES_R0402LF-887,1%,1/16W,CHIA]
    1  PVCCINFAON_CPU0_ADDR      A  @S9S_MB_2U_LIB.S9S_MB_2U(SCH_1):PVCCINFAON_CPU0_ADDR
    2  GND                B  @S9S_MB_2U_LIB.S9S_MB_2U(SCH_1):GND

Q_RES  I28  PR107  [Q_RES_0402LF-0,5%,1/16W,EMPTY,A]
    2  PVCCINFAON_CPU0_CSPIN      B  @S9S_MB_2U_LIB.S9S_MB_2U(SCH_1):PVCCINFAON_CPU0_CSPIN
    1  P12V_AUX           A  @S9S_MB_2U_LIB.S9S_MB_2U(SCH_1):P12V_AUX

Q_RES  I27  PR108  [Q_RES_0402LF-0,5%,1/16W,CHIP,CA]
    2  PVCCINFAON_CPU0_VIN_CSNIN      B  @S9S_MB_2U_LIB.S9S_MB_2U(SCH_1):PVCCINFAON_CPU0_VIN_CSNIN
    1  P12V_AUX           A  @S9S_MB_2U_LIB.S9S_MB_2U(SCH_1):P12V_AUX

Q_RES  I68  PR109  [Q_RES_0402LF-1K,1%,1/16W,CHIP,A]
    2  PWRGD_PVCCINFAON_CPU0_R      B  @S9S_MB_2U_LIB.S9S_MB_2U(SCH_1):PWRGD_PVCCINFAON_CPU0_R
    1  P3V3_AUX           A  @S9S_MB_2U_LIB.S9S_MB_2U(SCH_1):P3V3_AUX

Q_RES  I67  PR110  [Q_RES_0402LF-0,5%,1/16W,CHIP,CA]
    2  PWRGD_PVCCINFAON_CPU0_R      B  @S9S_MB_2U_LIB.S9S_MB_2U(SCH_1):PWRGD_PVCCINFAON_CPU0_R
    1  PWRGD_PVCCINFAON_CPU0      A  @S9S_MB_2U_LIB.S9S_MB_2U(SCH_1):PWRGD_PVCCINFAON_CPU0

Q_RES  I64  PR111  [Q_RES_0402LF-0,5%,1/16W,CHIP,CA]
    2  PVCCINFAON_CPU0_EN_R      B  @S9S_MB_2U_LIB.S9S_MB_2U(SCH_1):PVCCINFAON_CPU0_EN_R
    1  FM_PVCCINFAON_CPU0_EN      A  @S9S_MB_2U_LIB.S9S_MB_2U(SCH_1):FM_PVCCINFAON_CPU0_EN

Q_RES  I63  PR112  [Q_RES_0402LF-150,1%,1/16W,CHIPA]
    2  SVID_CLK_PVCCINFAON_CPU0_R      B  @S9S_MB_2U_LIB.S9S_MB_2U(SCH_1):SVID_CLK_PVCCINFAON_CPU0_R
    1  SVID_CLK0_CPU0_R      A  @S9S_MB_2U_LIB.S9S_MB_2U(SCH_1):SVID_CLK0_CPU0_R

Q_RES  I62  PR113  [Q_RES_0402LF-0,5%,1/16W,CHIP,CA]
    2  SVID_DIO_PVCCINFAON_CPU0_R      B  @S9S_MB_2U_LIB.S9S_MB_2U(SCH_1):SVID_DIO_PVCCINFAON_CPU0_R
    1  SVID_DIO0_CPU0_R      A  @S9S_MB_2U_LIB.S9S_MB_2U(SCH_1):SVID_DIO0_CPU0_R

Q_RES  I61  PR114  [Q_RES_0402LF-0,5%,1/16W,CHIP,CA]
    2  SVID_ALERT_PVCCINFAON_CPU0_R      B  @S9S_MB_2U_LIB.S9S_MB_2U(SCH_1):SVID_ALERT_PVCCINFAON_CPU0_R
    1  SVID_ALERT0_CPU0_R_N      A  @S9S_MB_2U_LIB.S9S_MB_2U(SCH_1):SVID_ALERT0_CPU0_R_N

Q_RES  I60  PR115  [Q_RES_0402LF-0,5%,1/16W,CHIP,CA]
    1  SMB_VR_3V3AUX_SCL_R      A  @S9S_MB_2U_LIB.S9S_MB_2U(SCH_1):SMB_VR_3V3AUX_SCL_R
    2  SMB_CLK_PVCCINFAON_CPU0      B  @S9S_MB_2U_LIB.S9S_MB_2U(SCH_1):SMB_CLK_PVCCINFAON_CPU0

Q_RES  I59  PR116  [Q_RES_0402LF-0,5%,1/16W,CHIP,CA]
    1  SMB_VR_3V3AUX_SDA_R      A  @S9S_MB_2U_LIB.S9S_MB_2U(SCH_1):SMB_VR_3V3AUX_SDA_R
    2  SMB_DIO_PVCCINFAON_CPU0      B  @S9S_MB_2U_LIB.S9S_MB_2U(SCH_1):SMB_DIO_PVCCINFAON_CPU0

Q_RES  I31  PR117  [Q_RES_0402LF-1K,1%,1/16W,CHIP,A]
    2  PWRGD_PVCCFA_EHV_CPU0_R      B  @S9S_MB_2U_LIB.S9S_MB_2U(SCH_1):PWRGD_PVCCFA_EHV_CPU0_R
    1  P3V3_AUX           A  @S9S_MB_2U_LIB.S9S_MB_2U(SCH_1):P3V3_AUX

Q_RES  I30  PR118  [Q_RES_0402LF-0,5%,1/16W,CHIP,CA]
    2  PWRGD_PVCCFA_EHV_CPU0_R      B  @S9S_MB_2U_LIB.S9S_MB_2U(SCH_1):PWRGD_PVCCFA_EHV_CPU0_R
    1  PWRGD_PVCCFA_EHV_CPU0      A  @S9S_MB_2U_LIB.S9S_MB_2U(SCH_1):PWRGD_PVCCFA_EHV_CPU0

Q_RES  I32  PR119  [Q_RES_0402LF-0,5%,1/16W,CHIP,CA]
    2  PVCCFA_EHV_CPU0_EN_R      B  @S9S_MB_2U_LIB.S9S_MB_2U(SCH_1):PVCCFA_EHV_CPU0_EN_R
    1  FM_PVCCFA_EHV_CPU0_EN      A  @S9S_MB_2U_LIB.S9S_MB_2U(SCH_1):FM_PVCCFA_EHV_CPU0_EN

Q_RES  I58  PR120  [Q_RES_0402LF-0,5%,1/16W,CHIP,CA]
    2  SH_PVCCINFAON_CPU0_R      B  @S9S_MB_2U_LIB.S9S_MB_2U(SCH_1):SH_PVCCINFAON_CPU0_R
    1  SH_PVCCINFAON_CPU0      A  @S9S_MB_2U_LIB.S9S_MB_2U(SCH_1):SH_PVCCINFAON_CPU0

Q_RES  I45  PR121  [Q_RES_0402LF-0,5%,1/16W,CHIP,CA]
    2  SH_PVCCFA_EHV_CPU0_R      B  @S9S_MB_2U_LIB.S9S_MB_2U(SCH_1):SH_PVCCFA_EHV_CPU0_R
    1  SH_PVCCFA_EHV_CPU0      A  @S9S_MB_2U_LIB.S9S_MB_2U(SCH_1):SH_PVCCFA_EHV_CPU0

Q_RES  I33  PR122  [Q_RES_0402LF-0,5%,1/16W,CHIP,CA]
    1  PVCCINFAON_CPU0_CSPIN      A  @S9S_MB_2U_LIB.S9S_MB_2U(SCH_1):PVCCINFAON_CPU0_CSPIN
    2  GND                B  @S9S_MB_2U_LIB.S9S_MB_2U(SCH_1):GND

Q_RES  I36  PR123  [Q_RES_0402LF-1K,1%,1/16W,EMPTYA]
    1  PVCCINFAON_CPU0_VIN_CSNIN      A  @S9S_MB_2U_LIB.S9S_MB_2U(SCH_1):PVCCINFAON_CPU0_VIN_CSNIN
    2  GND                B  @S9S_MB_2U_LIB.S9S_MB_2U(SCH_1):GND

Q_RES  I95  PR130  [Q_RES_0402LF-1,1%,1/16W,CHIP,CA]
    1  PVCCINFAON_CPU0_VCC      A  @S9S_MB_2U_LIB.S9S_MB_2U(SCH_1):PVCCINFAON_CPU0_VCC
    2  P3V3_AUX           B  @S9S_MB_2U_LIB.S9S_MB_2U(SCH_1):P3V3_AUX

Q_RES  I80  PR131  [Q_RES_0402LF-1K,1%,1/16W,CHIP,A]
    1  P3V3_AUX           A  @S9S_MB_2U_LIB.S9S_MB_2U(SCH_1):P3V3_AUX
    2  IRQ_CPU0_VRHOT_N      B  @S9S_MB_2U_LIB.S9S_MB_2U(SCH_1):IRQ_CPU0_VRHOT_N

Q_RES  I2   PR132  [Q_RES_0402LF-8.87K,1%,1/16W,EMA]
    1  PVCCIN_CPU0_LSET8      A  @S9S_MB_2U_LIB.S9S_MB_2U(SCH_1):PVCCIN_CPU0_LSET8
    2  GND                B  @S9S_MB_2U_LIB.S9S_MB_2U(SCH_1):GND

Q_RES  I13  PR133  [Q_RES_0402LF-8.87K,1%,1/16W,EMA]
    1  PVCCIN_CPU0_LSET7      A  @S9S_MB_2U_LIB.S9S_MB_2U(SCH_1):PVCCIN_CPU0_LSET7
    2  GND                B  @S9S_MB_2U_LIB.S9S_MB_2U(SCH_1):GND

Q_RES  I10  PR134  [Q_RES_0402LF-2.2,1%,1/16W,CHIPA]
    2  PVCCIN_CPU0_VDD8      B  @S9S_MB_2U_LIB.S9S_MB_2U(SCH_1):PVCCIN_CPU0_VDD8
    1  PVCCIN_CPU0_PVCC      A  @S9S_MB_2U_LIB.S9S_MB_2U(SCH_1):PVCCIN_CPU0_PVCC

Q_RES  I26  PR135  [Q_RES_0402LF-2.2,1%,1/16W,CHIPA]
    2  PVCCIN_CPU0_VDD7      B  @S9S_MB_2U_LIB.S9S_MB_2U(SCH_1):PVCCIN_CPU0_VDD7
    1  PVCCIN_CPU0_PVCC      A  @S9S_MB_2U_LIB.S9S_MB_2U(SCH_1):PVCCIN_CPU0_PVCC

Q_RES  I99  PR136  [Q_RES_0402LF-0,5%,1/16W,CHIP,CA]
    1  PVCCIN_CPU0_VOS8      A  @S9S_MB_2U_LIB.S9S_MB_2U(SCH_1):PVCCIN_CPU0_VOS8
    2  PVCCIN_CPU0        B  @S9S_MB_2U_LIB.S9S_MB_2U(SCH_1):PVCCIN_CPU0

Q_RES  I84  PR137  [Q_RES_0402LF-0,5%,1/16W,CHIP,CA]
    1  PVCCIN_CPU0_VOS7      A  @S9S_MB_2U_LIB.S9S_MB_2U(SCH_1):PVCCIN_CPU0_VOS7
    2  PVCCIN_CPU0        B  @S9S_MB_2U_LIB.S9S_MB_2U(SCH_1):PVCCIN_CPU0

Q_RES  I2   PR138  [Q_RES_0402LF-8.87K,1%,1/16W,EMA]
    1  PVCCIN_CPU0_LSET6      A  @S9S_MB_2U_LIB.S9S_MB_2U(SCH_1):PVCCIN_CPU0_LSET6
    2  GND                B  @S9S_MB_2U_LIB.S9S_MB_2U(SCH_1):GND

Q_RES  I21  PR139  [Q_RES_0402LF-8.87K,1%,1/16W,EMA]
    1  PVCCIN_CPU0_LSET5      A  @S9S_MB_2U_LIB.S9S_MB_2U(SCH_1):PVCCIN_CPU0_LSET5
    2  GND                B  @S9S_MB_2U_LIB.S9S_MB_2U(SCH_1):GND

Q_RES  I11  PR140  [Q_RES_0402LF-2.2,1%,1/16W,CHIPA]
    2  PVCCIN_CPU0_VDD6      B  @S9S_MB_2U_LIB.S9S_MB_2U(SCH_1):PVCCIN_CPU0_VDD6
    1  PVCCIN_CPU0_PVCC      A  @S9S_MB_2U_LIB.S9S_MB_2U(SCH_1):PVCCIN_CPU0_PVCC

Q_RES  I32  PR141  [Q_RES_0402LF-2.2,1%,1/16W,CHIPA]
    2  PVCCIN_CPU0_VDD5      B  @S9S_MB_2U_LIB.S9S_MB_2U(SCH_1):PVCCIN_CPU0_VDD5
    1  PVCCIN_CPU0_PVCC      A  @S9S_MB_2U_LIB.S9S_MB_2U(SCH_1):PVCCIN_CPU0_PVCC

Q_RES  I92  PR142  [Q_RES_0402LF-0,5%,1/16W,CHIP,CA]
    1  PVCCIN_CPU0_VOS6      A  @S9S_MB_2U_LIB.S9S_MB_2U(SCH_1):PVCCIN_CPU0_VOS6
    2  PVCCIN_CPU0        B  @S9S_MB_2U_LIB.S9S_MB_2U(SCH_1):PVCCIN_CPU0

Q_RES  I76  PR143  [Q_RES_0402LF-0,5%,1/16W,CHIP,CA]
    1  PVCCIN_CPU0_VOS5      A  @S9S_MB_2U_LIB.S9S_MB_2U(SCH_1):PVCCIN_CPU0_VOS5
    2  PVCCIN_CPU0        B  @S9S_MB_2U_LIB.S9S_MB_2U(SCH_1):PVCCIN_CPU0

Q_RES  I2   PR144  [Q_RES_0402LF-8.87K,1%,1/16W,EMA]
    1  PVCCIN_CPU0_LSET4      A  @S9S_MB_2U_LIB.S9S_MB_2U(SCH_1):PVCCIN_CPU0_LSET4
    2  GND                B  @S9S_MB_2U_LIB.S9S_MB_2U(SCH_1):GND

Q_RES  I19  PR145  [Q_RES_0402LF-8.87K,1%,1/16W,EMA]
    1  PVCCIN_CPU0_LSET3      A  @S9S_MB_2U_LIB.S9S_MB_2U(SCH_1):PVCCIN_CPU0_LSET3
    2  GND                B  @S9S_MB_2U_LIB.S9S_MB_2U(SCH_1):GND

Q_RES  I10  PR146  [Q_RES_0402LF-2.2,1%,1/16W,CHIPA]
    2  PVCCIN_CPU0_VDD4      B  @S9S_MB_2U_LIB.S9S_MB_2U(SCH_1):PVCCIN_CPU0_VDD4
    1  PVCCIN_CPU0_PVCC      A  @S9S_MB_2U_LIB.S9S_MB_2U(SCH_1):PVCCIN_CPU0_PVCC

Q_RES  I27  PR147  [Q_RES_0402LF-2.2,1%,1/16W,CHIPA]
    2  PVCCIN_CPU0_VDD3      B  @S9S_MB_2U_LIB.S9S_MB_2U(SCH_1):PVCCIN_CPU0_VDD3
    1  PVCCIN_CPU0_PVCC      A  @S9S_MB_2U_LIB.S9S_MB_2U(SCH_1):PVCCIN_CPU0_PVCC

Q_RES  I92  PR148  [Q_RES_0402LF-0,5%,1/16W,CHIP,CA]
    1  PVCCIN_CPU0_VOS4      A  @S9S_MB_2U_LIB.S9S_MB_2U(SCH_1):PVCCIN_CPU0_VOS4
    2  PVCCIN_CPU0        B  @S9S_MB_2U_LIB.S9S_MB_2U(SCH_1):PVCCIN_CPU0

Q_RES  I76  PR149  [Q_RES_0402LF-0,5%,1/16W,CHIP,CA]
    1  PVCCIN_CPU0_VOS3      A  @S9S_MB_2U_LIB.S9S_MB_2U(SCH_1):PVCCIN_CPU0_VOS3
    2  PVCCIN_CPU0        B  @S9S_MB_2U_LIB.S9S_MB_2U(SCH_1):PVCCIN_CPU0

Q_RES  I2   PR150  [Q_RES_0402LF-8.87K,1%,1/16W,EMA]
    1  PVCCIN_CPU0_LSET2      A  @S9S_MB_2U_LIB.S9S_MB_2U(SCH_1):PVCCIN_CPU0_LSET2
    2  GND                B  @S9S_MB_2U_LIB.S9S_MB_2U(SCH_1):GND

Q_RES  I14  PR151  [Q_RES_0402LF-8.87K,1%,1/16W,EMA]
    1  PVCCIN_CPU0_LSET1      A  @S9S_MB_2U_LIB.S9S_MB_2U(SCH_1):PVCCIN_CPU0_LSET1
    2  GND                B  @S9S_MB_2U_LIB.S9S_MB_2U(SCH_1):GND

Q_RES  I11  PR152  [Q_RES_0402LF-2.2,1%,1/16W,CHIPA]
    2  PVCCIN_CPU0_VDD2      B  @S9S_MB_2U_LIB.S9S_MB_2U(SCH_1):PVCCIN_CPU0_VDD2
    1  PVCCIN_CPU0_PVCC      A  @S9S_MB_2U_LIB.S9S_MB_2U(SCH_1):PVCCIN_CPU0_PVCC

Q_RES  I32  PR153  [Q_RES_0402LF-2.2,1%,1/16W,CHIPA]
    2  PVCCIN_CPU0_VDD1      B  @S9S_MB_2U_LIB.S9S_MB_2U(SCH_1):PVCCIN_CPU0_VDD1
    1  PVCCIN_CPU0_PVCC      A  @S9S_MB_2U_LIB.S9S_MB_2U(SCH_1):PVCCIN_CPU0_PVCC

Q_RES  I124  PR154  [Q_RES_0402LF-0,5%,1/16W,CHIP,CA]
    1  PVCCIN_CPU0_VOS2      A  @S9S_MB_2U_LIB.S9S_MB_2U(SCH_1):PVCCIN_CPU0_VOS2
    2  PVCCIN_CPU0        B  @S9S_MB_2U_LIB.S9S_MB_2U(SCH_1):PVCCIN_CPU0

Q_RES  I112  PR155  [Q_RES_0402LF-0,5%,1/16W,CHIP,CA]
    1  PVCCIN_CPU0_VOS1      A  @S9S_MB_2U_LIB.S9S_MB_2U(SCH_1):PVCCIN_CPU0_VOS1
    2  PVCCIN_CPU0        B  @S9S_MB_2U_LIB.S9S_MB_2U(SCH_1):PVCCIN_CPU0

Q_RES  I6   PR156  [Q_RES_0402LF-0,5%,1/16W,CHIP,CA]
    2  PVCCIN_CPU0_VIN_CSNIN      B  @S9S_MB_2U_LIB.S9S_MB_2U(SCH_1):PVCCIN_CPU0_VIN_CSNIN
    1  P12V_AUX           A  @S9S_MB_2U_LIB.S9S_MB_2U(SCH_1):P12V_AUX

Q_RES  I9   PR157  [Q_RES_0402LF-0,5%,1/16W,EMPTY,A]
    2  PVCCIN_CPU0_CSPIN      B  @S9S_MB_2U_LIB.S9S_MB_2U(SCH_1):PVCCIN_CPU0_CSPIN
    1  P12V_AUX           A  @S9S_MB_2U_LIB.S9S_MB_2U(SCH_1):P12V_AUX

Q_RES  I36  PR158  [Q_RES_0402LF-0,5%,1/16W,CHIP,CA]
    1  PVCCIN_CPU0_CSPIN      A  @S9S_MB_2U_LIB.S9S_MB_2U(SCH_1):PVCCIN_CPU0_CSPIN
    2  GND                B  @S9S_MB_2U_LIB.S9S_MB_2U(SCH_1):GND

Q_RES  I7   PR159  [Q_RES_0402LF-28K,1%,1/16W,EMPTA]
    1  PVCCIN_CPU0_VREF      A  @S9S_MB_2U_LIB.S9S_MB_2U(SCH_1):PVCCIN_CPU0_VREF
    2  PVCCIN_CPU0_ADDR      B  @S9S_MB_2U_LIB.S9S_MB_2U(SCH_1):PVCCIN_CPU0_ADDR

Q_RES  I71  PR160  [Q_RES_0402LF-1K,1%,1/16W,CHIP,A]
    2  PWRGD_PVCCIN_CPU0_R      B  @S9S_MB_2U_LIB.S9S_MB_2U(SCH_1):PWRGD_PVCCIN_CPU0_R
    1  P3V3_AUX           A  @S9S_MB_2U_LIB.S9S_MB_2U(SCH_1):P3V3_AUX

Q_RES  I70  PR161  [Q_RES_0402LF-0,5%,1/16W,CHIP,CA]
    2  PWRGD_PVCCIN_CPU0_R      B  @S9S_MB_2U_LIB.S9S_MB_2U(SCH_1):PWRGD_PVCCIN_CPU0_R
    1  PWRGD_PVCCIN_CPU0      A  @S9S_MB_2U_LIB.S9S_MB_2U(SCH_1):PWRGD_PVCCIN_CPU0

Q_RES  I69  PR162  [Q_RES_0402LF-0,5%,1/16W,CHIP,CA]
    2  PVCCIN_CPU0_EN_R      B  @S9S_MB_2U_LIB.S9S_MB_2U(SCH_1):PVCCIN_CPU0_EN_R
    1  FM_PVCCIN_CPU0_EN      A  @S9S_MB_2U_LIB.S9S_MB_2U(SCH_1):FM_PVCCIN_CPU0_EN

Q_RES  I66  PR163  [Q_RES_0402LF-150,1%,1/16W,CHIPA]
    2  SVID_CLK_PVCCIN_CPU0_R      B  @S9S_MB_2U_LIB.S9S_MB_2U(SCH_1):SVID_CLK_PVCCIN_CPU0_R
    1  SVID_CLK0_CPU0_R      A  @S9S_MB_2U_LIB.S9S_MB_2U(SCH_1):SVID_CLK0_CPU0_R

Q_RES  I65  PR164  [Q_RES_0402LF-0,5%,1/16W,CHIP,CA]
    2  SVID_DIO_PVCCIN_CPU0_R      B  @S9S_MB_2U_LIB.S9S_MB_2U(SCH_1):SVID_DIO_PVCCIN_CPU0_R
    1  SVID_DIO0_CPU0_R      A  @S9S_MB_2U_LIB.S9S_MB_2U(SCH_1):SVID_DIO0_CPU0_R

Q_RES  I63  PR165  [Q_RES_0402LF-0,5%,1/16W,CHIP,CA]
    2  SVID_ALERT_PVCCIN_CPU0_R      B  @S9S_MB_2U_LIB.S9S_MB_2U(SCH_1):SVID_ALERT_PVCCIN_CPU0_R
    1  SVID_ALERT0_CPU0_R_N      A  @S9S_MB_2U_LIB.S9S_MB_2U(SCH_1):SVID_ALERT0_CPU0_R_N

Q_RES  I44  PR166  [Q_RES_0402LF-1K,1%,1/16W,EMPTYA]
    1  PVCCIN_CPU0_VIN_CSNIN      A  @S9S_MB_2U_LIB.S9S_MB_2U(SCH_1):PVCCIN_CPU0_VIN_CSNIN
    2  GND                B  @S9S_MB_2U_LIB.S9S_MB_2U(SCH_1):GND

Q_RES  I64  PR167  [Q_RES_0402LF-0,5%,1/16W,CHIP,CA]
    1  SMB_VR_3V3AUX_SCL_R      A  @S9S_MB_2U_LIB.S9S_MB_2U(SCH_1):SMB_VR_3V3AUX_SCL_R
    2  SMB_CLK_PVCCIN_CPU0      B  @S9S_MB_2U_LIB.S9S_MB_2U(SCH_1):SMB_CLK_PVCCIN_CPU0

Q_RES  I61  PR168  [Q_RES_0402LF-0,5%,1/16W,CHIP,CA]
    1  SMB_VR_3V3AUX_SDA_R      A  @S9S_MB_2U_LIB.S9S_MB_2U(SCH_1):SMB_VR_3V3AUX_SDA_R
    2  SMB_DIO_PVCCIN_CPU0      B  @S9S_MB_2U_LIB.S9S_MB_2U(SCH_1):SMB_DIO_PVCCIN_CPU0

Q_RES  I51  PR169  [Q_RES_0402LF-1K,1%,1/16W,CHIP,A]
    2  PVCCIN_CPU0_PIN_ALERT      B  @S9S_MB_2U_LIB.S9S_MB_2U(SCH_1):PVCCIN_CPU0_PIN_ALERT
    1  P3V3_AUX           A  @S9S_MB_2U_LIB.S9S_MB_2U(SCH_1):P3V3_AUX

Q_RES  I60  PR170  [Q_RES_0402LF-0,5%,1/16W,CHIP,CA]
    2  SH_PVCCIN_CPU0_R      B  @S9S_MB_2U_LIB.S9S_MB_2U(SCH_1):SH_PVCCIN_CPU0_R
    1  SH_PVCCIN_CPU0      A  @S9S_MB_2U_LIB.S9S_MB_2U(SCH_1):SH_PVCCIN_CPU0

Q_RES  I5   PR171  [Q_RES_0402LF-0,5%,1/16W,CHIP,CA]
    1  PVCCIN_CPU0_ADDR      A  @S9S_MB_2U_LIB.S9S_MB_2U(SCH_1):PVCCIN_CPU0_ADDR
    2  GND                B  @S9S_MB_2U_LIB.S9S_MB_2U(SCH_1):GND

Q_RES  I53  PR172  [Q_RES_0402LF-1K,1%,1/16W,CHIP,A]
    2  PVCCIN_CPU0_VR_FAULT      B  @S9S_MB_2U_LIB.S9S_MB_2U(SCH_1):PVCCIN_CPU0_VR_FAULT
    1  P3V3_AUX           A  @S9S_MB_2U_LIB.S9S_MB_2U(SCH_1):P3V3_AUX

Q_RES  I121  PR176  [Q_RES_0402LF-1,1%,1/16W,CHIP,CA]
    1  PVCCIN_CPU0_VCC      A  @S9S_MB_2U_LIB.S9S_MB_2U(SCH_1):PVCCIN_CPU0_VCC
    2  P3V3_AUX           B  @S9S_MB_2U_LIB.S9S_MB_2U(SCH_1):P3V3_AUX

Q_RES  I55  PR177  [Q_RES_0402LF-1K,1%,1/16W,CHIP,A]
    1  P3V3_AUX           A  @S9S_MB_2U_LIB.S9S_MB_2U(SCH_1):P3V3_AUX
    2  IRQ_CPU0_VRHOT_N      B  @S9S_MB_2U_LIB.S9S_MB_2U(SCH_1):IRQ_CPU0_VRHOT_N

Q_RES  I38  PR186  [Q_RES_0402LF-10K,1%,1/16W,CHIPA]
    2  PWRGD_P1V05_PCH_AUX_R      B  @S9S_MB_2U_LIB.S9S_MB_2U(SCH_1):PWRGD_P1V05_PCH_AUX_R
    1  P3V3_AUX           A  @S9S_MB_2U_LIB.S9S_MB_2U(SCH_1):P3V3_AUX

Q_RES  I13  PR187  [Q_RES_0402LF-10K,1%,1/16W,CHIPA]
    2  SH_P1V05_PCH_AUX_N      B  @S9S_MB_2U_LIB.S9S_MB_2U(SCH_1):SH_P1V05_PCH_AUX_N
    1  P1V05_PCH_AUX_FB      A  @S9S_MB_2U_LIB.S9S_MB_2U(SCH_1):P1V05_PCH_AUX_FB

Q_RES  I13  PR200  [Q_RES_0402LF-2.2,1%,1/16W,CHIPA]
    2  PVCCD_HV_CPU1_VDD1      B  @S9S_MB_2U_LIB.S9S_MB_2U(SCH_1):PVCCD_HV_CPU1_VDD1
    1  PVCCD_HV_CPU1_PVCC      A  @S9S_MB_2U_LIB.S9S_MB_2U(SCH_1):PVCCD_HV_CPU1_PVCC

Q_RES  I204  PR202  [Q_RES_0402LF-28K,1%,1/16W,EMPTA]
    1  PVCCD_HV_CPU1_VREF      A  @S9S_MB_2U_LIB.S9S_MB_2U(SCH_1):PVCCD_HV_CPU1_VREF
    2  PVCCD_HV_CPU1_ADDR      B  @S9S_MB_2U_LIB.S9S_MB_2U(SCH_1):PVCCD_HV_CPU1_ADDR

Q_RES  I201  PR203  [Q_RES_0402LF-30.1K    ,1%  ,1/A]
    2  PVCCD_HV_CPU1_ADDR      B  @S9S_MB_2U_LIB.S9S_MB_2U(SCH_1):PVCCD_HV_CPU1_ADDR
    1  GND                A  @S9S_MB_2U_LIB.S9S_MB_2U(SCH_1):GND

Q_RES  I233  PR206  [Q_RES_0402LF-1K,1%,1/16W,CHIP,A]
    2  PWRGD_PVCCD_HV_CPU1_R      B  @S9S_MB_2U_LIB.S9S_MB_2U(SCH_1):PWRGD_PVCCD_HV_CPU1_R
    1  P3V3_AUX           A  @S9S_MB_2U_LIB.S9S_MB_2U(SCH_1):P3V3_AUX

Q_RES  I232  PR207  [Q_RES_0402LF-0,5%,1/16W,CHIP,CA]
    2  PWRGD_PVCCD_HV_CPU1_R      B  @S9S_MB_2U_LIB.S9S_MB_2U(SCH_1):PWRGD_PVCCD_HV_CPU1_R
    1  PWRGD_PVCCD_HV_CPU1      A  @S9S_MB_2U_LIB.S9S_MB_2U(SCH_1):PWRGD_PVCCD_HV_CPU1

Q_RES  I230  PR208  [Q_RES_0402LF-0,5%,1/16W,CHIP,CA]
    2  PVCCD_HV_CPU1_EN_R      B  @S9S_MB_2U_LIB.S9S_MB_2U(SCH_1):PVCCD_HV_CPU1_EN_R
    1  FM_PVCCD_HV_CPU1_EN      A  @S9S_MB_2U_LIB.S9S_MB_2U(SCH_1):FM_PVCCD_HV_CPU1_EN

Q_RES  I229  PR209  [Q_RES_0402LF-150,1%,1/16W,CHIPA]
    2  SVID_CLK_PVCCD_HV_CPU1_R      B  @S9S_MB_2U_LIB.S9S_MB_2U(SCH_1):SVID_CLK_PVCCD_HV_CPU1_R
    1  SVID_CLK1_CPU1_R      A  @S9S_MB_2U_LIB.S9S_MB_2U(SCH_1):SVID_CLK1_CPU1_R

Q_RES  I228  PR210  [Q_RES_0402LF-0,5%,1/16W,CHIP,CA]
    2  SVID_DIO_PVCCD_HV_CPU1_R      B  @S9S_MB_2U_LIB.S9S_MB_2U(SCH_1):SVID_DIO_PVCCD_HV_CPU1_R
    1  SVID_DIO1_CPU1_R      A  @S9S_MB_2U_LIB.S9S_MB_2U(SCH_1):SVID_DIO1_CPU1_R

Q_RES  I227  PR211  [Q_RES_0402LF-0,5%,1/16W,CHIP,CA]
    2  SVID_ALERT_PVCCD_HV_CPU1_R      B  @S9S_MB_2U_LIB.S9S_MB_2U(SCH_1):SVID_ALERT_PVCCD_HV_CPU1_R
    1  SVID_ALERT1_CPU1_R_N      A  @S9S_MB_2U_LIB.S9S_MB_2U(SCH_1):SVID_ALERT1_CPU1_R_N

Q_RES  I225  PR212  [Q_RES_0402LF-0,5%,1/16W,CHIP,CA]
    1  SMB_VR_3V3AUX_SCL_R      A  @S9S_MB_2U_LIB.S9S_MB_2U(SCH_1):SMB_VR_3V3AUX_SCL_R
    2  SMB_CLK_PVCCD_HV_CPU1      B  @S9S_MB_2U_LIB.S9S_MB_2U(SCH_1):SMB_CLK_PVCCD_HV_CPU1

Q_RES  I226  PR213  [Q_RES_0402LF-0,5%,1/16W,CHIP,CA]
    1  SMB_VR_3V3AUX_SDA_R      A  @S9S_MB_2U_LIB.S9S_MB_2U(SCH_1):SMB_VR_3V3AUX_SDA_R
    2  SMB_DIO_PVCCD_HV_CPU1      B  @S9S_MB_2U_LIB.S9S_MB_2U(SCH_1):SMB_DIO_PVCCD_HV_CPU1

Q_RES  I236  PR214  [Q_RES_0402LF-1K,1%,1/16W,EMPTYA]
    1  PVCCD_HV_CPU1_ISENSE_P      A  @S9S_MB_2U_LIB.S9S_MB_2U(SCH_1):PVCCD_HV_CPU1_ISENSE_P
    2  GND                B  @S9S_MB_2U_LIB.S9S_MB_2U(SCH_1):GND

Q_RES  I245  PR215  [Q_RES_0402LF-1K,1%,1/16W,CHIP,A]
    2  PVCCD_HV_CPU1_PIN_ALT      B  @S9S_MB_2U_LIB.S9S_MB_2U(SCH_1):PVCCD_HV_CPU1_PIN_ALT
    1  P3V3_AUX           A  @S9S_MB_2U_LIB.S9S_MB_2U(SCH_1):P3V3_AUX

Q_RES  I252  PR216  [Q_RES_0402LF-0,5%,1/16W,CHIP,CA]
    2  SH_PVCCD_HV_CPU1_R      B  @S9S_MB_2U_LIB.S9S_MB_2U(SCH_1):SH_PVCCD_HV_CPU1_R
    1  SH_PVCCD_HV_CPU1      A  @S9S_MB_2U_LIB.S9S_MB_2U(SCH_1):SH_PVCCD_HV_CPU1

Q_RES  I247  PR217  [Q_RES_0402LF-1K,1%,1/16W,CHIP,A]
    2  PVCCD_HV_CPU1_FAULT      B  @S9S_MB_2U_LIB.S9S_MB_2U(SCH_1):PVCCD_HV_CPU1_FAULT
    1  P3V3_AUX           A  @S9S_MB_2U_LIB.S9S_MB_2U(SCH_1):P3V3_AUX

Q_RES  I238  PR218  [Q_RES_0402LF-1K,1%,1/16W,EMPTYA]
    1  PVCCD_HV_CPU1_ISENSE_N      A  @S9S_MB_2U_LIB.S9S_MB_2U(SCH_1):PVCCD_HV_CPU1_ISENSE_N
    2  GND                B  @S9S_MB_2U_LIB.S9S_MB_2U(SCH_1):GND

Q_RES  I274  PR220  [Q_RES_0402LF-1,1%,1/16W,CHIP,CA]
    1  PVCCD_HV_CPU1_VCC      A  @S9S_MB_2U_LIB.S9S_MB_2U(SCH_1):PVCCD_HV_CPU1_VCC
    2  P3V3_AUX           B  @S9S_MB_2U_LIB.S9S_MB_2U(SCH_1):P3V3_AUX

Q_RES  I261  PR223  [Q_RES_0402LF-1K,1%,1/16W,CHIP,A]
    1  P3V3_AUX           A  @S9S_MB_2U_LIB.S9S_MB_2U(SCH_1):P3V3_AUX
    2  IRQ_PVCCD_CPU1_VRHOT_LVC3_N      B  @S9S_MB_2U_LIB.S9S_MB_2U(SCH_1):IRQ_PVCCD_CPU1_VRHOT_LVC3_N

Q_RES  I202  PR224  [Q_RES_0402LF-8.87K,1%,1/16W,EMA]
    1  PVCCFA_EHV_FIVRA_CPU1_LSET2      A  @S9S_MB_2U_LIB.S9S_MB_2U(SCH_1):PVCCFA_EHV_FIVRA_CPU1_LSET2
    2  GND                B  @S9S_MB_2U_LIB.S9S_MB_2U(SCH_1):GND

Q_RES  I213  PR225  [Q_RES_0402LF-8.87K,1%,1/16W,EMA]
    1  PVCCFA_EHV_FIVRA_CPU1_LSET1      A  @S9S_MB_2U_LIB.S9S_MB_2U(SCH_1):PVCCFA_EHV_FIVRA_CPU1_LSET1
    2  GND                B  @S9S_MB_2U_LIB.S9S_MB_2U(SCH_1):GND

Q_RES  I232  PR226  [Q_RES_0402LF-2.2,1%,1/16W,CHIPA]
    2  PVCCFA_EHV_FIVRA_CPU1_VDD1      B  @S9S_MB_2U_LIB.S9S_MB_2U(SCH_1):PVCCFA_EHV_FIVRA_CPU1_VDD1
    1  PVCCFA_EHV_FIVRA_CPU1_PVCC1      A  @S9S_MB_2U_LIB.S9S_MB_2U(SCH_1):PVCCFA_EHV_FIVRA_CPU1_PVCC1

Q_RES  I215  PR227  [Q_RES_0402LF-2.2,1%,1/16W,CHIPA]
    2  PVCCFA_EHV_FIVRA_CPU1_VDD2      B  @S9S_MB_2U_LIB.S9S_MB_2U(SCH_1):PVCCFA_EHV_FIVRA_CPU1_VDD2
    1  PVCCFA_EHV_FIVRA_CPU1_PVCC2      A  @S9S_MB_2U_LIB.S9S_MB_2U(SCH_1):PVCCFA_EHV_FIVRA_CPU1_PVCC2

Q_RES  I203  PR232  [Q_RES_0402LF-1K,1%,1/16W,CHIP,A]
    2  PWRGD_PVCCFA_EHV_FIVRA_CPU1_R      B  @S9S_MB_2U_LIB.S9S_MB_2U(SCH_1):PWRGD_PVCCFA_EHV_FIVRA_CPU1_R
    1  P3V3_AUX           A  @S9S_MB_2U_LIB.S9S_MB_2U(SCH_1):P3V3_AUX

Q_RES  I202  PR233  [Q_RES_0402LF-0,5%,1/16W,CHIP,CA]
    2  PWRGD_PVCCFA_EHV_FIVRA_CPU1_R      B  @S9S_MB_2U_LIB.S9S_MB_2U(SCH_1):PWRGD_PVCCFA_EHV_FIVRA_CPU1_R
    1  PWRGD_PVCCFA_EHV_FIVRA_CPU1      A  @S9S_MB_2U_LIB.S9S_MB_2U(SCH_1):PWRGD_PVCCFA_EHV_FIVRA_CPU1

Q_RES  I204  PR234  [Q_RES_0402LF-0,5%,1/16W,CHIP,CA]
    2  PVCCFA_EHV_FIVRA_CPU1_EN_R      B  @S9S_MB_2U_LIB.S9S_MB_2U(SCH_1):PVCCFA_EHV_FIVRA_CPU1_EN_R
    1  FM_PVCCFA_EHV_FIVRA_CPU1_EN      A  @S9S_MB_2U_LIB.S9S_MB_2U(SCH_1):FM_PVCCFA_EHV_FIVRA_CPU1_EN

Q_RES  I214  PR241  [Q_RES_0402LF-1K,1%,1/16W,CHIP,A]
    2  PVCCIN_CPU1_PIN_ALERT      B  @S9S_MB_2U_LIB.S9S_MB_2U(SCH_1):PVCCIN_CPU1_PIN_ALERT
    1  P3V3_AUX           A  @S9S_MB_2U_LIB.S9S_MB_2U(SCH_1):P3V3_AUX

Q_RES  I220  PR242  [Q_RES_0402LF-0,5%,1/16W,CHIP,CA]
    2  SH_PVCCFA_EHV_FIVRA_CPU1_R      B  @S9S_MB_2U_LIB.S9S_MB_2U(SCH_1):SH_PVCCFA_EHV_FIVRA_CPU1_R
    1  SH_PVCCFA_EHV_FIVRA_CPU1      A  @S9S_MB_2U_LIB.S9S_MB_2U(SCH_1):SH_PVCCFA_EHV_FIVRA_CPU1

Q_RES  I215  PR243  [Q_RES_0402LF-1K,1%,1/16W,CHIP,A]
    2  PVCCIN_CPU1_VR_FAULT      B  @S9S_MB_2U_LIB.S9S_MB_2U(SCH_1):PVCCIN_CPU1_VR_FAULT
    1  P3V3_AUX           A  @S9S_MB_2U_LIB.S9S_MB_2U(SCH_1):P3V3_AUX

Q_RES  I218  PR249  [Q_RES_0402LF-1K,1%,1/16W,CHIP,A]
    1  P3V3_AUX           A  @S9S_MB_2U_LIB.S9S_MB_2U(SCH_1):P3V3_AUX
    2  IRQ_CPU1_VRHOT_N      B  @S9S_MB_2U_LIB.S9S_MB_2U(SCH_1):IRQ_CPU1_VRHOT_N

Q_RES  I13  PR250  [Q_RES_0402LF-2.2,1%,1/16W,CHIPA]
    2  PVCCFA_EHV_CPU1_VDD1      B  @S9S_MB_2U_LIB.S9S_MB_2U(SCH_1):PVCCFA_EHV_CPU1_VDD1
    1  PVCCFA_EHV_CPU1_PVCC      A  @S9S_MB_2U_LIB.S9S_MB_2U(SCH_1):PVCCFA_EHV_CPU1_PVCC

Q_RES  I27  PR254  [Q_RES_0402LF-2.2,1%,1/16W,CHIPA]
    2  PVCCINFAON_CPU1_VDD1      B  @S9S_MB_2U_LIB.S9S_MB_2U(SCH_1):PVCCINFAON_CPU1_VDD1
    1  PVCCINFAON_CPU1_PVCC      A  @S9S_MB_2U_LIB.S9S_MB_2U(SCH_1):PVCCINFAON_CPU1_PVCC

Q_RES  I15  PR255  [Q_RES_0402LF-2.2,1%,1/16W,CHIPA]
    2  PVCCINFAON_CPU1_VDD2      B  @S9S_MB_2U_LIB.S9S_MB_2U(SCH_1):PVCCINFAON_CPU1_VDD2
    1  PVCCINFAON_CPU1_PVCC      A  @S9S_MB_2U_LIB.S9S_MB_2U(SCH_1):PVCCINFAON_CPU1_PVCC

Q_RES  I10  PR258  [Q_RES_0402LF-28K,1%,1/16W,EMPTA]
    1  PVCCINFAON_CPU1_VREF      A  @S9S_MB_2U_LIB.S9S_MB_2U(SCH_1):PVCCINFAON_CPU1_VREF
    2  PVCCINFAON_CPU1_ADDR      B  @S9S_MB_2U_LIB.S9S_MB_2U(SCH_1):PVCCINFAON_CPU1_ADDR

Q_RES  I6   PR259  [Q_RES_0402LF -9.53K,1%,1/16W ,A]
    1  PVCCINFAON_CPU1_ADDR      A  @S9S_MB_2U_LIB.S9S_MB_2U(SCH_1):PVCCINFAON_CPU1_ADDR
    2  GND                B  @S9S_MB_2U_LIB.S9S_MB_2U(SCH_1):GND

Q_RES  I12  PR260  [Q_RES_0402LF-0,5%,1/16W,EMPTY,A]
    2  PVCCINFAON_CPU1_CSPIN      B  @S9S_MB_2U_LIB.S9S_MB_2U(SCH_1):PVCCINFAON_CPU1_CSPIN
    1  P12V_AUX           A  @S9S_MB_2U_LIB.S9S_MB_2U(SCH_1):P12V_AUX

Q_RES  I11  PR261  [Q_RES_0402LF-0,5%,1/16W,CHIP,CA]
    2  PVCCINFAON_CPU1_VIN_CSNIN      B  @S9S_MB_2U_LIB.S9S_MB_2U(SCH_1):PVCCINFAON_CPU1_VIN_CSNIN
    1  P12V_AUX           A  @S9S_MB_2U_LIB.S9S_MB_2U(SCH_1):P12V_AUX

Q_RES  I52  PR262  [Q_RES_0402LF-1K,1%,1/16W,CHIP,A]
    2  PWRGD_PVCCINFAON_CPU1_R      B  @S9S_MB_2U_LIB.S9S_MB_2U(SCH_1):PWRGD_PVCCINFAON_CPU1_R
    1  P3V3_AUX           A  @S9S_MB_2U_LIB.S9S_MB_2U(SCH_1):P3V3_AUX

Q_RES  I50  PR263  [Q_RES_0402LF-0,5%,1/16W,CHIP,CA]
    2  PWRGD_PVCCINFAON_CPU1_R      B  @S9S_MB_2U_LIB.S9S_MB_2U(SCH_1):PWRGD_PVCCINFAON_CPU1_R
    1  PWRGD_PVCCINFAON_CPU1      A  @S9S_MB_2U_LIB.S9S_MB_2U(SCH_1):PWRGD_PVCCINFAON_CPU1

Q_RES  I51  PR264  [Q_RES_0402LF-0,5%,1/16W,CHIP,CA]
    2  PVCCINFAON_CPU1_EN_R      B  @S9S_MB_2U_LIB.S9S_MB_2U(SCH_1):PVCCINFAON_CPU1_EN_R
    1  FM_PVCCINFAON_CPU1_EN      A  @S9S_MB_2U_LIB.S9S_MB_2U(SCH_1):FM_PVCCINFAON_CPU1_EN

Q_RES  I45  PR265  [Q_RES_0402LF-150,1%,1/16W,CHIPA]
    2  SVID_CLK_PVCCINFAON_CPU1_R      B  @S9S_MB_2U_LIB.S9S_MB_2U(SCH_1):SVID_CLK_PVCCINFAON_CPU1_R
    1  SVID_CLK0_CPU1_R      A  @S9S_MB_2U_LIB.S9S_MB_2U(SCH_1):SVID_CLK0_CPU1_R

Q_RES  I46  PR266  [Q_RES_0402LF-0,5%,1/16W,CHIP,CA]
    2  SVID_DIO_PVCCINFAON_CPU1_R      B  @S9S_MB_2U_LIB.S9S_MB_2U(SCH_1):SVID_DIO_PVCCINFAON_CPU1_R
    1  SVID_DIO0_CPU1_R      A  @S9S_MB_2U_LIB.S9S_MB_2U(SCH_1):SVID_DIO0_CPU1_R

Q_RES  I44  PR267  [Q_RES_0402LF-0,5%,1/16W,CHIP,CA]
    2  SVID_ALERT_PVCCINFAON_CPU1_R      B  @S9S_MB_2U_LIB.S9S_MB_2U(SCH_1):SVID_ALERT_PVCCINFAON_CPU1_R
    1  SVID_ALERT0_CPU1_R_N      A  @S9S_MB_2U_LIB.S9S_MB_2U(SCH_1):SVID_ALERT0_CPU1_R_N

Q_RES  I43  PR268  [Q_RES_0402LF-0,5%,1/16W,CHIP,CA]
    1  SMB_VR_3V3AUX_SCL_R      A  @S9S_MB_2U_LIB.S9S_MB_2U(SCH_1):SMB_VR_3V3AUX_SCL_R
    2  SMB_CLK_PVCCINFAON_CPU1      B  @S9S_MB_2U_LIB.S9S_MB_2U(SCH_1):SMB_CLK_PVCCINFAON_CPU1

Q_RES  I41  PR269  [Q_RES_0402LF-0,5%,1/16W,CHIP,CA]
    1  SMB_VR_3V3AUX_SDA_R      A  @S9S_MB_2U_LIB.S9S_MB_2U(SCH_1):SMB_VR_3V3AUX_SDA_R
    2  SMB_DIO_PVCCINFAON_CPU1      B  @S9S_MB_2U_LIB.S9S_MB_2U(SCH_1):SMB_DIO_PVCCINFAON_CPU1

Q_RES  I17  PR270  [Q_RES_0402LF-1K,1%,1/16W,CHIP,A]
    2  PWRGD_PVCCFA_EHV_CPU1_R      B  @S9S_MB_2U_LIB.S9S_MB_2U(SCH_1):PWRGD_PVCCFA_EHV_CPU1_R
    1  P3V3_AUX           A  @S9S_MB_2U_LIB.S9S_MB_2U(SCH_1):P3V3_AUX

Q_RES  I16  PR271  [Q_RES_0402LF-0,5%,1/16W,CHIP,CA]
    2  PWRGD_PVCCFA_EHV_CPU1_R      B  @S9S_MB_2U_LIB.S9S_MB_2U(SCH_1):PWRGD_PVCCFA_EHV_CPU1_R
    1  PWRGD_PVCCFA_EHV_CPU1      A  @S9S_MB_2U_LIB.S9S_MB_2U(SCH_1):PWRGD_PVCCFA_EHV_CPU1

Q_RES  I18  PR272  [Q_RES_0402LF-0,5%,1/16W,CHIP,CA]
    2  PVCCFA_EHV_CPU1_EN_R      B  @S9S_MB_2U_LIB.S9S_MB_2U(SCH_1):PVCCFA_EHV_CPU1_EN_R
    1  FM_PVCCFA_EHV_CPU1_EN      A  @S9S_MB_2U_LIB.S9S_MB_2U(SCH_1):FM_PVCCFA_EHV_CPU1_EN

Q_RES  I42  PR273  [Q_RES_0402LF-0,5%,1/16W,CHIP,CA]
    2  SH_PVCCINFAON_CPU1_R      B  @S9S_MB_2U_LIB.S9S_MB_2U(SCH_1):SH_PVCCINFAON_CPU1_R
    1  SH_PVCCINFAON_CPU1      A  @S9S_MB_2U_LIB.S9S_MB_2U(SCH_1):SH_PVCCINFAON_CPU1

Q_RES  I29  PR274  [Q_RES_0402LF-0,5%,1/16W,CHIP,CA]
    2  SH_PVCCFA_EHV_CPU1_R      B  @S9S_MB_2U_LIB.S9S_MB_2U(SCH_1):SH_PVCCFA_EHV_CPU1_R
    1  SH_PVCCFA_EHV_CPU1      A  @S9S_MB_2U_LIB.S9S_MB_2U(SCH_1):SH_PVCCFA_EHV_CPU1

Q_RES  I13  PR275  [Q_RES_0402LF-0,5%,1/16W,CHIP,CA]
    1  PVCCINFAON_CPU1_CSPIN      A  @S9S_MB_2U_LIB.S9S_MB_2U(SCH_1):PVCCINFAON_CPU1_CSPIN
    2  GND                B  @S9S_MB_2U_LIB.S9S_MB_2U(SCH_1):GND

Q_RES  I56  PR276  [Q_RES_0402LF-1K,1%,1/16W,EMPTYA]
    1  PVCCINFAON_CPU1_VIN_CSNIN      A  @S9S_MB_2U_LIB.S9S_MB_2U(SCH_1):PVCCINFAON_CPU1_VIN_CSNIN
    2  GND                B  @S9S_MB_2U_LIB.S9S_MB_2U(SCH_1):GND

Q_RES  I89  PR283  [Q_RES_0402LF-1,1%,1/16W,CHIP,CA]
    1  PVCCINFAON_CPU1_VCC      A  @S9S_MB_2U_LIB.S9S_MB_2U(SCH_1):PVCCINFAON_CPU1_VCC
    2  P3V3_AUX           B  @S9S_MB_2U_LIB.S9S_MB_2U(SCH_1):P3V3_AUX

Q_RES  I92  PR284  [Q_RES_0402LF-1K,1%,1/16W,CHIP,A]
    1  P3V3_AUX           A  @S9S_MB_2U_LIB.S9S_MB_2U(SCH_1):P3V3_AUX
    2  IRQ_CPU1_VRHOT_N      B  @S9S_MB_2U_LIB.S9S_MB_2U(SCH_1):IRQ_CPU1_VRHOT_N

Q_RES  I2   PR285  [Q_RES_0402LF-8.87K,1%,1/16W,EMA]
    1  PVCCIN_CPU1_LSET8      A  @S9S_MB_2U_LIB.S9S_MB_2U(SCH_1):PVCCIN_CPU1_LSET8
    2  GND                B  @S9S_MB_2U_LIB.S9S_MB_2U(SCH_1):GND

Q_RES  I18  PR286  [Q_RES_0402LF-8.87K,1%,1/16W,EMA]
    1  PVCCIN_CPU1_LSET7      A  @S9S_MB_2U_LIB.S9S_MB_2U(SCH_1):PVCCIN_CPU1_LSET7
    2  GND                B  @S9S_MB_2U_LIB.S9S_MB_2U(SCH_1):GND

Q_RES  I26  PR287  [Q_RES_0402LF-2.2,1%,1/16W,CHIPA]
    2  PVCCIN_CPU1_VDD8      B  @S9S_MB_2U_LIB.S9S_MB_2U(SCH_1):PVCCIN_CPU1_VDD8
    1  PVCCIN_CPU1_PVCC      A  @S9S_MB_2U_LIB.S9S_MB_2U(SCH_1):PVCCIN_CPU1_PVCC

Q_RES  I34  PR288  [Q_RES_0402LF-2.2,1%,1/16W,CHIPA]
    2  PVCCIN_CPU1_VDD7      B  @S9S_MB_2U_LIB.S9S_MB_2U(SCH_1):PVCCIN_CPU1_VDD7
    1  PVCCIN_CPU1_PVCC      A  @S9S_MB_2U_LIB.S9S_MB_2U(SCH_1):PVCCIN_CPU1_PVCC

Q_RES  I98  PR289  [Q_RES_0402LF-0,5%,1/16W,CHIP,CA]
    1  PVCCIN_CPU1_VOS8      A  @S9S_MB_2U_LIB.S9S_MB_2U(SCH_1):PVCCIN_CPU1_VOS8
    2  PVCCIN_CPU1        B  @S9S_MB_2U_LIB.S9S_MB_2U(SCH_1):PVCCIN_CPU1

Q_RES  I79  PR290  [Q_RES_0402LF-0,5%,1/16W,CHIP,CA]
    1  PVCCIN_CPU1_VOS7      A  @S9S_MB_2U_LIB.S9S_MB_2U(SCH_1):PVCCIN_CPU1_VOS7
    2  PVCCIN_CPU1        B  @S9S_MB_2U_LIB.S9S_MB_2U(SCH_1):PVCCIN_CPU1

Q_RES  I2   PR291  [Q_RES_0402LF-8.87K,1%,1/16W,EMA]
    1  PVCCIN_CPU1_LSET6      A  @S9S_MB_2U_LIB.S9S_MB_2U(SCH_1):PVCCIN_CPU1_LSET6
    2  GND                B  @S9S_MB_2U_LIB.S9S_MB_2U(SCH_1):GND

Q_RES  I13  PR292  [Q_RES_0402LF-8.87K,1%,1/16W,EMA]
    1  PVCCIN_CPU1_LSET5      A  @S9S_MB_2U_LIB.S9S_MB_2U(SCH_1):PVCCIN_CPU1_LSET5
    2  GND                B  @S9S_MB_2U_LIB.S9S_MB_2U(SCH_1):GND

Q_RES  I10  PR293  [Q_RES_0402LF-2.2,1%,1/16W,CHIPA]
    2  PVCCIN_CPU1_VDD6      B  @S9S_MB_2U_LIB.S9S_MB_2U(SCH_1):PVCCIN_CPU1_VDD6
    1  PVCCIN_CPU1_PVCC      A  @S9S_MB_2U_LIB.S9S_MB_2U(SCH_1):PVCCIN_CPU1_PVCC

Q_RES  I21  PR294  [Q_RES_0402LF-2.2,1%,1/16W,CHIPA]
    2  PVCCIN_CPU1_VDD5      B  @S9S_MB_2U_LIB.S9S_MB_2U(SCH_1):PVCCIN_CPU1_VDD5
    1  PVCCIN_CPU1_PVCC      A  @S9S_MB_2U_LIB.S9S_MB_2U(SCH_1):PVCCIN_CPU1_PVCC

Q_RES  I96  PR295  [Q_RES_0402LF-0,5%,1/16W,CHIP,CA]
    1  PVCCIN_CPU1_VOS6      A  @S9S_MB_2U_LIB.S9S_MB_2U(SCH_1):PVCCIN_CPU1_VOS6
    2  PVCCIN_CPU1        B  @S9S_MB_2U_LIB.S9S_MB_2U(SCH_1):PVCCIN_CPU1

Q_RES  I80  PR296  [Q_RES_0402LF-0,5%,1/16W,CHIP,CA]
    1  PVCCIN_CPU1_VOS5      A  @S9S_MB_2U_LIB.S9S_MB_2U(SCH_1):PVCCIN_CPU1_VOS5
    2  PVCCIN_CPU1        B  @S9S_MB_2U_LIB.S9S_MB_2U(SCH_1):PVCCIN_CPU1

Q_RES  I2   PR297  [Q_RES_0402LF-8.87K,1%,1/16W,EMA]
    1  PVCCIN_CPU1_LSET4      A  @S9S_MB_2U_LIB.S9S_MB_2U(SCH_1):PVCCIN_CPU1_LSET4
    2  GND                B  @S9S_MB_2U_LIB.S9S_MB_2U(SCH_1):GND

Q_RES  I20  PR298  [Q_RES_0402LF-8.87K,1%,1/16W,EMA]
    1  PVCCIN_CPU1_LSET3      A  @S9S_MB_2U_LIB.S9S_MB_2U(SCH_1):PVCCIN_CPU1_LSET3
    2  GND                B  @S9S_MB_2U_LIB.S9S_MB_2U(SCH_1):GND

Q_RES  I12  PR299  [Q_RES_0402LF-2.2,1%,1/16W,CHIPA]
    2  PVCCIN_CPU1_VDD4      B  @S9S_MB_2U_LIB.S9S_MB_2U(SCH_1):PVCCIN_CPU1_VDD4
    1  PVCCIN_CPU1_PVCC      A  @S9S_MB_2U_LIB.S9S_MB_2U(SCH_1):PVCCIN_CPU1_PVCC

Q_RES  I27  PR300  [Q_RES_0402LF-2.2,1%,1/16W,CHIPA]
    2  PVCCIN_CPU1_VDD3      B  @S9S_MB_2U_LIB.S9S_MB_2U(SCH_1):PVCCIN_CPU1_VDD3
    1  PVCCIN_CPU1_PVCC      A  @S9S_MB_2U_LIB.S9S_MB_2U(SCH_1):PVCCIN_CPU1_PVCC

Q_RES  I92  PR301  [Q_RES_0402LF-0,5%,1/16W,CHIP,CA]
    1  PVCCIN_CPU1_VOS4      A  @S9S_MB_2U_LIB.S9S_MB_2U(SCH_1):PVCCIN_CPU1_VOS4
    2  PVCCIN_CPU1        B  @S9S_MB_2U_LIB.S9S_MB_2U(SCH_1):PVCCIN_CPU1

Q_RES  I80  PR302  [Q_RES_0402LF-0,5%,1/16W,CHIP,CA]
    1  PVCCIN_CPU1_VOS3      A  @S9S_MB_2U_LIB.S9S_MB_2U(SCH_1):PVCCIN_CPU1_VOS3
    2  PVCCIN_CPU1        B  @S9S_MB_2U_LIB.S9S_MB_2U(SCH_1):PVCCIN_CPU1

Q_RES  I166  PR303  [Q_RES_0402LF-0,5%,1/16W,CHIP,CA]
    2  PVCCIN_CPU1_VIN_CSNIN      B  @S9S_MB_2U_LIB.S9S_MB_2U(SCH_1):PVCCIN_CPU1_VIN_CSNIN
    1  P12V_AUX           A  @S9S_MB_2U_LIB.S9S_MB_2U(SCH_1):P12V_AUX

Q_RES  I167  PR304  [Q_RES_0402LF-0,5%,1/16W,EMPTY,A]
    2  PVCCIN_CPU1_CSPIN      B  @S9S_MB_2U_LIB.S9S_MB_2U(SCH_1):PVCCIN_CPU1_CSPIN
    1  P12V_AUX           A  @S9S_MB_2U_LIB.S9S_MB_2U(SCH_1):P12V_AUX

Q_RES  I199  PR305  [Q_RES_0402LF-0,5%,1/16W,CHIP,CA]
    1  PVCCIN_CPU1_CSPIN      A  @S9S_MB_2U_LIB.S9S_MB_2U(SCH_1):PVCCIN_CPU1_CSPIN
    2  GND                B  @S9S_MB_2U_LIB.S9S_MB_2U(SCH_1):GND

Q_RES  I161  PR306  [Q_RES_0402LF-28K,1%,1/16W,EMPTA]
    1  PVCCIN_CPU1_VREF      A  @S9S_MB_2U_LIB.S9S_MB_2U(SCH_1):PVCCIN_CPU1_VREF
    2  PVCCIN_CPU1_ADDR      B  @S9S_MB_2U_LIB.S9S_MB_2U(SCH_1):PVCCIN_CPU1_ADDR

Q_RES  I198  PR307  [Q_RES_0402LF-1K,1%,1/16W,CHIP,A]
    2  PWRGD_PVCCIN_CPU1_R      B  @S9S_MB_2U_LIB.S9S_MB_2U(SCH_1):PWRGD_PVCCIN_CPU1_R
    1  P3V3_AUX           A  @S9S_MB_2U_LIB.S9S_MB_2U(SCH_1):P3V3_AUX

Q_RES  I197  PR308  [Q_RES_0402LF-0,5%,1/16W,CHIP,CA]
    2  PWRGD_PVCCIN_CPU1_R      B  @S9S_MB_2U_LIB.S9S_MB_2U(SCH_1):PWRGD_PVCCIN_CPU1_R
    1  PWRGD_PVCCIN_CPU1      A  @S9S_MB_2U_LIB.S9S_MB_2U(SCH_1):PWRGD_PVCCIN_CPU1

Q_RES  I196  PR309  [Q_RES_0402LF-0,5%,1/16W,CHIP,CA]
    2  PVCCIN_CPU1_EN_R      B  @S9S_MB_2U_LIB.S9S_MB_2U(SCH_1):PVCCIN_CPU1_EN_R
    1  FM_PVCCIN_CPU1_EN      A  @S9S_MB_2U_LIB.S9S_MB_2U(SCH_1):FM_PVCCIN_CPU1_EN

Q_RES  I192  PR310  [Q_RES_0402LF-150,1%,1/16W,CHIPA]
    2  SVID_CLK_PVCCIN_CPU1_R      B  @S9S_MB_2U_LIB.S9S_MB_2U(SCH_1):SVID_CLK_PVCCIN_CPU1_R
    1  SVID_CLK0_CPU1_R      A  @S9S_MB_2U_LIB.S9S_MB_2U(SCH_1):SVID_CLK0_CPU1_R

Q_RES  I191  PR311  [Q_RES_0402LF-0,5%,1/16W,CHIP,CA]
    2  SVID_DIO_PVCCIN_CPU1_R      B  @S9S_MB_2U_LIB.S9S_MB_2U(SCH_1):SVID_DIO_PVCCIN_CPU1_R
    1  SVID_DIO0_CPU1_R      A  @S9S_MB_2U_LIB.S9S_MB_2U(SCH_1):SVID_DIO0_CPU1_R

Q_RES  I190  PR312  [Q_RES_0402LF-0,5%,1/16W,CHIP,CA]
    2  SVID_ALERT_PVCCIN_CPU1_R      B  @S9S_MB_2U_LIB.S9S_MB_2U(SCH_1):SVID_ALERT_PVCCIN_CPU1_R
    1  SVID_ALERT0_CPU1_R_N      A  @S9S_MB_2U_LIB.S9S_MB_2U(SCH_1):SVID_ALERT0_CPU1_R_N

Q_RES  I208  PR313  [Q_RES_0402LF-1K,1%,1/16W,EMPTYA]
    1  PVCCIN_CPU1_VIN_CSNIN      A  @S9S_MB_2U_LIB.S9S_MB_2U(SCH_1):PVCCIN_CPU1_VIN_CSNIN
    2  GND                B  @S9S_MB_2U_LIB.S9S_MB_2U(SCH_1):GND

Q_RES  I241  PR314  [Q_RES_0402LF-0,5%,1/16W,CHIP,CA]
    1  SMB_VR_3V3AUX_SCL_R      A  @S9S_MB_2U_LIB.S9S_MB_2U(SCH_1):SMB_VR_3V3AUX_SCL_R
    2  SMB_CLK_PVCCIN_CPU1      B  @S9S_MB_2U_LIB.S9S_MB_2U(SCH_1):SMB_CLK_PVCCIN_CPU1

Q_RES  I239  PR315  [Q_RES_0402LF-0,5%,1/16W,CHIP,CA]
    1  SMB_VR_3V3AUX_SDA_R      A  @S9S_MB_2U_LIB.S9S_MB_2U(SCH_1):SMB_VR_3V3AUX_SDA_R
    2  SMB_DIO_PVCCIN_CPU1      B  @S9S_MB_2U_LIB.S9S_MB_2U(SCH_1):SMB_DIO_PVCCIN_CPU1

Q_RES  I238  PR317  [Q_RES_0402LF-0,5%,1/16W,CHIP,CA]
    2  SH_PVCCIN_CPU1_R      B  @S9S_MB_2U_LIB.S9S_MB_2U(SCH_1):SH_PVCCIN_CPU1_R
    1  SH_PVCCIN_CPU1      A  @S9S_MB_2U_LIB.S9S_MB_2U(SCH_1):SH_PVCCIN_CPU1

Q_RES  I165  PR318  [Q_RES_0402LF-5.23K,1%,1/16W,CHA]
    1  PVCCIN_CPU1_ADDR      A  @S9S_MB_2U_LIB.S9S_MB_2U(SCH_1):PVCCIN_CPU1_ADDR
    2  GND                B  @S9S_MB_2U_LIB.S9S_MB_2U(SCH_1):GND

Q_RES  I278  PR323  [Q_RES_0402LF-1,1%,1/16W,CHIP,CA]
    1  PVCCIN_CPU1_VCC      A  @S9S_MB_2U_LIB.S9S_MB_2U(SCH_1):PVCCIN_CPU1_VCC
    2  P3V3_AUX           B  @S9S_MB_2U_LIB.S9S_MB_2U(SCH_1):P3V3_AUX

Q_RES  I2   PR325  [Q_RES_0402LF-8.87K,1%,1/16W,EMA]
    1  PVCCIN_CPU1_LSET2      A  @S9S_MB_2U_LIB.S9S_MB_2U(SCH_1):PVCCIN_CPU1_LSET2
    2  GND                B  @S9S_MB_2U_LIB.S9S_MB_2U(SCH_1):GND

Q_RES  I12  PR326  [Q_RES_0402LF-8.87K,1%,1/16W,EMA]
    1  PVCCIN_CPU1_LSET1      A  @S9S_MB_2U_LIB.S9S_MB_2U(SCH_1):PVCCIN_CPU1_LSET1
    2  GND                B  @S9S_MB_2U_LIB.S9S_MB_2U(SCH_1):GND

Q_RES  I13  PR327  [Q_RES_0402LF-2.2,1%,1/16W,CHIPA]
    2  PVCCIN_CPU1_VDD2      B  @S9S_MB_2U_LIB.S9S_MB_2U(SCH_1):PVCCIN_CPU1_VDD2
    1  PVCCIN_CPU1_PVCC      A  @S9S_MB_2U_LIB.S9S_MB_2U(SCH_1):PVCCIN_CPU1_PVCC

Q_RES  I31  PR328  [Q_RES_0402LF-2.2,1%,1/16W,CHIPA]
    2  PVCCIN_CPU1_VDD1      B  @S9S_MB_2U_LIB.S9S_MB_2U(SCH_1):PVCCIN_CPU1_VDD1
    1  PVCCIN_CPU1_PVCC      A  @S9S_MB_2U_LIB.S9S_MB_2U(SCH_1):PVCCIN_CPU1_PVCC

Q_RES  I102  PR329  [Q_RES_0402LF-0,5%,1/16W,CHIP,CA]
    1  PVCCIN_CPU1_VOS2      A  @S9S_MB_2U_LIB.S9S_MB_2U(SCH_1):PVCCIN_CPU1_VOS2
    2  PVCCIN_CPU1        B  @S9S_MB_2U_LIB.S9S_MB_2U(SCH_1):PVCCIN_CPU1

Q_RES  I90  PR330  [Q_RES_0402LF-0,5%,1/16W,CHIP,CA]
    1  PVCCIN_CPU1_VOS1      A  @S9S_MB_2U_LIB.S9S_MB_2U(SCH_1):PVCCIN_CPU1_VOS1
    2  PVCCIN_CPU1        B  @S9S_MB_2U_LIB.S9S_MB_2U(SCH_1):PVCCIN_CPU1

Q_RES  I40  PR335  [Q_RES_0402LF-1K,1%,1/16W,CHIP,A]
    2  PWRGD_PVCCFA_EHV_FIVRA_CPU0_R      B  @S9S_MB_2U_LIB.S9S_MB_2U(SCH_1):PWRGD_PVCCFA_EHV_FIVRA_CPU0_R
    1  P3V3_AUX           A  @S9S_MB_2U_LIB.S9S_MB_2U(SCH_1):P3V3_AUX

Q_RES  I39  PR336  [Q_RES_0402LF-0,5%,1/16W,CHIP,CA]
    2  PWRGD_PVCCFA_EHV_FIVRA_CPU0_R      B  @S9S_MB_2U_LIB.S9S_MB_2U(SCH_1):PWRGD_PVCCFA_EHV_FIVRA_CPU0_R
    1  PWRGD_PVCCFA_EHV_FIVRA_CPU0      A  @S9S_MB_2U_LIB.S9S_MB_2U(SCH_1):PWRGD_PVCCFA_EHV_FIVRA_CPU0

Q_RES  I41  PR337  [Q_RES_0402LF-0,5%,1/16W,CHIP,CA]
    2  PVCCFA_EHV_FIVRA_CPU0_EN_R      B  @S9S_MB_2U_LIB.S9S_MB_2U(SCH_1):PVCCFA_EHV_FIVRA_CPU0_EN_R
    1  FM_PVCCFA_EHV_FIVRA_CPU0_EN      A  @S9S_MB_2U_LIB.S9S_MB_2U(SCH_1):FM_PVCCFA_EHV_FIVRA_CPU0_EN

Q_RES  I57  PR345  [Q_RES_0402LF-0,5%,1/16W,CHIP,CA]
    2  SH_PVCCFA_EHV_FIVRA_CPU0_R      B  @S9S_MB_2U_LIB.S9S_MB_2U(SCH_1):SH_PVCCFA_EHV_FIVRA_CPU0_R
    1  SH_PVCCFA_EHV_FIVRA_CPU0      A  @S9S_MB_2U_LIB.S9S_MB_2U(SCH_1):SH_PVCCFA_EHV_FIVRA_CPU0

Q_RES  I2   PR353  [Q_RES_0402LF-8.87K,1%,1/16W,EMA]
    1  PVCCFA_EHV_FIVRA_CPU0_LSET2      A  @S9S_MB_2U_LIB.S9S_MB_2U(SCH_1):PVCCFA_EHV_FIVRA_CPU0_LSET2
    2  GND                B  @S9S_MB_2U_LIB.S9S_MB_2U(SCH_1):GND

Q_RES  I17  PR354  [Q_RES_0402LF-8.87K,1%,1/16W,EMA]
    1  PVCCFA_EHV_FIVRA_CPU0_LSET1      A  @S9S_MB_2U_LIB.S9S_MB_2U(SCH_1):PVCCFA_EHV_FIVRA_CPU0_LSET1
    2  GND                B  @S9S_MB_2U_LIB.S9S_MB_2U(SCH_1):GND

Q_RES  I25  PR355  [Q_RES_0402LF-2.2,1%,1/16W,CHIPA]
    2  PVCCFA_EHV_FIVRA_CPU0_VDD1      B  @S9S_MB_2U_LIB.S9S_MB_2U(SCH_1):PVCCFA_EHV_FIVRA_CPU0_VDD1
    1  PVCCFA_EHV_FIVRA_CPU0_PVCC1      A  @S9S_MB_2U_LIB.S9S_MB_2U(SCH_1):PVCCFA_EHV_FIVRA_CPU0_PVCC1

Q_RES  I10  PR356  [Q_RES_0402LF-2.2,1%,1/16W,CHIPA]
    2  PVCCFA_EHV_FIVRA_CPU0_VDD2      B  @S9S_MB_2U_LIB.S9S_MB_2U(SCH_1):PVCCFA_EHV_FIVRA_CPU0_VDD2
    1  PVCCFA_EHV_FIVRA_CPU0_PVCC2      A  @S9S_MB_2U_LIB.S9S_MB_2U(SCH_1):PVCCFA_EHV_FIVRA_CPU0_PVCC2

Q_RES  I7   PR357  [Q_RES_0402LF-28K,1%,1/16W,EMPTA]
    1  PVCCD_HV_CPU0_VREF      A  @S9S_MB_2U_LIB.S9S_MB_2U(SCH_1):PVCCD_HV_CPU0_VREF
    2  PVCCD_HV_CPU0_ADDR      B  @S9S_MB_2U_LIB.S9S_MB_2U(SCH_1):PVCCD_HV_CPU0_ADDR

Q_RES  I6   PR358  [Q_RES_0402LF-4.64K,0.5%,1/16W,A]
    2  PVCCD_HV_CPU0_ADDR      B  @S9S_MB_2U_LIB.S9S_MB_2U(SCH_1):PVCCD_HV_CPU0_ADDR
    1  GND                A  @S9S_MB_2U_LIB.S9S_MB_2U(SCH_1):GND

Q_RES  I43  PR361  [Q_RES_0402LF-1K,1%,1/16W,CHIP,A]
    2  PWRGD_PVCCD_HV_CPU0_R      B  @S9S_MB_2U_LIB.S9S_MB_2U(SCH_1):PWRGD_PVCCD_HV_CPU0_R
    1  P3V3_AUX           A  @S9S_MB_2U_LIB.S9S_MB_2U(SCH_1):P3V3_AUX

Q_RES  I44  PR362  [Q_RES_0402LF-0,5%,1/16W,CHIP,CA]
    2  PWRGD_PVCCD_HV_CPU0_R      B  @S9S_MB_2U_LIB.S9S_MB_2U(SCH_1):PWRGD_PVCCD_HV_CPU0_R
    1  PWRGD_PVCCD_HV_CPU0      A  @S9S_MB_2U_LIB.S9S_MB_2U(SCH_1):PWRGD_PVCCD_HV_CPU0

Q_RES  I40  PR363  [Q_RES_0402LF-0,5%,1/16W,CHIP,CA]
    2  PVCCD_HV_CPU0_EN_R      B  @S9S_MB_2U_LIB.S9S_MB_2U(SCH_1):PVCCD_HV_CPU0_EN_R
    1  FM_PVCCD_HV_CPU0_EN      A  @S9S_MB_2U_LIB.S9S_MB_2U(SCH_1):FM_PVCCD_HV_CPU0_EN

Q_RES  I39  PR364  [Q_RES_0402LF-150,1%,1/16W,CHIPA]
    2  SVID_CLK_PVCCD_HV_CPU0_R      B  @S9S_MB_2U_LIB.S9S_MB_2U(SCH_1):SVID_CLK_PVCCD_HV_CPU0_R
    1  SVID_CLK1_CPU0_R      A  @S9S_MB_2U_LIB.S9S_MB_2U(SCH_1):SVID_CLK1_CPU0_R

Q_RES  I37  PR365  [Q_RES_0402LF-0,5%,1/16W,CHIP,CA]
    2  SVID_DIO_PVCCD_HV_CPU0_R      B  @S9S_MB_2U_LIB.S9S_MB_2U(SCH_1):SVID_DIO_PVCCD_HV_CPU0_R
    1  SVID_DIO1_CPU0_R      A  @S9S_MB_2U_LIB.S9S_MB_2U(SCH_1):SVID_DIO1_CPU0_R

Q_RES  I38  PR366  [Q_RES_0402LF-0,5%,1/16W,CHIP,CA]
    2  SVID_ALERT_PVCCD_HV_CPU0_R      B  @S9S_MB_2U_LIB.S9S_MB_2U(SCH_1):SVID_ALERT_PVCCD_HV_CPU0_R
    1  SVID_ALERT1_CPU0_R_N      A  @S9S_MB_2U_LIB.S9S_MB_2U(SCH_1):SVID_ALERT1_CPU0_R_N

Q_RES  I35  PR367  [Q_RES_0402LF-0,5%,1/16W,CHIP,CA]
    1  SMB_VR_3V3AUX_SCL_R      A  @S9S_MB_2U_LIB.S9S_MB_2U(SCH_1):SMB_VR_3V3AUX_SCL_R
    2  SMB_CLK_PVCCD_HV_CPU0      B  @S9S_MB_2U_LIB.S9S_MB_2U(SCH_1):SMB_CLK_PVCCD_HV_CPU0

Q_RES  I36  PR368  [Q_RES_0402LF-0,5%,1/16W,CHIP,CA]
    1  SMB_VR_3V3AUX_SDA_R      A  @S9S_MB_2U_LIB.S9S_MB_2U(SCH_1):SMB_VR_3V3AUX_SDA_R
    2  SMB_DIO_PVCCD_HV_CPU0      B  @S9S_MB_2U_LIB.S9S_MB_2U(SCH_1):SMB_DIO_PVCCD_HV_CPU0

Q_RES  I12  PR369  [Q_RES_0402LF-1K,1%,1/16W,EMPTYA]
    1  PVCCD_HV_CPU0_ISENSE_P      A  @S9S_MB_2U_LIB.S9S_MB_2U(SCH_1):PVCCD_HV_CPU0_ISENSE_P
    2  GND                B  @S9S_MB_2U_LIB.S9S_MB_2U(SCH_1):GND

Q_RES  I15  PR370  [Q_RES_0402LF-1K,1%,1/16W,CHIP,A]
    2  PVCCD_HV_CPU0_PIN_ALT      B  @S9S_MB_2U_LIB.S9S_MB_2U(SCH_1):PVCCD_HV_CPU0_PIN_ALT
    1  P3V3_AUX           A  @S9S_MB_2U_LIB.S9S_MB_2U(SCH_1):P3V3_AUX

Q_RES  I41  PR371  [Q_RES_0402LF-0,5%,1/16W,CHIP,CA]
    2  SH_PVCCD_HV_CPU0_R      B  @S9S_MB_2U_LIB.S9S_MB_2U(SCH_1):SH_PVCCD_HV_CPU0_R
    1  SH_PVCCD_HV_CPU0      A  @S9S_MB_2U_LIB.S9S_MB_2U(SCH_1):SH_PVCCD_HV_CPU0

Q_RES  I17  PR372  [Q_RES_0402LF-1K,1%,1/16W,CHIP,A]
    2  PVCCD_HV_CPU0_FAULT      B  @S9S_MB_2U_LIB.S9S_MB_2U(SCH_1):PVCCD_HV_CPU0_FAULT
    1  P3V3_AUX           A  @S9S_MB_2U_LIB.S9S_MB_2U(SCH_1):P3V3_AUX

Q_RES  I46  PR373  [Q_RES_0402LF-1K,1%,1/16W,EMPTYA]
    1  PVCCD_HV_CPU0_ISENSE_N      A  @S9S_MB_2U_LIB.S9S_MB_2U(SCH_1):PVCCD_HV_CPU0_ISENSE_N
    2  GND                B  @S9S_MB_2U_LIB.S9S_MB_2U(SCH_1):GND

Q_RES  I72  PR375  [Q_RES_0402LF-1,1%,1/16W,CHIP,CA]
    1  PVCCD_HV_CPU0_VCC      A  @S9S_MB_2U_LIB.S9S_MB_2U(SCH_1):PVCCD_HV_CPU0_VCC
    2  P3V3_AUX           B  @S9S_MB_2U_LIB.S9S_MB_2U(SCH_1):P3V3_AUX

Q_RES  I60  PR378  [Q_RES_0402LF-1K,1%,1/16W,CHIP,A]
    1  P3V3_AUX           A  @S9S_MB_2U_LIB.S9S_MB_2U(SCH_1):P3V3_AUX
    2  IRQ_PVCCD_CPU0_VRHOT_LVC3_N      B  @S9S_MB_2U_LIB.S9S_MB_2U(SCH_1):IRQ_PVCCD_CPU0_VRHOT_LVC3_N

Q_RES  I336  PR380  [Q_RES_0402LF-2.2,1%,1/16W,CHIPA]
    2  PVCCD_HV_CPU0_VDD1      B  @S9S_MB_2U_LIB.S9S_MB_2U(SCH_1):PVCCD_HV_CPU0_VDD1
    1  PVCCD_HV_CPU0_PVCC      A  @S9S_MB_2U_LIB.S9S_MB_2U(SCH_1):PVCCD_HV_CPU0_PVCC

Q_RES  I16  PR389  [Q_RES_0402LF-1,1%,1/16W,CHIP,CA]
    1  P5V_AUX            A  @S9S_MB_2U_LIB.S9S_MB_2U(SCH_1):P5V_AUX
    2  P3V3_AUX_VCC       B  @S9S_MB_2U_LIB.S9S_MB_2U(SCH_1):P3V3_AUX_VCC

Q_RES  I10  PR395  [Q_RES_0402LF-0,5%,1/16W,CHIP,CA]
    2  PVCC1_AUX          B  @S9S_MB_2U_LIB.S9S_MB_2U(SCH_1):PVCC1_AUX
    1  P3V3_AUX           A  @S9S_MB_2U_LIB.S9S_MB_2U(SCH_1):P3V3_AUX

Q_RES  I2   PR396  [Q_RES_0402LF-0,5%,1/16W,EMPTY,A]
    2  PVCC1_AUX          B  @S9S_MB_2U_LIB.S9S_MB_2U(SCH_1):PVCC1_AUX
    1  P5V_AUX            A  @S9S_MB_2U_LIB.S9S_MB_2U(SCH_1):P5V_AUX

Q_RES  I77  PR400  [Q_RES_0402LF-10K,1%,1/16W,EMPTB]
    1  PVCCIN_CPU0_ATSEN      A  @S9S_MB_2U_LIB.S9S_MB_2U(SCH_1):PVCCIN_CPU0_ATSEN
    2  GND                B  @S9S_MB_2U_LIB.S9S_MB_2U(SCH_1):GND

Q_RES  I31  PR402  [Q_RES_0402LF-0,5%,1/16W,CHIP,CA]
    2  PVCCIN_CPU0_PVCC      B  @S9S_MB_2U_LIB.S9S_MB_2U(SCH_1):PVCCIN_CPU0_PVCC
    1  P5V                A  @S9S_MB_2U_LIB.S9S_MB_2U(SCH_1):P5V

Q_RES  I36  PR403  [Q_RES_0402LF-0,5%,1/16W,EMPTY,A]
    2  PVCCIN_CPU0_PVCC      B  @S9S_MB_2U_LIB.S9S_MB_2U(SCH_1):PVCCIN_CPU0_PVCC
    1  P3V3               A  @S9S_MB_2U_LIB.S9S_MB_2U(SCH_1):P3V3

Q_RES  I59  PR409  [Q_RES_0402LF-0,5%,1/16W,EMPTY,A]
    1  PVCCD_HV_CPU0_ISYS_R      A  @S9S_MB_2U_LIB.S9S_MB_2U(SCH_1):PVCCD_HV_CPU0_ISYS_R
    2  NC                 B  NC

Q_RES  I260  PR410  [Q_RES_0402LF-0,5%,1/16W,EMPTY,A]
    1  PVCCD_HV_CPU1_ISYS_R      A  @S9S_MB_2U_LIB.S9S_MB_2U(SCH_1):PVCCD_HV_CPU1_ISYS_R
    2  NC                 B  NC

Q_RES  I16  PR411  [Q_RES_0402LF-0,5%,1/16W,CHIP,CA]
    2  FM_PCH_P1V8_AUX_EN_R      B  @S9S_MB_2U_LIB.S9S_MB_2U(SCH_1):FM_PCH_P1V8_AUX_EN_R
    1  FM_PCH_P1V8_AUX_EN      A  @S9S_MB_2U_LIB.S9S_MB_2U(SCH_1):FM_PCH_P1V8_AUX_EN

Q_RES  I15  PR412  [Q_RES_0402LF-0,5%,1/16W,EMPTY,A]
    1  NC                 A  NC
    2  FM_PCH_P1V8_AUX_EN_R      B  @S9S_MB_2U_LIB.S9S_MB_2U(SCH_1):FM_PCH_P1V8_AUX_EN_R

Q_RES  I73  PR435  [Q_RES_0402LF-10K,1%,1/16W,EMPTB]
    1  PVCCINFAON_CPU0_ATSEN      A  @S9S_MB_2U_LIB.S9S_MB_2U(SCH_1):PVCCINFAON_CPU0_ATSEN
    2  GND                B  @S9S_MB_2U_LIB.S9S_MB_2U(SCH_1):GND

Q_RES  I79  PR436  [Q_RES_0402LF-10K,1%,1/16W,EMPTB]
    1  PVCCFA_EHV_CPU0_BTSEN      A  @S9S_MB_2U_LIB.S9S_MB_2U(SCH_1):PVCCFA_EHV_CPU0_BTSEN
    2  GND                B  @S9S_MB_2U_LIB.S9S_MB_2U(SCH_1):GND

Q_RES  I170  PR437  [Q_RES_0402LF-0,5%,1/16W,CHIP,CA]
    2  PVCCINFAON_CPU0_PVCC      B  @S9S_MB_2U_LIB.S9S_MB_2U(SCH_1):PVCCINFAON_CPU0_PVCC
    1  P5V                A  @S9S_MB_2U_LIB.S9S_MB_2U(SCH_1):P5V

Q_RES  I176  PR441  [Q_RES_0402LF-0,5%,1/16W,EMPTY,A]
    2  PVCCINFAON_CPU0_PVCC      B  @S9S_MB_2U_LIB.S9S_MB_2U(SCH_1):PVCCINFAON_CPU0_PVCC
    1  P3V3               A  @S9S_MB_2U_LIB.S9S_MB_2U(SCH_1):P3V3

Q_RES  I13  PR442  [Q_RES_0402LF-0,5%,1/16W,CHIP,CA]
    2  PVCCFA_EHV_CPU0_PVCC      B  @S9S_MB_2U_LIB.S9S_MB_2U(SCH_1):PVCCFA_EHV_CPU0_PVCC
    1  P5V                A  @S9S_MB_2U_LIB.S9S_MB_2U(SCH_1):P5V

Q_RES  I15  PR443  [Q_RES_0402LF-0,5%,1/16W,EMPTY,A]
    2  PVCCFA_EHV_CPU0_PVCC      B  @S9S_MB_2U_LIB.S9S_MB_2U(SCH_1):PVCCFA_EHV_CPU0_PVCC
    1  P3V3               A  @S9S_MB_2U_LIB.S9S_MB_2U(SCH_1):P3V3

Q_RES  I24  PR444  [Q_RES_0402LF-0,5%,1/16W,CHIP,CA]
    2  PVCCFA_EHV_FIVRA_CPU0_PVCC1      B  @S9S_MB_2U_LIB.S9S_MB_2U(SCH_1):PVCCFA_EHV_FIVRA_CPU0_PVCC1
    1  P5V                A  @S9S_MB_2U_LIB.S9S_MB_2U(SCH_1):P5V

Q_RES  I11  PR447  [Q_RES_0402LF-0,5%,1/16W,CHIP,CA]
    2  PVCCFA_EHV_FIVRA_CPU0_PVCC2      B  @S9S_MB_2U_LIB.S9S_MB_2U(SCH_1):PVCCFA_EHV_FIVRA_CPU0_PVCC2
    1  P5V                A  @S9S_MB_2U_LIB.S9S_MB_2U(SCH_1):P5V

Q_RES  I82  PR450  [Q_RES_0402LF-0,5%,1/16W,EMPTY,A]
    2  NC                 B  NC
    1  PVCCIN_CPU0_ISYS_R      A  @S9S_MB_2U_LIB.S9S_MB_2U(SCH_1):PVCCIN_CPU0_ISYS_R

Q_RES  I81  PR451  [Q_RES_0402LF-0,5%,1/16W,CHIP,CA]
    1  PVCCIN_CPU0_ISYS_R      A  @S9S_MB_2U_LIB.S9S_MB_2U(SCH_1):PVCCIN_CPU0_ISYS_R
    2  GND                B  @S9S_MB_2U_LIB.S9S_MB_2U(SCH_1):GND

Q_RES  I263  PR452  [Q_RES_0402LF-0,5%,1/16W,EMPTY,A]
    2  NC                 B  NC
    1  PVCCIN_CPU1_ISYS_R      A  @S9S_MB_2U_LIB.S9S_MB_2U(SCH_1):PVCCIN_CPU1_ISYS_R

Q_RES  I262  PR453  [Q_RES_0402LF-0,5%,1/16W,CHIP,CA]
    1  PVCCIN_CPU1_ISYS_R      A  @S9S_MB_2U_LIB.S9S_MB_2U(SCH_1):PVCCIN_CPU1_ISYS_R
    2  GND                B  @S9S_MB_2U_LIB.S9S_MB_2U(SCH_1):GND

Q_RES  I182  PR501  [Q_RES_0402LF-8.25K,1%,1/16W,CHA]
    1  PVNN_MAIN_CPU0_FB_RC      A  @S9S_MB_2U_LIB.S9S_MB_2U(SCH_1):PVNN_MAIN_CPU0_FB_RC
    2  PVNN_MAIN_CPU0      B  @S9S_MB_2U_LIB.S9S_MB_2U(SCH_1):PVNN_MAIN_CPU0

Q_RES  I190  PR502  [Q_RES_0402LF-8.25K,1%,1/16W,CHA]
    1  PVNN_MAIN_CPU1_FB_RC      A  @S9S_MB_2U_LIB.S9S_MB_2U(SCH_1):PVNN_MAIN_CPU1_FB_RC
    2  PVNN_MAIN_CPU1      B  @S9S_MB_2U_LIB.S9S_MB_2U(SCH_1):PVNN_MAIN_CPU1

Q_RES  I11  PR519  [Q_RES_0402LF-100,1%,1/16W,CHIPA]
    1  VSENSE_PVCCINFAON_CPU0_DN      A  @S9S_MB_2U_LIB.S9S_MB_2U(SCH_1):VSENSE_PVCCINFAON_CPU0_DN
    2  GND                B  @S9S_MB_2U_LIB.S9S_MB_2U(SCH_1):GND

Q_RES  I8   PR520  [Q_RES_0402LF-100,1%,1/16W,CHIPA]
    1  VSENSE_PVCCFA_EHV_CPU0_DN      A  @S9S_MB_2U_LIB.S9S_MB_2U(SCH_1):VSENSE_PVCCFA_EHV_CPU0_DN
    2  GND                B  @S9S_MB_2U_LIB.S9S_MB_2U(SCH_1):GND

Q_RES  I16  PR521  [Q_RES_0402LF-100,1%,1/16W,CHIPA]
    1  VSENSE_PVCCINFAON_CPU0_DP      A  @S9S_MB_2U_LIB.S9S_MB_2U(SCH_1):VSENSE_PVCCINFAON_CPU0_DP
    2  PVCCINFAON_CPU0      B  @S9S_MB_2U_LIB.S9S_MB_2U(SCH_1):PVCCINFAON_CPU0

Q_RES  I10  PR522  [Q_RES_0402LF-100,1%,1/16W,CHIPA]
    1  VSENSE_PVCCFA_EHV_CPU0_DP      A  @S9S_MB_2U_LIB.S9S_MB_2U(SCH_1):VSENSE_PVCCFA_EHV_CPU0_DP
    2  PVCCFA_EHV_CPU0      B  @S9S_MB_2U_LIB.S9S_MB_2U(SCH_1):PVCCFA_EHV_CPU0

Q_RES  I41  PR523  [Q_RES_0402LF-1K,1%,1/16W,CHIP,A]
    2  PVCCINFAON_CPU0_VR_FAULT      B  @S9S_MB_2U_LIB.S9S_MB_2U(SCH_1):PVCCINFAON_CPU0_VR_FAULT
    1  P3V3_AUX           A  @S9S_MB_2U_LIB.S9S_MB_2U(SCH_1):P3V3_AUX

Q_RES  I42  PR524  [Q_RES_0402LF-1K,1%,1/16W,CHIP,A]
    2  PVCCINFAON_CPU0_PIN_ALERT      B  @S9S_MB_2U_LIB.S9S_MB_2U(SCH_1):PVCCINFAON_CPU0_PIN_ALERT
    1  P3V3_AUX           A  @S9S_MB_2U_LIB.S9S_MB_2U(SCH_1):P3V3_AUX

Q_RES  I21  PR527  [Q_RES_0402LF-100,1%,1/16W,CHIPA]
    1  VSENSE_PVCCIN_CPU0_DN      A  @S9S_MB_2U_LIB.S9S_MB_2U(SCH_1):VSENSE_PVCCIN_CPU0_DN
    2  GND                B  @S9S_MB_2U_LIB.S9S_MB_2U(SCH_1):GND

Q_RES  I102  PR528  [Q_RES_0402LF-100,1%,1/16W,CHIPA]
    1  SVID_DIO0_CPU0_R      A  @S9S_MB_2U_LIB.S9S_MB_2U(SCH_1):SVID_DIO0_CPU0_R
    2  PVNN_TERM_CPU0      B  @S9S_MB_2U_LIB.S9S_MB_2U(SCH_1):PVNN_TERM_CPU0

Q_RES  I101  PR529  [Q_RES_0402LF-49.9     ,1%  ,1/A]
    1  SVID_CLK0_CPU0_R      A  @S9S_MB_2U_LIB.S9S_MB_2U(SCH_1):SVID_CLK0_CPU0_R
    2  PVNN_TERM_CPU0      B  @S9S_MB_2U_LIB.S9S_MB_2U(SCH_1):PVNN_TERM_CPU0

Q_RES  I100  PR530  [Q_RES_0402LF-49.9     ,1%  ,1/B]
    1  SVID_ALERT0_CPU0_R_N      A  @S9S_MB_2U_LIB.S9S_MB_2U(SCH_1):SVID_ALERT0_CPU0_R_N
    2  PVNN_TERM_CPU0      B  @S9S_MB_2U_LIB.S9S_MB_2U(SCH_1):PVNN_TERM_CPU0

Q_RES  I31  PR531  [Q_RES_0402LF-100,1%,1/16W,CHIPA]
    1  VSENSE_PVCCIN_CPU0_DP      A  @S9S_MB_2U_LIB.S9S_MB_2U(SCH_1):VSENSE_PVCCIN_CPU0_DP
    2  PVCCIN_CPU0        B  @S9S_MB_2U_LIB.S9S_MB_2U(SCH_1):PVCCIN_CPU0

Q_RES  I206  PR558  [Q_RES_0402LF-100,1%,1/16W,CHIPA]
    1  VSENSE_PVCCD_HV_CPU1_DN      A  @S9S_MB_2U_LIB.S9S_MB_2U(SCH_1):VSENSE_PVCCD_HV_CPU1_DN
    2  GND                B  @S9S_MB_2U_LIB.S9S_MB_2U(SCH_1):GND

Q_RES  I223  PR559  [Q_RES_0402LF-100,1%,1/16W,CHIPA]
    1  VSENSE_PVCCD_HV_CPU1_DP      A  @S9S_MB_2U_LIB.S9S_MB_2U(SCH_1):VSENSE_PVCCD_HV_CPU1_DP
    2  PVCCD_HV_CPU1      B  @S9S_MB_2U_LIB.S9S_MB_2U(SCH_1):PVCCD_HV_CPU1

Q_RES  I171  PR560  [Q_RES_0402LF-100,1%,1/16W,CHIPA]
    1  VSENSE_PVCCFA_EHV_FIVRA_CPU1_DN      A  @S9S_MB_2U_LIB.S9S_MB_2U(SCH_1):VSENSE_PVCCFA_EHV_FIVRA_CPU1_DN
    2  GND                B  @S9S_MB_2U_LIB.S9S_MB_2U(SCH_1):GND

Q_RES  I175  PR561  [Q_RES_0402LF-100,1%,1/16W,CHIPA]
    1  VSENSE_PVCCFA_EHV_FIVRA_CPU1_DP      A  @S9S_MB_2U_LIB.S9S_MB_2U(SCH_1):VSENSE_PVCCFA_EHV_FIVRA_CPU1_DP
    2  PVCCFA_EHV_FIVRA_CPU1      B  @S9S_MB_2U_LIB.S9S_MB_2U(SCH_1):PVCCFA_EHV_FIVRA_CPU1

Q_RES  I22  PR566  [Q_RES_0402LF-100,1%,1/16W,CHIPA]
    1  VSENSE_PVCCINFAON_CPU1_DN      A  @S9S_MB_2U_LIB.S9S_MB_2U(SCH_1):VSENSE_PVCCINFAON_CPU1_DN
    2  GND                B  @S9S_MB_2U_LIB.S9S_MB_2U(SCH_1):GND

Q_RES  I19  PR567  [Q_RES_0402LF-100,1%,1/16W,CHIPA]
    1  VSENSE_PVCCFA_EHV_CPU1_DN      A  @S9S_MB_2U_LIB.S9S_MB_2U(SCH_1):VSENSE_PVCCFA_EHV_CPU1_DN
    2  GND                B  @S9S_MB_2U_LIB.S9S_MB_2U(SCH_1):GND

Q_RES  I98  PR568  [Q_RES_0402LF-100,1%,1/16W,CHIPA]
    1  VSENSE_PVCCINFAON_CPU1_DP      A  @S9S_MB_2U_LIB.S9S_MB_2U(SCH_1):VSENSE_PVCCINFAON_CPU1_DP
    2  PVCCINFAON_CPU1      B  @S9S_MB_2U_LIB.S9S_MB_2U(SCH_1):PVCCINFAON_CPU1

Q_RES  I21  PR569  [Q_RES_0402LF-100,1%,1/16W,CHIPA]
    1  VSENSE_PVCCFA_EHV_CPU1_DP      A  @S9S_MB_2U_LIB.S9S_MB_2U(SCH_1):VSENSE_PVCCFA_EHV_CPU1_DP
    2  PVCCFA_EHV_CPU1      B  @S9S_MB_2U_LIB.S9S_MB_2U(SCH_1):PVCCFA_EHV_CPU1

Q_RES  I26  PR570  [Q_RES_0402LF-1K,1%,1/16W,CHIP,A]
    2  PVCCINFAON_CPU1_VR_FAULT      B  @S9S_MB_2U_LIB.S9S_MB_2U(SCH_1):PVCCINFAON_CPU1_VR_FAULT
    1  P3V3_AUX           A  @S9S_MB_2U_LIB.S9S_MB_2U(SCH_1):P3V3_AUX

Q_RES  I25  PR571  [Q_RES_0402LF-1K,1%,1/16W,CHIP,A]
    2  PVCCINFAON_CPU1_PIN_ALERT      B  @S9S_MB_2U_LIB.S9S_MB_2U(SCH_1):PVCCINFAON_CPU1_PIN_ALERT
    1  P3V3_AUX           A  @S9S_MB_2U_LIB.S9S_MB_2U(SCH_1):P3V3_AUX

Q_RES  I176  PR574  [Q_RES_0402LF-100,1%,1/16W,CHIPA]
    1  VSENSE_PVCCIN_CPU1_DN      A  @S9S_MB_2U_LIB.S9S_MB_2U(SCH_1):VSENSE_PVCCIN_CPU1_DN
    2  GND                B  @S9S_MB_2U_LIB.S9S_MB_2U(SCH_1):GND

Q_RES  I272  PR575  [Q_RES_0402LF-100,1%,1/16W,CHIPA]
    1  SVID_DIO0_CPU1_R      A  @S9S_MB_2U_LIB.S9S_MB_2U(SCH_1):SVID_DIO0_CPU1_R
    2  PVNN_TERM_CPU1      B  @S9S_MB_2U_LIB.S9S_MB_2U(SCH_1):PVNN_TERM_CPU1

Q_RES  I269  PR576  [Q_RES_0402LF-49.9     ,1%  ,1/A]
    1  SVID_CLK0_CPU1_R      A  @S9S_MB_2U_LIB.S9S_MB_2U(SCH_1):SVID_CLK0_CPU1_R
    2  PVNN_TERM_CPU1      B  @S9S_MB_2U_LIB.S9S_MB_2U(SCH_1):PVNN_TERM_CPU1

Q_RES  I268  PR577  [Q_RES_0402LF-49.9     ,1%  ,1/B]
    1  SVID_ALERT0_CPU1_R_N      A  @S9S_MB_2U_LIB.S9S_MB_2U(SCH_1):SVID_ALERT0_CPU1_R_N
    2  PVNN_TERM_CPU1      B  @S9S_MB_2U_LIB.S9S_MB_2U(SCH_1):PVNN_TERM_CPU1

Q_RES  I188  PR578  [Q_RES_0402LF-100,1%,1/16W,CHIPA]
    1  VSENSE_PVCCIN_CPU1_DP      A  @S9S_MB_2U_LIB.S9S_MB_2U(SCH_1):VSENSE_PVCCIN_CPU1_DP
    2  PVCCIN_CPU1        B  @S9S_MB_2U_LIB.S9S_MB_2U(SCH_1):PVCCIN_CPU1

Q_RES  I16  PR586  [Q_RES_0402LF-100,1%,1/16W,CHIPA]
    1  VSENSE_PVCCFA_EHV_FIVRA_CPU0_DN      A  @S9S_MB_2U_LIB.S9S_MB_2U(SCH_1):VSENSE_PVCCFA_EHV_FIVRA_CPU0_DN
    2  GND                B  @S9S_MB_2U_LIB.S9S_MB_2U(SCH_1):GND

Q_RES  I20  PR587  [Q_RES_0402LF-100,1%,1/16W,CHIPA]
    1  VSENSE_PVCCFA_EHV_FIVRA_CPU0_DP      A  @S9S_MB_2U_LIB.S9S_MB_2U(SCH_1):VSENSE_PVCCFA_EHV_FIVRA_CPU0_DP
    2  PVCCFA_EHV_FIVRA_CPU0      B  @S9S_MB_2U_LIB.S9S_MB_2U(SCH_1):PVCCFA_EHV_FIVRA_CPU0

Q_RES  I78  PR591  [Q_RES_0402LF-100,1%,1/16W,CHIPA]
    1  VSENSE_PVCCD_HV_CPU0_DN      A  @S9S_MB_2U_LIB.S9S_MB_2U(SCH_1):VSENSE_PVCCD_HV_CPU0_DN
    2  GND                B  @S9S_MB_2U_LIB.S9S_MB_2U(SCH_1):GND

Q_RES  I33  PR592  [Q_RES_0402LF-100,1%,1/16W,CHIPA]
    1  VSENSE_PVCCD_HV_CPU0_DP      A  @S9S_MB_2U_LIB.S9S_MB_2U(SCH_1):VSENSE_PVCCD_HV_CPU0_DP
    2  PVCCD_HV_CPU0      B  @S9S_MB_2U_LIB.S9S_MB_2U(SCH_1):PVCCD_HV_CPU0

Q_RES  I26  PR632  [Q_RES_0402LF-0,5%,1/16W,EMPTY,A]
    2  PVCCFA_EHV_FIVRA_CPU0_PVCC1      B  @S9S_MB_2U_LIB.S9S_MB_2U(SCH_1):PVCCFA_EHV_FIVRA_CPU0_PVCC1
    1  P3V3               A  @S9S_MB_2U_LIB.S9S_MB_2U(SCH_1):P3V3

Q_RES  I14  PR633  [Q_RES_0402LF-0,5%,1/16W,EMPTY,A]
    2  PVCCFA_EHV_FIVRA_CPU0_PVCC2      B  @S9S_MB_2U_LIB.S9S_MB_2U(SCH_1):PVCCFA_EHV_FIVRA_CPU0_PVCC2
    1  P3V3               A  @S9S_MB_2U_LIB.S9S_MB_2U(SCH_1):P3V3

Q_RES  I57  PR634  [Q_RES_0402LF-10K,1%,1/16W,EMPTB]
    1  PVCCD_HV_CPU0_ATSEN      A  @S9S_MB_2U_LIB.S9S_MB_2U(SCH_1):PVCCD_HV_CPU0_ATSEN
    2  GND                B  @S9S_MB_2U_LIB.S9S_MB_2U(SCH_1):GND

Q_RES  I335  PR635  [Q_RES_0402LF-0,5%,1/16W,CHIP,CA]
    2  PVCCD_HV_CPU0_PVCC      B  @S9S_MB_2U_LIB.S9S_MB_2U(SCH_1):PVCCD_HV_CPU0_PVCC
    1  P5V                A  @S9S_MB_2U_LIB.S9S_MB_2U(SCH_1):P5V

Q_RES  I337  PR636  [Q_RES_0402LF-0,5%,1/16W,EMPTY,A]
    2  PVCCD_HV_CPU0_PVCC      B  @S9S_MB_2U_LIB.S9S_MB_2U(SCH_1):PVCCD_HV_CPU0_PVCC
    1  P3V3               A  @S9S_MB_2U_LIB.S9S_MB_2U(SCH_1):P3V3

Q_RES  I260  PR637  [Q_RES_0402LF-10K,1%,1/16W,EMPTB]
    1  PVCCIN_CPU1_ATSEN      A  @S9S_MB_2U_LIB.S9S_MB_2U(SCH_1):PVCCIN_CPU1_ATSEN
    2  GND                B  @S9S_MB_2U_LIB.S9S_MB_2U(SCH_1):GND

Q_RES  I25  PR639  [Q_RES_0402LF-0,5%,1/16W,CHIP,CA]
    2  PVCCIN_CPU1_PVCC      B  @S9S_MB_2U_LIB.S9S_MB_2U(SCH_1):PVCCIN_CPU1_PVCC
    1  P5V                A  @S9S_MB_2U_LIB.S9S_MB_2U(SCH_1):P5V

Q_RES  I34  PR640  [Q_RES_0402LF-0,5%,1/16W,EMPTY,A]
    2  PVCCIN_CPU1_PVCC      B  @S9S_MB_2U_LIB.S9S_MB_2U(SCH_1):PVCCIN_CPU1_PVCC
    1  P3V3               A  @S9S_MB_2U_LIB.S9S_MB_2U(SCH_1):P3V3

Q_RES  I70  PR665  [Q_RES_0402LF-10K,1%,1/16W,EMPTB]
    1  PVCCINFAON_CPU1_ATSEN      A  @S9S_MB_2U_LIB.S9S_MB_2U(SCH_1):PVCCINFAON_CPU1_ATSEN
    2  GND                B  @S9S_MB_2U_LIB.S9S_MB_2U(SCH_1):GND

Q_RES  I93  PR667  [Q_RES_0402LF-10K,1%,1/16W,EMPTB]
    1  PVCCFA_EHV_CPU1_BTSEN      A  @S9S_MB_2U_LIB.S9S_MB_2U(SCH_1):PVCCFA_EHV_CPU1_BTSEN
    2  GND                B  @S9S_MB_2U_LIB.S9S_MB_2U(SCH_1):GND

Q_RES  I20  PR668  [Q_RES_0402LF-0,5%,1/16W,CHIP,CA]
    2  PVCCINFAON_CPU1_PVCC      B  @S9S_MB_2U_LIB.S9S_MB_2U(SCH_1):PVCCINFAON_CPU1_PVCC
    1  P5V                A  @S9S_MB_2U_LIB.S9S_MB_2U(SCH_1):P5V

Q_RES  I28  PR677  [Q_RES_0402LF-0,5%,1/16W,EMPTY,A]
    2  PVCCINFAON_CPU1_PVCC      B  @S9S_MB_2U_LIB.S9S_MB_2U(SCH_1):PVCCINFAON_CPU1_PVCC
    1  P3V3               A  @S9S_MB_2U_LIB.S9S_MB_2U(SCH_1):P3V3

Q_RES  I11  PR678  [Q_RES_0402LF-0,5%,1/16W,CHIP,CA]
    2  PVCCFA_EHV_CPU1_PVCC      B  @S9S_MB_2U_LIB.S9S_MB_2U(SCH_1):PVCCFA_EHV_CPU1_PVCC
    1  P5V                A  @S9S_MB_2U_LIB.S9S_MB_2U(SCH_1):P5V

Q_RES  I16  PR699  [Q_RES_0402LF-0,5%,1/16W,EMPTY,A]
    2  PVCCFA_EHV_CPU1_PVCC      B  @S9S_MB_2U_LIB.S9S_MB_2U(SCH_1):PVCCFA_EHV_CPU1_PVCC
    1  P3V3               A  @S9S_MB_2U_LIB.S9S_MB_2U(SCH_1):P3V3

Q_RES  I277  PR701  [Q_RES_0402LF-0,5%,1/16W,CHIP,CA]
    2  PVCCFA_EHV_FIVRA_CPU1_PVCC1      B  @S9S_MB_2U_LIB.S9S_MB_2U(SCH_1):PVCCFA_EHV_FIVRA_CPU1_PVCC1
    1  P5V                A  @S9S_MB_2U_LIB.S9S_MB_2U(SCH_1):P5V

Q_RES  I210  PR702  [Q_RES_0402LF-0,5%,1/16W,CHIP,CA]
    2  PVCCFA_EHV_FIVRA_CPU1_PVCC2      B  @S9S_MB_2U_LIB.S9S_MB_2U(SCH_1):PVCCFA_EHV_FIVRA_CPU1_PVCC2
    1  P5V                A  @S9S_MB_2U_LIB.S9S_MB_2U(SCH_1):P5V

Q_RES  I235  PR703  [Q_RES_0402LF-0,5%,1/16W,EMPTY,A]
    2  PVCCFA_EHV_FIVRA_CPU1_PVCC1      B  @S9S_MB_2U_LIB.S9S_MB_2U(SCH_1):PVCCFA_EHV_FIVRA_CPU1_PVCC1
    1  P3V3               A  @S9S_MB_2U_LIB.S9S_MB_2U(SCH_1):P3V3

Q_RES  I219  PR704  [Q_RES_0402LF-0,5%,1/16W,EMPTY,A]
    2  PVCCFA_EHV_FIVRA_CPU1_PVCC2      B  @S9S_MB_2U_LIB.S9S_MB_2U(SCH_1):PVCCFA_EHV_FIVRA_CPU1_PVCC2
    1  P3V3               A  @S9S_MB_2U_LIB.S9S_MB_2U(SCH_1):P3V3

Q_RES  I263  PR705  [Q_RES_0402LF-10K,1%,1/16W,EMPTB]
    1  PVCCD_HV_CPU1_ATSEN      A  @S9S_MB_2U_LIB.S9S_MB_2U(SCH_1):PVCCD_HV_CPU1_ATSEN
    2  GND                B  @S9S_MB_2U_LIB.S9S_MB_2U(SCH_1):GND

Q_RES  I11  PR706  [Q_RES_0402LF-0,5%,1/16W,CHIP,CA]
    2  PVCCD_HV_CPU1_PVCC      B  @S9S_MB_2U_LIB.S9S_MB_2U(SCH_1):PVCCD_HV_CPU1_PVCC
    1  P5V                A  @S9S_MB_2U_LIB.S9S_MB_2U(SCH_1):P5V

Q_RES  I14  PR707  [Q_RES_0402LF-0,5%,1/16W,EMPTY,A]
    2  PVCCD_HV_CPU1_PVCC      B  @S9S_MB_2U_LIB.S9S_MB_2U(SCH_1):PVCCD_HV_CPU1_PVCC
    1  P3V3               A  @S9S_MB_2U_LIB.S9S_MB_2U(SCH_1):P3V3

Q_RES  I34  PR830  [Q_RES_0402LF-31.6K,1%,1/16W,CHA]
    1  P3V3_AUX_FB        A  @S9S_MB_2U_LIB.S9S_MB_2U(SCH_1):P3V3_AUX_FB
    2  GND                B  @S9S_MB_2U_LIB.S9S_MB_2U(SCH_1):GND

Q_RES  I36  PR831  [Q_RES_0402LF-100K,1%,1/16W,CHIA]
    1  P3V3_AUX_FB        A  @S9S_MB_2U_LIB.S9S_MB_2U(SCH_1):P3V3_AUX_FB
    2  P3V3_AUX           B  @S9S_MB_2U_LIB.S9S_MB_2U(SCH_1):P3V3_AUX

Q_RES  I9   PR832  [Q_RES_0402LF-7.5K,1%,1/16W,CHIA]
    1  P3V3_AUX_MODE      A  @S9S_MB_2U_LIB.S9S_MB_2U(SCH_1):P3V3_AUX_MODE
    2  GND                B  @S9S_MB_2U_LIB.S9S_MB_2U(SCH_1):GND

Q_RES  I11  PR833  [Q_RES_0402LF-1.5K,1%,1/16W,EMPA]
    1  P3V3_AUX_SS        A  @S9S_MB_2U_LIB.S9S_MB_2U(SCH_1):P3V3_AUX_SS
    2  GND                B  @S9S_MB_2U_LIB.S9S_MB_2U(SCH_1):GND

Q_RES  I13  PR834  [Q_RES_0402LF-21.5K,1%,1/16W,CHA]
    1  P3V3_AUX_ILIM      A  @S9S_MB_2U_LIB.S9S_MB_2U(SCH_1):P3V3_AUX_ILIM
    2  GND                B  @S9S_MB_2U_LIB.S9S_MB_2U(SCH_1):GND

Q_RES  I29  PR835  [Q_RES_0402LF-0,5%,1/16W,CHIP,CA]
    2  SW_P3V3_AUX_BOOT_R      B  @S9S_MB_2U_LIB.S9S_MB_2U(SCH_1):SW_P3V3_AUX_BOOT_R
    1  SW_P3V3_AUX_BOOT      A  @S9S_MB_2U_LIB.S9S_MB_2U(SCH_1):SW_P3V3_AUX_BOOT

Q_RES  I25  PR836  [Q_RES_0402LF-1K,1%,1/16W,CHIP,A]
    1  P3V3_AUX_VOS       A  @S9S_MB_2U_LIB.S9S_MB_2U(SCH_1):P3V3_AUX_VOS
    2  P3V3_AUX           B  @S9S_MB_2U_LIB.S9S_MB_2U(SCH_1):P3V3_AUX

Q_RES  I2   PR1297  [Q_RES_0402LF-8.87K,1%,1/16W,EMA]
    1  PVCCFA_EHV_FIVRA_CPU0_LSET4      A  @S9S_MB_2U_LIB.S9S_MB_2U(SCH_1):PVCCFA_EHV_FIVRA_CPU0_LSET4
    2  GND                B  @S9S_MB_2U_LIB.S9S_MB_2U(SCH_1):GND

Q_RES  I13  PR1298  [Q_RES_0402LF-8.87K,1%,1/16W,EMA]
    1  PVCCFA_EHV_FIVRA_CPU0_LSET3      A  @S9S_MB_2U_LIB.S9S_MB_2U(SCH_1):PVCCFA_EHV_FIVRA_CPU0_LSET3
    2  GND                B  @S9S_MB_2U_LIB.S9S_MB_2U(SCH_1):GND

Q_RES  I21  PR1299  [Q_RES_0402LF-2.2,1%,1/16W,EMPTA]
    2  PVCCFA_EHV_FIVRA_CPU0_VDD3      B  @S9S_MB_2U_LIB.S9S_MB_2U(SCH_1):PVCCFA_EHV_FIVRA_CPU0_VDD3
    1  PVCCFA_EHV_FIVRA_CPU0_PVCC1      A  @S9S_MB_2U_LIB.S9S_MB_2U(SCH_1):PVCCFA_EHV_FIVRA_CPU0_PVCC1

Q_RES  I10  PR1300  [Q_RES_0402LF-2.2,1%,1/16W,EMPTA]
    2  PVCCFA_EHV_FIVRA_CPU0_VDD4      B  @S9S_MB_2U_LIB.S9S_MB_2U(SCH_1):PVCCFA_EHV_FIVRA_CPU0_VDD4
    1  PVCCFA_EHV_FIVRA_CPU0_PVCC2      A  @S9S_MB_2U_LIB.S9S_MB_2U(SCH_1):PVCCFA_EHV_FIVRA_CPU0_PVCC2

Q_RES  I162  PR1301  [Q_RES_0402LF-60.4K,1%,1/16W,CHA]
    1  PVNN_MAIN_CPU0_MODE      A  @S9S_MB_2U_LIB.S9S_MB_2U(SCH_1):PVNN_MAIN_CPU0_MODE
    2  GND                B  @S9S_MB_2U_LIB.S9S_MB_2U(SCH_1):GND

Q_RES  I33  PR1302  [Q_RES_0402LF-10K,1%,1/16W,CHIPA]
    2  PWRGD_P1V8_PCH_AUX_R      B  @S9S_MB_2U_LIB.S9S_MB_2U(SCH_1):PWRGD_P1V8_PCH_AUX_R
    1  P3V3_AUX           A  @S9S_MB_2U_LIB.S9S_MB_2U(SCH_1):P3V3_AUX

Q_RES  I161  PR1303  [Q_RES_0402LF-9.09K,1%,1/16W,CHA]
    1  PVNN_MAIN_CPU0_CS      A  @S9S_MB_2U_LIB.S9S_MB_2U(SCH_1):PVNN_MAIN_CPU0_CS
    2  GND                B  @S9S_MB_2U_LIB.S9S_MB_2U(SCH_1):GND

Q_RES  I2   PR1304  [Q_RES_0402LF-8.87K,1%,1/16W,EMA]
    1  PVCCFA_EHV_FIVRA_CPU1_LSET4      A  @S9S_MB_2U_LIB.S9S_MB_2U(SCH_1):PVCCFA_EHV_FIVRA_CPU1_LSET4
    2  GND                B  @S9S_MB_2U_LIB.S9S_MB_2U(SCH_1):GND

Q_RES  I13  PR1305  [Q_RES_0402LF-8.87K,1%,1/16W,EMA]
    1  PVCCFA_EHV_FIVRA_CPU1_LSET3      A  @S9S_MB_2U_LIB.S9S_MB_2U(SCH_1):PVCCFA_EHV_FIVRA_CPU1_LSET3
    2  GND                B  @S9S_MB_2U_LIB.S9S_MB_2U(SCH_1):GND

Q_RES  I21  PR1306  [Q_RES_0402LF-2.2,1%,1/16W,CHIPA]
    2  PVCCFA_EHV_FIVRA_CPU1_VDD3      B  @S9S_MB_2U_LIB.S9S_MB_2U(SCH_1):PVCCFA_EHV_FIVRA_CPU1_VDD3
    1  PVCCFA_EHV_FIVRA_CPU1_PVCC1      A  @S9S_MB_2U_LIB.S9S_MB_2U(SCH_1):PVCCFA_EHV_FIVRA_CPU1_PVCC1

Q_RES  I10  PR1307  [Q_RES_0402LF-2.2,1%,1/16W,CHIPA]
    2  PVCCFA_EHV_FIVRA_CPU1_VDD4      B  @S9S_MB_2U_LIB.S9S_MB_2U(SCH_1):PVCCFA_EHV_FIVRA_CPU1_VDD4
    1  PVCCFA_EHV_FIVRA_CPU1_PVCC2      A  @S9S_MB_2U_LIB.S9S_MB_2U(SCH_1):PVCCFA_EHV_FIVRA_CPU1_PVCC2

Q_RES  I25  PR1309  [Q_RES_0402LF-10K,1%,1/16W,EMPTA]
    2  PWRGD_PVPP_HBM_CPU0_R      B  @S9S_MB_2U_LIB.S9S_MB_2U(SCH_1):PWRGD_PVPP_HBM_CPU0_R
    1  P3V3_AUX           A  @S9S_MB_2U_LIB.S9S_MB_2U(SCH_1):P3V3_AUX

Q_RES  I49  PR1310  [Q_RES_0402LF-18.2K,0.1%,1/16W,A]
    2  SH_PVPP_HBM_CPU0_N      B  @S9S_MB_2U_LIB.S9S_MB_2U(SCH_1):SH_PVPP_HBM_CPU0_N
    1  PVPP_HBM_CPU0_FB      A  @S9S_MB_2U_LIB.S9S_MB_2U(SCH_1):PVPP_HBM_CPU0_FB

Q_RES  I58  PR1311  [Q_RES_0402LF-0,5%,1/16W,CHIP,CA]
    1  PVCCD_HV_CPU0_ISYS_R      A  @S9S_MB_2U_LIB.S9S_MB_2U(SCH_1):PVCCD_HV_CPU0_ISYS_R
    2  GND                B  @S9S_MB_2U_LIB.S9S_MB_2U(SCH_1):GND

Q_RES  I23  PR1313  [Q_RES_0402LF-10K,1%,1/16W,CHIPA]
    2  PWRGD_PVPP_HBM_CPU1_R      B  @S9S_MB_2U_LIB.S9S_MB_2U(SCH_1):PWRGD_PVPP_HBM_CPU1_R
    1  P3V3_AUX           A  @S9S_MB_2U_LIB.S9S_MB_2U(SCH_1):P3V3_AUX

Q_RES  I49  PR1314  [Q_RES_0402LF-18.2K,0.1%,1/16W,B]
    2  SH_PVPP_HBM_CPU1_N      B  @S9S_MB_2U_LIB.S9S_MB_2U(SCH_1):SH_PVPP_HBM_CPU1_N
    1  PVPP_HBM_CPU1_FB      A  @S9S_MB_2U_LIB.S9S_MB_2U(SCH_1):PVPP_HBM_CPU1_FB

Q_RES  I259  PR1315  [Q_RES_0402LF-0,5%,1/16W,CHIP,CA]
    1  PVCCD_HV_CPU1_ISYS_R      A  @S9S_MB_2U_LIB.S9S_MB_2U(SCH_1):PVCCD_HV_CPU1_ISYS_R
    2  GND                B  @S9S_MB_2U_LIB.S9S_MB_2U(SCH_1):GND

Q_RES  I174  PR1317  [Q_RES_0402LF-10K,1%,1/16W,CHIPA]
    2  PWRGD_PVNN_MAIN_CPU0_R      B  @S9S_MB_2U_LIB.S9S_MB_2U(SCH_1):PWRGD_PVNN_MAIN_CPU0_R
    1  P3V3_AUX           A  @S9S_MB_2U_LIB.S9S_MB_2U(SCH_1):P3V3_AUX

Q_RES  I187  PR1320  [Q_RES_0402LF-10K,1%,1/16W,CHIPA]
    2  PWRGD_PVNN_MAIN_CPU1_R      B  @S9S_MB_2U_LIB.S9S_MB_2U(SCH_1):PWRGD_PVNN_MAIN_CPU1_R
    1  P3V3_AUX           A  @S9S_MB_2U_LIB.S9S_MB_2U(SCH_1):P3V3_AUX

Q_RES  I53  PR1322  [Q_RES_0402LF-0,5%,1/16W,CHIP,CA]
    1  PVCCFA_EHV_FIVRA_CPU0_VOS1      A  @S9S_MB_2U_LIB.S9S_MB_2U(SCH_1):PVCCFA_EHV_FIVRA_CPU0_VOS1
    2  PVCCFA_EHV_FIVRA_CPU0      B  @S9S_MB_2U_LIB.S9S_MB_2U(SCH_1):PVCCFA_EHV_FIVRA_CPU0

Q_RES  I36  PR1323  [Q_RES_0402LF-0,5%,1/16W,CHIP,CA]
    1  PVCCFA_EHV_FIVRA_CPU0_VOS2      A  @S9S_MB_2U_LIB.S9S_MB_2U(SCH_1):PVCCFA_EHV_FIVRA_CPU0_VOS2
    2  PVCCFA_EHV_FIVRA_CPU0      B  @S9S_MB_2U_LIB.S9S_MB_2U(SCH_1):PVCCFA_EHV_FIVRA_CPU0

Q_RES  I47  PR1324  [Q_RES_0402LF-0,5%,1/16W,EMPTY,A]
    1  PVCCFA_EHV_FIVRA_CPU0_VOS3      A  @S9S_MB_2U_LIB.S9S_MB_2U(SCH_1):PVCCFA_EHV_FIVRA_CPU0_VOS3
    2  PVCCFA_EHV_FIVRA_CPU0      B  @S9S_MB_2U_LIB.S9S_MB_2U(SCH_1):PVCCFA_EHV_FIVRA_CPU0

Q_RES  I29  PR1325  [Q_RES_0402LF-0,5%,1/16W,EMPTY,A]
    1  PVCCFA_EHV_FIVRA_CPU0_VOS4      A  @S9S_MB_2U_LIB.S9S_MB_2U(SCH_1):PVCCFA_EHV_FIVRA_CPU0_VOS4
    2  PVCCFA_EHV_FIVRA_CPU0      B  @S9S_MB_2U_LIB.S9S_MB_2U(SCH_1):PVCCFA_EHV_FIVRA_CPU0

Q_RES  I21  PR1326  [Q_RES_0402LF-0,5%,1/16W,CHIP,CA]
    1  P3V3_AUX           A  @S9S_MB_2U_LIB.S9S_MB_2U(SCH_1):P3V3_AUX
    2  P1V05_PCH_AUX_VCC      B  @S9S_MB_2U_LIB.S9S_MB_2U(SCH_1):P1V05_PCH_AUX_VCC

Q_RES  I10  PR1327  [Q_RES_0402LF-6.81K,1%,1/16W,CHA]
    1  P1V05_PCH_AUX_CS      A  @S9S_MB_2U_LIB.S9S_MB_2U(SCH_1):P1V05_PCH_AUX_CS
    2  GND                B  @S9S_MB_2U_LIB.S9S_MB_2U(SCH_1):GND

Q_RES  I41  PR1328  [Q_RES_0402LF-7.32K,1%,1/16W,CHA]
    2  SH_P1V05_PCH_AUX_P      B  @S9S_MB_2U_LIB.S9S_MB_2U(SCH_1):SH_P1V05_PCH_AUX_P
    1  P1V05_PCH_AUX_FB      A  @S9S_MB_2U_LIB.S9S_MB_2U(SCH_1):P1V05_PCH_AUX_FB

Q_RES  I7   PR1329  [Q_RES_0402LF-5.1,5%,1/16W,CHIPA]
    1  PVCC1_AUX          A  @S9S_MB_2U_LIB.S9S_MB_2U(SCH_1):PVCC1_AUX
    2  P1V8_PCH_AUX_VCC      B  @S9S_MB_2U_LIB.S9S_MB_2U(SCH_1):P1V8_PCH_AUX_VCC

Q_RES  I12  PR1330  [Q_RES_0402LF-150K,1%,1/16W,CHIA]
    1  P1V8_PCH_AUX_MODE      A  @S9S_MB_2U_LIB.S9S_MB_2U(SCH_1):P1V8_PCH_AUX_MODE
    2  GND                B  @S9S_MB_2U_LIB.S9S_MB_2U(SCH_1):GND

Q_RES  I260  PR1331  [Q_RES_0402LF-0,5%,1/16W,CHIP,CA]
    1  PVCCFA_EHV_FIVRA_CPU1_VOS1      A  @S9S_MB_2U_LIB.S9S_MB_2U(SCH_1):PVCCFA_EHV_FIVRA_CPU1_VOS1
    2  PVCCFA_EHV_FIVRA_CPU1      B  @S9S_MB_2U_LIB.S9S_MB_2U(SCH_1):PVCCFA_EHV_FIVRA_CPU1

Q_RES  I239  PR1332  [Q_RES_0402LF-0,5%,1/16W,CHIP,CA]
    1  PVCCFA_EHV_FIVRA_CPU1_VOS2      A  @S9S_MB_2U_LIB.S9S_MB_2U(SCH_1):PVCCFA_EHV_FIVRA_CPU1_VOS2
    2  PVCCFA_EHV_FIVRA_CPU1      B  @S9S_MB_2U_LIB.S9S_MB_2U(SCH_1):PVCCFA_EHV_FIVRA_CPU1

Q_RES  I47  PR1333  [Q_RES_0402LF-0,5%,1/16W,CHIP,CA]
    1  PVCCFA_EHV_FIVRA_CPU1_VOS3      A  @S9S_MB_2U_LIB.S9S_MB_2U(SCH_1):PVCCFA_EHV_FIVRA_CPU1_VOS3
    2  PVCCFA_EHV_FIVRA_CPU1      B  @S9S_MB_2U_LIB.S9S_MB_2U(SCH_1):PVCCFA_EHV_FIVRA_CPU1

Q_RES  I30  PR1334  [Q_RES_0402LF-0,5%,1/16W,CHIP,CA]
    1  PVCCFA_EHV_FIVRA_CPU1_VOS4      A  @S9S_MB_2U_LIB.S9S_MB_2U(SCH_1):PVCCFA_EHV_FIVRA_CPU1_VOS4
    2  PVCCFA_EHV_FIVRA_CPU1      B  @S9S_MB_2U_LIB.S9S_MB_2U(SCH_1):PVCCFA_EHV_FIVRA_CPU1

Q_RES  I5   PR1335  [Q_RES_0402LF-0,5%,1/16W,EMPTY,A]
    2  PVPP_HBM_CPU0_VCC      B  @S9S_MB_2U_LIB.S9S_MB_2U(SCH_1):PVPP_HBM_CPU0_VCC
    1  P3V3_AUX           A  @S9S_MB_2U_LIB.S9S_MB_2U(SCH_1):P3V3_AUX

Q_RES  I12  PR1336  [Q_RES_0402LF-8.87K,1%,1/16W,EMA]
    1  PVPP_HBM_CPU0_CS      A  @S9S_MB_2U_LIB.S9S_MB_2U(SCH_1):PVPP_HBM_CPU0_CS
    2  GND                B  @S9S_MB_2U_LIB.S9S_MB_2U(SCH_1):GND

Q_RES  I53  PR1337  [Q_RES_0402LF-36K,1%,1/16W,EMPTA]
    2  SH_PVPP_HBM_CPU0_P      B  @S9S_MB_2U_LIB.S9S_MB_2U(SCH_1):SH_PVPP_HBM_CPU0_P
    1  PVPP_HBM_CPU0_FB      A  @S9S_MB_2U_LIB.S9S_MB_2U(SCH_1):PVPP_HBM_CPU0_FB

Q_RES  I8   PR1338  [Q_RES_0402LF-0,5%,1/16W,CHIP,CA]
    2  PVPP_HBM_CPU1_VCC      B  @S9S_MB_2U_LIB.S9S_MB_2U(SCH_1):PVPP_HBM_CPU1_VCC
    1  P3V3_AUX           A  @S9S_MB_2U_LIB.S9S_MB_2U(SCH_1):P3V3_AUX

Q_RES  I14  PR1339  [Q_RES_0402LF-9.31K,1%,1/16W,CHA]
    1  PVPP_HBM_CPU1_CS      A  @S9S_MB_2U_LIB.S9S_MB_2U(SCH_1):PVPP_HBM_CPU1_CS
    2  GND                B  @S9S_MB_2U_LIB.S9S_MB_2U(SCH_1):GND

Q_RES  I54  PR1340  [Q_RES_0402LF-36K,1%,1/16W,CHIPA]
    2  SH_PVPP_HBM_CPU1_P      B  @S9S_MB_2U_LIB.S9S_MB_2U(SCH_1):SH_PVPP_HBM_CPU1_P
    1  PVPP_HBM_CPU1_FB      A  @S9S_MB_2U_LIB.S9S_MB_2U(SCH_1):PVPP_HBM_CPU1_FB

Q_RES  I10  PR1380  [Q_RES_0402LF-49.9     ,1%  ,1/A]
    2  PVCCD_HV_CPU0_ISENSE_P      B  @S9S_MB_2U_LIB.S9S_MB_2U(SCH_1):PVCCD_HV_CPU0_ISENSE_P
    1  P12V_S3_AUX_CPU0_NVDIMM_ISENS_1      A  @S9S_MB_2U_LIB.S9S_MB_2U(SCH_1):P12V_S3_AUX_CPU0_NVDIMM_ISENSE_P

Q_RES  I26  PR1388  [Q_RES_0402LF-0,5%,1/16W,EMPTY,A]
    1  NC                 A  NC
    2  FM_P1V05_PCH_AUX_R_EN      B  @S9S_MB_2U_LIB.S9S_MB_2U(SCH_1):FM_P1V05_PCH_AUX_R_EN

Q_RES  I25  PR1389  [Q_RES_0402LF-0,5%,1/16W,CHIP,CA]
    2  FM_P1V05_PCH_AUX_R_EN      B  @S9S_MB_2U_LIB.S9S_MB_2U(SCH_1):FM_P1V05_PCH_AUX_R_EN
    1  FM_P1V05_PCH_AUX_EN      A  @S9S_MB_2U_LIB.S9S_MB_2U(SCH_1):FM_P1V05_PCH_AUX_EN

Q_RES  I9   PR1390  [Q_RES_0402LF-49.9     ,1%  ,1/A]
    2  PVCCD_HV_CPU0_ISENSE_N      B  @S9S_MB_2U_LIB.S9S_MB_2U(SCH_1):PVCCD_HV_CPU0_ISENSE_N
    1  P12V_S3_AUX_CPU0_NVDIMM_ISENSE_      A  @S9S_MB_2U_LIB.S9S_MB_2U(SCH_1):P12V_S3_AUX_CPU0_NVDIMM_ISENSE_N

Q_RES  I203  PR1400  [Q_RES_0402LF-49.9     ,1%  ,1/A]
    2  PVCCD_HV_CPU1_ISENSE_P      B  @S9S_MB_2U_LIB.S9S_MB_2U(SCH_1):PVCCD_HV_CPU1_ISENSE_P
    1  P12V_S3_AUX_CPU1_NVDIMM_ISENS_1      A  @S9S_MB_2U_LIB.S9S_MB_2U(SCH_1):P12V_S3_AUX_CPU1_NVDIMM_ISENSE_P

Q_RES  I202  PR1410  [Q_RES_0402LF-49.9     ,1%  ,1/A]
    2  PVCCD_HV_CPU1_ISENSE_N      B  @S9S_MB_2U_LIB.S9S_MB_2U(SCH_1):PVCCD_HV_CPU1_ISENSE_N
    1  P12V_S3_AUX_CPU1_NVDIMM_ISENSE_      A  @S9S_MB_2U_LIB.S9S_MB_2U(SCH_1):P12V_S3_AUX_CPU1_NVDIMM_ISENSE_N

Q_RES  I27  PR1647  [Q_RES_0402LF-10K,1%,1/16W,EMPTA]
    1  P3V3_AUX           A  @S9S_MB_2U_LIB.S9S_MB_2U(SCH_1):P3V3_AUX
    2  FM_P1V05_PCH_AUX_R_EN      B  @S9S_MB_2U_LIB.S9S_MB_2U(SCH_1):FM_P1V05_PCH_AUX_R_EN

Q_RES  I39  PR1650  [Q_RES_0402LF-0,5%,1/16W,CHIP,CA]
    1  PWRGD_P1V05_PCH_AUX_R      A  @S9S_MB_2U_LIB.S9S_MB_2U(SCH_1):PWRGD_P1V05_PCH_AUX_R
    2  PWRGD_P1V05_PCH_AUX      B  @S9S_MB_2U_LIB.S9S_MB_2U(SCH_1):PWRGD_P1V05_PCH_AUX

Q_RES  I35  PR1651  [Q_RES_0402LF-0,5%,1/16W,CHIP,CA]
    1  PWRGD_P1V8_PCH_AUX_R      A  @S9S_MB_2U_LIB.S9S_MB_2U(SCH_1):PWRGD_P1V8_PCH_AUX_R
    2  PWRGD_P1V8_PCH_AUX      B  @S9S_MB_2U_LIB.S9S_MB_2U(SCH_1):PWRGD_P1V8_PCH_AUX

Q_RES  I146  PR1707  [Q_RES_0402LF-8.87K,1%,1/16W,EMA]
    1  PVCCINFAON_CPU0_LSET2      A  @S9S_MB_2U_LIB.S9S_MB_2U(SCH_1):PVCCINFAON_CPU0_LSET2
    2  GND                B  @S9S_MB_2U_LIB.S9S_MB_2U(SCH_1):GND

Q_RES  I156  PR1708  [Q_RES_0402LF-8.87K,1%,1/16W,EMA]
    1  PVCCINFAON_CPU0_LSET1      A  @S9S_MB_2U_LIB.S9S_MB_2U(SCH_1):PVCCINFAON_CPU0_LSET1
    2  GND                B  @S9S_MB_2U_LIB.S9S_MB_2U(SCH_1):GND

Q_RES  I2   PR1709  [Q_RES_0402LF-8.87K,1%,1/16W,EMA]
    1  PVCCFA_EHV_CPU0_LSET1      A  @S9S_MB_2U_LIB.S9S_MB_2U(SCH_1):PVCCFA_EHV_CPU0_LSET1
    2  GND                B  @S9S_MB_2U_LIB.S9S_MB_2U(SCH_1):GND

Q_RES  I216  PR1718  [Q_RES_0402LF-49.9     ,1%  ,1/A]
    2  SVID_CLK1_CPU1_R      B  @S9S_MB_2U_LIB.S9S_MB_2U(SCH_1):SVID_CLK1_CPU1_R
    1  PVNN_TERM_CPU1      A  @S9S_MB_2U_LIB.S9S_MB_2U(SCH_1):PVNN_TERM_CPU1

Q_RES  I7   PR1726  [Q_RES_0402LF-8.87K,1%,1/16W,EMA]
    1  PVCCINFAON_CPU1_LSET1      A  @S9S_MB_2U_LIB.S9S_MB_2U(SCH_1):PVCCINFAON_CPU1_LSET1
    2  GND                B  @S9S_MB_2U_LIB.S9S_MB_2U(SCH_1):GND

Q_RES  I3   PR1727  [Q_RES_0402LF-8.87K,1%,1/16W,EMA]
    1  PVCCINFAON_CPU1_LSET2      A  @S9S_MB_2U_LIB.S9S_MB_2U(SCH_1):PVCCINFAON_CPU1_LSET2
    2  GND                B  @S9S_MB_2U_LIB.S9S_MB_2U(SCH_1):GND

Q_RES  I2   PR1728  [Q_RES_0402LF-8.87K,1%,1/16W,EMA]
    1  PVCCFA_EHV_CPU1_LSET1      A  @S9S_MB_2U_LIB.S9S_MB_2U(SCH_1):PVCCFA_EHV_CPU1_LSET1
    2  GND                B  @S9S_MB_2U_LIB.S9S_MB_2U(SCH_1):GND

Q_RES  I2   PR1746  [Q_RES_0402LF-8.87K,1%,1/16W,EMA]
    1  PVCCD_HV_CPU1_LSET1      A  @S9S_MB_2U_LIB.S9S_MB_2U(SCH_1):PVCCD_HV_CPU1_LSET1
    2  GND                B  @S9S_MB_2U_LIB.S9S_MB_2U(SCH_1):GND

Q_RES  I217  PR1747  [Q_RES_0402LF-100,1%,1/16W,CHIPA]
    2  SVID_DIO1_CPU1_R      B  @S9S_MB_2U_LIB.S9S_MB_2U(SCH_1):SVID_DIO1_CPU1_R
    1  PVNN_TERM_CPU1      A  @S9S_MB_2U_LIB.S9S_MB_2U(SCH_1):PVNN_TERM_CPU1

Q_RES  I22  PR1766  [Q_RES_0402LF-3.3,1%,1/16W,CHIPA]
    2  SW_PVCCIN_CPU1_BOOT2_R      B  @S9S_MB_2U_LIB.S9S_MB_2U(SCH_1):SW_PVCCIN_CPU1_BOOT2_R
    1  SW_PVCCIN_CPU1_BOOT2      A  @S9S_MB_2U_LIB.S9S_MB_2U(SCH_1):SW_PVCCIN_CPU1_BOOT2

Q_RES  I37  PR1767  [Q_RES_0402LF-3.3,1%,1/16W,CHIPA]
    2  SW_PVCCIN_CPU1_BOOT1_R      B  @S9S_MB_2U_LIB.S9S_MB_2U(SCH_1):SW_PVCCIN_CPU1_BOOT1_R
    1  SW_PVCCIN_CPU1_BOOT1      A  @S9S_MB_2U_LIB.S9S_MB_2U(SCH_1):SW_PVCCIN_CPU1_BOOT1

Q_RES  I35  PR1768  [Q_RES_0402LF-3.3,1%,1/16W,CHIPA]
    2  SW_PVCCIN_CPU0_BOOT4_R      B  @S9S_MB_2U_LIB.S9S_MB_2U(SCH_1):SW_PVCCIN_CPU0_BOOT4_R
    1  SW_PVCCIN_CPU0_BOOT4      A  @S9S_MB_2U_LIB.S9S_MB_2U(SCH_1):SW_PVCCIN_CPU0_BOOT4

Q_RES  I49  PR1769  [Q_RES_0402LF-3.3,1%,1/16W,CHIPA]
    2  SW_PVCCIN_CPU0_BOOT3_R      B  @S9S_MB_2U_LIB.S9S_MB_2U(SCH_1):SW_PVCCIN_CPU0_BOOT3_R
    1  SW_PVCCIN_CPU0_BOOT3      A  @S9S_MB_2U_LIB.S9S_MB_2U(SCH_1):SW_PVCCIN_CPU0_BOOT3

Q_RES  I17  PR1770  [Q_RES_0402LF-3.3,1%,1/16W,CHIPA]
    2  SW_PVCCIN_CPU0_BOOT6_R      B  @S9S_MB_2U_LIB.S9S_MB_2U(SCH_1):SW_PVCCIN_CPU0_BOOT6_R
    1  SW_PVCCIN_CPU0_BOOT6      A  @S9S_MB_2U_LIB.S9S_MB_2U(SCH_1):SW_PVCCIN_CPU0_BOOT6

Q_RES  I37  PR1771  [Q_RES_0402LF-3.3,1%,1/16W,CHIPA]
    2  SW_PVCCIN_CPU0_BOOT5_R      B  @S9S_MB_2U_LIB.S9S_MB_2U(SCH_1):SW_PVCCIN_CPU0_BOOT5_R
    1  SW_PVCCIN_CPU0_BOOT5      A  @S9S_MB_2U_LIB.S9S_MB_2U(SCH_1):SW_PVCCIN_CPU0_BOOT5

Q_RES  I35  PR1772  [Q_RES_0402LF-3.3,1%,1/16W,CHIPA]
    2  SW_PVCCIN_CPU0_BOOT8_R      B  @S9S_MB_2U_LIB.S9S_MB_2U(SCH_1):SW_PVCCIN_CPU0_BOOT8_R
    1  SW_PVCCIN_CPU0_BOOT8      A  @S9S_MB_2U_LIB.S9S_MB_2U(SCH_1):SW_PVCCIN_CPU0_BOOT8

Q_RES  I49  PR1773  [Q_RES_0402LF-3.3,1%,1/16W,CHIPA]
    2  SW_PVCCIN_CPU0_BOOT7_R      B  @S9S_MB_2U_LIB.S9S_MB_2U(SCH_1):SW_PVCCIN_CPU0_BOOT7_R
    1  SW_PVCCIN_CPU0_BOOT7      A  @S9S_MB_2U_LIB.S9S_MB_2U(SCH_1):SW_PVCCIN_CPU0_BOOT7

Q_RES  I203  PR1774  [Q_RES_0402LF-4.7,1%,1/16W,CHIPA]
    2  SW_PVCCINFAON_CPU0_BOOT1_R      B  @S9S_MB_2U_LIB.S9S_MB_2U(SCH_1):SW_PVCCINFAON_CPU0_BOOT1_R
    1  SW_PVCCINFAON_CPU0_BOOT1      A  @S9S_MB_2U_LIB.S9S_MB_2U(SCH_1):SW_PVCCINFAON_CPU0_BOOT1

Q_RES  I181  PR1775  [Q_RES_0402LF-4.7,1%,1/16W,CHIPA]
    2  SW_PVCCINFAON_CPU0_BOOT2_R      B  @S9S_MB_2U_LIB.S9S_MB_2U(SCH_1):SW_PVCCINFAON_CPU0_BOOT2_R
    1  SW_PVCCINFAON_CPU0_BOOT2      A  @S9S_MB_2U_LIB.S9S_MB_2U(SCH_1):SW_PVCCINFAON_CPU0_BOOT2

Q_RES  I188  PR1776  [Q_RES_0402LF-0,5%,1/16W,CHIP,CA]
    2  PVCCINFAON_CPU0_VDD1      B  @S9S_MB_2U_LIB.S9S_MB_2U(SCH_1):PVCCINFAON_CPU0_VDD1
    1  PVCCINFAON_CPU0_PH1_NC1      A  @S9S_MB_2U_LIB.S9S_MB_2U(SCH_1):PVCCINFAON_CPU0_PH1_NC1

Q_RES  I180  PR1777  [Q_RES_0402LF-0,5%,1/16W,CHIP,CA]
    2  PVCCINFAON_CPU0_VDD2      B  @S9S_MB_2U_LIB.S9S_MB_2U(SCH_1):PVCCINFAON_CPU0_VDD2
    1  PVCCINFAON_CPU0_PH2_NC1      A  @S9S_MB_2U_LIB.S9S_MB_2U(SCH_1):PVCCINFAON_CPU0_PH2_NC1

Q_RES  I30  PR1778  [Q_RES_0402LF-4.7,1%,1/16W,CHIPA]
    2  SW_PVCCFA_EHV_CPU0_BOOT1_R      B  @S9S_MB_2U_LIB.S9S_MB_2U(SCH_1):SW_PVCCFA_EHV_CPU0_BOOT1_R
    1  SW_PVCCFA_EHV_CPU0_BOOT1      A  @S9S_MB_2U_LIB.S9S_MB_2U(SCH_1):SW_PVCCFA_EHV_CPU0_BOOT1

Q_RES  I19  PR1779  [Q_RES_0402LF-0,5%,1/16W,CHIP,CA]
    2  PVCCFA_EHV_CPU0_VDD1      B  @S9S_MB_2U_LIB.S9S_MB_2U(SCH_1):PVCCFA_EHV_CPU0_VDD1
    1  PVCCFA_EHV_CPU0_NC1      A  @S9S_MB_2U_LIB.S9S_MB_2U(SCH_1):PVCCFA_EHV_CPU0_NC1

Q_RES  I51  PR1780  [Q_RES_0402LF-3.3,1%,1/16W,CHIPA]
    2  SW_PVCCFA_EHV_FIVRA_CPU0_BOOT1_      B  @S9S_MB_2U_LIB.S9S_MB_2U(SCH_1):SW_PVCCFA_EHV_FIVRA_CPU0_BOOT1_R
    1  SW_PVCCFA_EHV_FIVRA_CPU0_BOOT1      A  @S9S_MB_2U_LIB.S9S_MB_2U(SCH_1):SW_PVCCFA_EHV_FIVRA_CPU0_BOOT1

Q_RES  I40  PR1781  [Q_RES_0402LF-3.3,1%,1/16W,CHIPA]
    2  SW_PVCCFA_EHV_FIVRA_CPU0_BOOT2_      B  @S9S_MB_2U_LIB.S9S_MB_2U(SCH_1):SW_PVCCFA_EHV_FIVRA_CPU0_BOOT2_R
    1  SW_PVCCFA_EHV_FIVRA_CPU0_BOOT2      A  @S9S_MB_2U_LIB.S9S_MB_2U(SCH_1):SW_PVCCFA_EHV_FIVRA_CPU0_BOOT2

Q_RES  I45  PR1782  [Q_RES_0402LF-3.3,1%,1/16W,EMPTA]
    2  SW_PVCCFA_EHV_FIVRA_CPU0_BOOT3_      B  @S9S_MB_2U_LIB.S9S_MB_2U(SCH_1):SW_PVCCFA_EHV_FIVRA_CPU0_BOOT3_R
    1  SW_PVCCFA_EHV_FIVRA_CPU0_BOOT3      A  @S9S_MB_2U_LIB.S9S_MB_2U(SCH_1):SW_PVCCFA_EHV_FIVRA_CPU0_BOOT3

Q_RES  I33  PR1783  [Q_RES_0402LF-3.3,1%,1/16W,EMPTA]
    2  SW_PVCCFA_EHV_FIVRA_CPU0_BOOT4_      B  @S9S_MB_2U_LIB.S9S_MB_2U(SCH_1):SW_PVCCFA_EHV_FIVRA_CPU0_BOOT4_R
    1  SW_PVCCFA_EHV_FIVRA_CPU0_BOOT4      A  @S9S_MB_2U_LIB.S9S_MB_2U(SCH_1):SW_PVCCFA_EHV_FIVRA_CPU0_BOOT4

Q_RES  I341  PR1784  [Q_RES_0402LF-4.7,1%,1/16W,CHIPA]
    2  SW_PVCCD_HV_CPU0_BOOT1_R      B  @S9S_MB_2U_LIB.S9S_MB_2U(SCH_1):SW_PVCCD_HV_CPU0_BOOT1_R
    1  SW_PVCCD_HV_CPU0_BOOT1      A  @S9S_MB_2U_LIB.S9S_MB_2U(SCH_1):SW_PVCCD_HV_CPU0_BOOT1

Q_RES  I342  PR1785  [Q_RES_0402LF-0,5%,1/16W,CHIP,CA]
    2  PVCCD_HV_CPU0_VDD1      B  @S9S_MB_2U_LIB.S9S_MB_2U(SCH_1):PVCCD_HV_CPU0_VDD1
    1  PVCCD_HV_CPU0_NC1      A  @S9S_MB_2U_LIB.S9S_MB_2U(SCH_1):PVCCD_HV_CPU0_NC1

Q_RES  I20  PR1786  [Q_RES_0402LF-3.3,1%,1/16W,CHIPA]
    2  SW_PVCCIN_CPU0_BOOT2_R      B  @S9S_MB_2U_LIB.S9S_MB_2U(SCH_1):SW_PVCCIN_CPU0_BOOT2_R
    1  SW_PVCCIN_CPU0_BOOT2      A  @S9S_MB_2U_LIB.S9S_MB_2U(SCH_1):SW_PVCCIN_CPU0_BOOT2

Q_RES  I39  PR1787  [Q_RES_0402LF-3.3,1%,1/16W,CHIPA]
    2  SW_PVCCIN_CPU0_BOOT1_R      B  @S9S_MB_2U_LIB.S9S_MB_2U(SCH_1):SW_PVCCIN_CPU0_BOOT1_R
    1  SW_PVCCIN_CPU0_BOOT1      A  @S9S_MB_2U_LIB.S9S_MB_2U(SCH_1):SW_PVCCIN_CPU0_BOOT1

Q_RES  I34  PR1788  [Q_RES_0402LF-3.3,1%,1/16W,CHIPA]
    2  SW_PVCCIN_CPU1_BOOT4_R      B  @S9S_MB_2U_LIB.S9S_MB_2U(SCH_1):SW_PVCCIN_CPU1_BOOT4_R
    1  SW_PVCCIN_CPU1_BOOT4      A  @S9S_MB_2U_LIB.S9S_MB_2U(SCH_1):SW_PVCCIN_CPU1_BOOT4

Q_RES  I47  PR1789  [Q_RES_0402LF-3.3,1%,1/16W,CHIPA]
    2  SW_PVCCIN_CPU1_BOOT3_R      B  @S9S_MB_2U_LIB.S9S_MB_2U(SCH_1):SW_PVCCIN_CPU1_BOOT3_R
    1  SW_PVCCIN_CPU1_BOOT3      A  @S9S_MB_2U_LIB.S9S_MB_2U(SCH_1):SW_PVCCIN_CPU1_BOOT3

Q_RES  I36  PR1790  [Q_RES_0402LF-3.3,1%,1/16W,CHIPA]
    2  SW_PVCCIN_CPU1_BOOT6_R      B  @S9S_MB_2U_LIB.S9S_MB_2U(SCH_1):SW_PVCCIN_CPU1_BOOT6_R
    1  SW_PVCCIN_CPU1_BOOT6      A  @S9S_MB_2U_LIB.S9S_MB_2U(SCH_1):SW_PVCCIN_CPU1_BOOT6

Q_RES  I47  PR1791  [Q_RES_0402LF-3.3,1%,1/16W,CHIPA]
    2  SW_PVCCIN_CPU1_BOOT5_R      B  @S9S_MB_2U_LIB.S9S_MB_2U(SCH_1):SW_PVCCIN_CPU1_BOOT5_R
    1  SW_PVCCIN_CPU1_BOOT5      A  @S9S_MB_2U_LIB.S9S_MB_2U(SCH_1):SW_PVCCIN_CPU1_BOOT5

Q_RES  I39  PR1792  [Q_RES_0402LF-3.3,1%,1/16W,CHIPA]
    2  SW_PVCCIN_CPU1_BOOT8_R      B  @S9S_MB_2U_LIB.S9S_MB_2U(SCH_1):SW_PVCCIN_CPU1_BOOT8_R
    1  SW_PVCCIN_CPU1_BOOT8      A  @S9S_MB_2U_LIB.S9S_MB_2U(SCH_1):SW_PVCCIN_CPU1_BOOT8

Q_RES  I47  PR1793  [Q_RES_0402LF-3.3,1%,1/16W,CHIPA]
    2  SW_PVCCIN_CPU1_BOOT7_R      B  @S9S_MB_2U_LIB.S9S_MB_2U(SCH_1):SW_PVCCIN_CPU1_BOOT7_R
    1  SW_PVCCIN_CPU1_BOOT7      A  @S9S_MB_2U_LIB.S9S_MB_2U(SCH_1):SW_PVCCIN_CPU1_BOOT7

Q_RES  I52  PR1794  [Q_RES_0402LF-4.7,1%,1/16W,CHIPA]
    2  SW_PVCCINFAON_CPU1_BOOT1_R      B  @S9S_MB_2U_LIB.S9S_MB_2U(SCH_1):SW_PVCCINFAON_CPU1_BOOT1_R
    1  SW_PVCCINFAON_CPU1_BOOT1      A  @S9S_MB_2U_LIB.S9S_MB_2U(SCH_1):SW_PVCCINFAON_CPU1_BOOT1

Q_RES  I35  PR1795  [Q_RES_0402LF-4.7,1%,1/16W,CHIPA]
    2  SW_PVCCINFAON_CPU1_BOOT2_R      B  @S9S_MB_2U_LIB.S9S_MB_2U(SCH_1):SW_PVCCINFAON_CPU1_BOOT2_R
    1  SW_PVCCINFAON_CPU1_BOOT2      A  @S9S_MB_2U_LIB.S9S_MB_2U(SCH_1):SW_PVCCINFAON_CPU1_BOOT2

Q_RES  I49  PR1796  [Q_RES_0402LF-0,5%,1/16W,CHIP,CA]
    2  PVCCINFAON_CPU1_VDD1      B  @S9S_MB_2U_LIB.S9S_MB_2U(SCH_1):PVCCINFAON_CPU1_VDD1
    1  PVCCINFAON_CPU1_PH1_NC1      A  @S9S_MB_2U_LIB.S9S_MB_2U(SCH_1):PVCCINFAON_CPU1_PH1_NC1

Q_RES  I31  PR1797  [Q_RES_0402LF-0,5%,1/16W,CHIP,CA]
    2  PVCCINFAON_CPU1_VDD2      B  @S9S_MB_2U_LIB.S9S_MB_2U(SCH_1):PVCCINFAON_CPU1_VDD2
    1  PVCCINFAON_CPU1_PH2_NC1      A  @S9S_MB_2U_LIB.S9S_MB_2U(SCH_1):PVCCINFAON_CPU1_PH2_NC1

Q_RES  I18  PR1798  [Q_RES_0402LF-4.7,1%,1/16W,CHIPA]
    2  SW_PVCCFA_EHV_CPU1_BOOT1_R      B  @S9S_MB_2U_LIB.S9S_MB_2U(SCH_1):SW_PVCCFA_EHV_CPU1_BOOT1_R
    1  SW_PVCCFA_EHV_CPU1_BOOT1      A  @S9S_MB_2U_LIB.S9S_MB_2U(SCH_1):SW_PVCCFA_EHV_CPU1_BOOT1

Q_RES  I19  PR1799  [Q_RES_0402LF-0,5%,1/16W,CHIP,CA]
    2  PVCCFA_EHV_CPU1_VDD1      B  @S9S_MB_2U_LIB.S9S_MB_2U(SCH_1):PVCCFA_EHV_CPU1_VDD1
    1  PVCCFA_EHV_CPU1_NC1      A  @S9S_MB_2U_LIB.S9S_MB_2U(SCH_1):PVCCFA_EHV_CPU1_NC1

Q_RES  I256  PR1800  [Q_RES_0402LF-3.3,1%,1/16W,CHIPA]
    2  SW_PVCCFA_EHV_FIVRA_CPU1_BOOT1_      B  @S9S_MB_2U_LIB.S9S_MB_2U(SCH_1):SW_PVCCFA_EHV_FIVRA_CPU1_BOOT1_R
    1  SW_PVCCFA_EHV_FIVRA_CPU1_BOOT1      A  @S9S_MB_2U_LIB.S9S_MB_2U(SCH_1):SW_PVCCFA_EHV_FIVRA_CPU1_BOOT1

Q_RES  I242  PR1801  [Q_RES_0402LF-3.3,1%,1/16W,CHIPA]
    2  SW_PVCCFA_EHV_FIVRA_CPU1_BOOT2_      B  @S9S_MB_2U_LIB.S9S_MB_2U(SCH_1):SW_PVCCFA_EHV_FIVRA_CPU1_BOOT2_R
    1  SW_PVCCFA_EHV_FIVRA_CPU1_BOOT2      A  @S9S_MB_2U_LIB.S9S_MB_2U(SCH_1):SW_PVCCFA_EHV_FIVRA_CPU1_BOOT2

Q_RES  I43  PR1802  [Q_RES_0402LF-3.3,1%,1/16W,CHIPA]
    2  SW_PVCCFA_EHV_FIVRA_CPU1_BOOT3_      B  @S9S_MB_2U_LIB.S9S_MB_2U(SCH_1):SW_PVCCFA_EHV_FIVRA_CPU1_BOOT3_R
    1  SW_PVCCFA_EHV_FIVRA_CPU1_BOOT3      A  @S9S_MB_2U_LIB.S9S_MB_2U(SCH_1):SW_PVCCFA_EHV_FIVRA_CPU1_BOOT3

Q_RES  I34  PR1803  [Q_RES_0402LF-3.3,1%,1/16W,CHIPA]
    2  SW_PVCCFA_EHV_FIVRA_CPU1_BOOT4_      B  @S9S_MB_2U_LIB.S9S_MB_2U(SCH_1):SW_PVCCFA_EHV_FIVRA_CPU1_BOOT4_R
    1  SW_PVCCFA_EHV_FIVRA_CPU1_BOOT4      A  @S9S_MB_2U_LIB.S9S_MB_2U(SCH_1):SW_PVCCFA_EHV_FIVRA_CPU1_BOOT4

Q_RES  I19  PR1804  [Q_RES_0402LF-4.7,1%,1/16W,CHIPA]
    2  SW_PVCCD_HV_CPU1_BOOT1_R      B  @S9S_MB_2U_LIB.S9S_MB_2U(SCH_1):SW_PVCCD_HV_CPU1_BOOT1_R
    1  SW_PVCCD_HV_CPU1_BOOT1      A  @S9S_MB_2U_LIB.S9S_MB_2U(SCH_1):SW_PVCCD_HV_CPU1_BOOT1

Q_RES  I17  PR1805  [Q_RES_0402LF-0,5%,1/16W,CHIP,CA]
    2  PVCCD_HV_CPU1_VDD1      B  @S9S_MB_2U_LIB.S9S_MB_2U(SCH_1):PVCCD_HV_CPU1_VDD1
    1  PVCCD_HV_CPU1_NC1      A  @S9S_MB_2U_LIB.S9S_MB_2U(SCH_1):PVCCD_HV_CPU1_NC1

Q_RES  I3   PR1945  [Q_RES_0402LF-510K,5%,1/16W,CHIA]
    2  P5V_AUX_EN         B  @S9S_MB_2U_LIB.S9S_MB_2U(SCH_1):P5V_AUX_EN
    1  P12V_AUX           A  @S9S_MB_2U_LIB.S9S_MB_2U(SCH_1):P12V_AUX

Q_RES  I1   PR1948  [Q_RES_0402LF-75K,1%,1/16W,CHIPA]
    1  P5V_AUX_EN         A  @S9S_MB_2U_LIB.S9S_MB_2U(SCH_1):P5V_AUX_EN
    2  GND                B  @S9S_MB_2U_LIB.S9S_MB_2U(SCH_1):GND

Q_RES  I171  PR2220  [Q_RES_0402LF-60.4K,1%,1/16W,CHA]
    1  PVNN_MAIN_CPU1_MODE      A  @S9S_MB_2U_LIB.S9S_MB_2U(SCH_1):PVNN_MAIN_CPU1_MODE
    2  GND                B  @S9S_MB_2U_LIB.S9S_MB_2U(SCH_1):GND

Q_RES  I177  PR2222  [Q_RES_0402LF-9.09K,1%,1/16W,CHA]
    1  PVNN_MAIN_CPU1_CS      A  @S9S_MB_2U_LIB.S9S_MB_2U(SCH_1):PVNN_MAIN_CPU1_CS
    2  GND                B  @S9S_MB_2U_LIB.S9S_MB_2U(SCH_1):GND

Q_RES  I40  PR2390  [Q_RES_0402LF-0,5%,1/16W,CHIP,CA]
    2  PWRGD_PVNN_PCH_AUX      B  @S9S_MB_2U_LIB.S9S_MB_2U(SCH_1):PWRGD_PVNN_PCH_AUX
    1  PWRGD_P1V05_PCH_AUX_R      A  @S9S_MB_2U_LIB.S9S_MB_2U(SCH_1):PWRGD_P1V05_PCH_AUX_R

Q_RES  I325  PR2718  [Q_RES_0402LF-8.87K,1%,1/16W,EMA]
    1  PVCCD_HV_CPU0_LSET1      A  @S9S_MB_2U_LIB.S9S_MB_2U(SCH_1):PVCCD_HV_CPU0_LSET1
    2  GND                B  @S9S_MB_2U_LIB.S9S_MB_2U(SCH_1):GND

ISL69260IRAZT  I51  PU5    [ISL69260IRAZT-ISL69260IRAZ-T,SA]
   22  VSENSE_PVCCINFAON_CPU0_DN  RGND0  @S9S_MB_2U_LIB.S9S_MB_2U(SCH_1):VSENSE_PVCCINFAON_CPU0_DN
   31  VSENSE_PVCCFA_EHV_CPU0_DN  RGND1  @S9S_MB_2U_LIB.S9S_MB_2U(SCH_1):VSENSE_PVCCFA_EHV_CPU0_DN
   18  SVID_DIO_PVCCINFAON_CPU0_R  SVDATA  @S9S_MB_2U_LIB.S9S_MB_2U(SCH_1):SVID_DIO_PVCCINFAON_CPU0_R
   17  SVID_CLK_PVCCINFAON_CPU0_R  SVCLK  @S9S_MB_2U_LIB.S9S_MB_2U(SCH_1):SVID_CLK_PVCCINFAON_CPU0_R
   19  SVID_ALERT_PVCCINFAON_CPU0_R  NSVALERT  @S9S_MB_2U_LIB.S9S_MB_2U(SCH_1):SVID_ALERT_PVCCINFAON_CPU0_R
    9  SMB_DIO_PVCCINFAON_CPU0  PMSDA  @S9S_MB_2U_LIB.S9S_MB_2U(SCH_1):SMB_DIO_PVCCINFAON_CPU0
   10  SMB_CLK_PVCCINFAON_CPU0  PMSCL  @S9S_MB_2U_LIB.S9S_MB_2U(SCH_1):SMB_CLK_PVCCINFAON_CPU0
   21  SH_PVCCINFAON_CPU0_R  VSEN0  @S9S_MB_2U_LIB.S9S_MB_2U(SCH_1):SH_PVCCINFAON_CPU0_R
   32  SH_PVCCFA_EHV_CPU0_R  VSEN1  @S9S_MB_2U_LIB.S9S_MB_2U(SCH_1):SH_PVCCFA_EHV_CPU0_R
   12  PWRGD_PVCCINFAON_CPU0_R    PG0  @S9S_MB_2U_LIB.S9S_MB_2U(SCH_1):PWRGD_PVCCINFAON_CPU0_R
   16  PWRGD_PVCCFA_EHV_CPU0_R    PG1  @S9S_MB_2U_LIB.S9S_MB_2U(SCH_1):PWRGD_PVCCFA_EHV_CPU0_R
   33  PVCCINFAON_CPU0_VR_FAULT    CFP  @S9S_MB_2U_LIB.S9S_MB_2U(SCH_1):PVCCINFAON_CPU0_VR_FAULT
   40  PVCCINFAON_CPU0_VREF   VCCS  @S9S_MB_2U_LIB.S9S_MB_2U(SCH_1):PVCCINFAON_CPU0_VREF
   38  PVCCINFAON_CPU0_VIN_CSNIN  VINSEN  @S9S_MB_2U_LIB.S9S_MB_2U(SCH_1):PVCCINFAON_CPU0_VIN_CSNIN
   39  PVCCINFAON_CPU0_VCC    VCC  @S9S_MB_2U_LIB.S9S_MB_2U(SCH_1):PVCCINFAON_CPU0_VCC
   15  PVCCINFAON_CPU0_PIN_ALERT  NPINALERT||NPSYSCRIT  @S9S_MB_2U_LIB.S9S_MB_2U(SCH_1):PVCCINFAON_CPU0_PIN_ALERT
   13  PVCCINFAON_CPU0_EN_R    EN0  @S9S_MB_2U_LIB.S9S_MB_2U(SCH_1):PVCCINFAON_CPU0_EN_R
   37  PVCCINFAON_CPU0_CSPIN  IINSEN||VMON||VSYS  @S9S_MB_2U_LIB.S9S_MB_2U(SCH_1):PVCCINFAON_CPU0_CSPIN
   35  PVCCINFAON_CPU0_ATSEN  TEMP0  @S9S_MB_2U_LIB.S9S_MB_2U(SCH_1):PVCCINFAON_CPU0_ATSEN
    7  PVCCINFAON_CPU0_APWM2   PWM6  @S9S_MB_2U_LIB.S9S_MB_2U(SCH_1):PVCCINFAON_CPU0_APWM2
    8  PVCCINFAON_CPU0_APWM1   PWM7  @S9S_MB_2U_LIB.S9S_MB_2U(SCH_1):PVCCINFAON_CPU0_APWM1
   34  PVCCINFAON_CPU0_ADDR  ADDR_CFG  @S9S_MB_2U_LIB.S9S_MB_2U(SCH_1):PVCCINFAON_CPU0_ADDR
   24  PVCCINFAON_CPU0_ACSP2    CS6  @S9S_MB_2U_LIB.S9S_MB_2U(SCH_1):PVCCINFAON_CPU0_ACSP2
   23  PVCCINFAON_CPU0_ACSP1    CS7  @S9S_MB_2U_LIB.S9S_MB_2U(SCH_1):PVCCINFAON_CPU0_ACSP1
   20  PVCCFA_EHV_CPU0_EN_R    EN1  @S9S_MB_2U_LIB.S9S_MB_2U(SCH_1):PVCCFA_EHV_CPU0_EN_R
   36  PVCCFA_EHV_CPU0_BTSEN  TEMP1||ISYS  @S9S_MB_2U_LIB.S9S_MB_2U(SCH_1):PVCCFA_EHV_CPU0_BTSEN
    1  PVCCFA_EHV_CPU0_BPWM1   PWM0  @S9S_MB_2U_LIB.S9S_MB_2U(SCH_1):PVCCFA_EHV_CPU0_BPWM1
   30  PVCCFA_EHV_CPU0_BCSP1    CS0  @S9S_MB_2U_LIB.S9S_MB_2U(SCH_1):PVCCFA_EHV_CPU0_BCSP1
   11  NC             NPMALERT  NC
    2  NC              PWM1  NC
    3  NC              PWM2  NC
    4  NC              PWM3  NC
    5  NC              PWM4  NC
    6  NC              PWM5  NC
   29  NC               CS1  NC
   28  NC               CS2  NC
   27  NC               CS3  NC
   26  NC               CS4  NC
   25  NC               CS5  NC
   14  IRQ_CPU0_VRHOT_N  NVRHOT  @S9S_MB_2U_LIB.S9S_MB_2U(SCH_1):IRQ_CPU0_VRHOT_N
   TH  GND            TH_GND  @S9S_MB_2U_LIB.S9S_MB_2U(SCH_1):GND

ISL99390FRZTR5935  I64  PU6_P0_8  [ISL99390FRZTR5935-ISL99390FRZ-A]
  10_19  SW_PVCCIN_CPU0_SW8     SW  @S9S_MB_2U_LIB.S9S_MB_2U(SCH_1):SW_PVCCIN_CPU0_SW8
   32  SW_PVCCIN_CPU0_BOOTR8  PHASE  @S9S_MB_2U_LIB.S9S_MB_2U(SCH_1):SW_PVCCIN_CPU0_BOOTR8
   33  SW_PVCCIN_CPU0_BOOT8   BOOT  @S9S_MB_2U_LIB.S9S_MB_2U(SCH_1):SW_PVCCIN_CPU0_BOOT8
   30  SW_P12V_PVCCIN_CPU0_FLT   VIN2  @S9S_MB_2U_LIB.S9S_MB_2U(SCH_1):SW_P12V_PVCCIN_CPU0_FLT
  25_29  SW_P12V_PVCCIN_CPU0_FLT   VIN1  @S9S_MB_2U_LIB.S9S_MB_2U(SCH_1):SW_P12V_PVCCIN_CPU0_FLT
   39  PVCCIN_CPU0_VREF  REFIN  @S9S_MB_2U_LIB.S9S_MB_2U(SCH_1):PVCCIN_CPU0_VREF
    1  PVCCIN_CPU0_VOS8    VOS  @S9S_MB_2U_LIB.S9S_MB_2U(SCH_1):PVCCIN_CPU0_VOS8
    3  PVCCIN_CPU0_VDD8    VCC  @S9S_MB_2U_LIB.S9S_MB_2U(SCH_1):PVCCIN_CPU0_VDD8
   35  PVCCIN_CPU0_VDD8     EN  @S9S_MB_2U_LIB.S9S_MB_2U(SCH_1):PVCCIN_CPU0_VDD8
   34  PVCCIN_CPU0_PWM8    PWM  @S9S_MB_2U_LIB.S9S_MB_2U(SCH_1):PVCCIN_CPU0_PWM8
    4  PVCCIN_CPU0_PVCC   PVCC  @S9S_MB_2U_LIB.S9S_MB_2U(SCH_1):PVCCIN_CPU0_PVCC
   37  PVCCIN_CPU0_LSET8   LSET  @S9S_MB_2U_LIB.S9S_MB_2U(SCH_1):PVCCIN_CPU0_LSET8
   38  PVCCIN_CPU0_IMON8   IOUT  @S9S_MB_2U_LIB.S9S_MB_2U(SCH_1):PVCCIN_CPU0_IMON8
   36  PVCCIN_CPU0_ATSEN  TOUT_FLT  @S9S_MB_2U_LIB.S9S_MB_2U(SCH_1):PVCCIN_CPU0_ATSEN
   41  NC               GL2  NC
    6  NC               GL1  NC
   31  NC               DNC  NC
   40  GND            PGND3  @S9S_MB_2U_LIB.S9S_MB_2U(SCH_1):GND
  7_9-20_24  GND            PGND2  @S9S_MB_2U_LIB.S9S_MB_2U(SCH_1):GND
    5  GND            PGND1  @S9S_MB_2U_LIB.S9S_MB_2U(SCH_1):GND
    2  GND             AGND  @S9S_MB_2U_LIB.S9S_MB_2U(SCH_1):GND

ISL99390FRZTR5935  I20  PU7_P0_7  [ISL99390FRZTR5935-ISL99390FRZ-A]
  10_19  SW_PVCCIN_CPU0_SW7     SW  @S9S_MB_2U_LIB.S9S_MB_2U(SCH_1):SW_PVCCIN_CPU0_SW7
   32  SW_PVCCIN_CPU0_BOOTR7  PHASE  @S9S_MB_2U_LIB.S9S_MB_2U(SCH_1):SW_PVCCIN_CPU0_BOOTR7
   33  SW_PVCCIN_CPU0_BOOT7   BOOT  @S9S_MB_2U_LIB.S9S_MB_2U(SCH_1):SW_PVCCIN_CPU0_BOOT7
   30  SW_P12V_PVCCIN_CPU0_FLT   VIN2  @S9S_MB_2U_LIB.S9S_MB_2U(SCH_1):SW_P12V_PVCCIN_CPU0_FLT
  25_29  SW_P12V_PVCCIN_CPU0_FLT   VIN1  @S9S_MB_2U_LIB.S9S_MB_2U(SCH_1):SW_P12V_PVCCIN_CPU0_FLT
   39  PVCCIN_CPU0_VREF  REFIN  @S9S_MB_2U_LIB.S9S_MB_2U(SCH_1):PVCCIN_CPU0_VREF
    1  PVCCIN_CPU0_VOS7    VOS  @S9S_MB_2U_LIB.S9S_MB_2U(SCH_1):PVCCIN_CPU0_VOS7
    3  PVCCIN_CPU0_VDD7    VCC  @S9S_MB_2U_LIB.S9S_MB_2U(SCH_1):PVCCIN_CPU0_VDD7
   35  PVCCIN_CPU0_VDD7     EN  @S9S_MB_2U_LIB.S9S_MB_2U(SCH_1):PVCCIN_CPU0_VDD7
   34  PVCCIN_CPU0_PWM7    PWM  @S9S_MB_2U_LIB.S9S_MB_2U(SCH_1):PVCCIN_CPU0_PWM7
    4  PVCCIN_CPU0_PVCC   PVCC  @S9S_MB_2U_LIB.S9S_MB_2U(SCH_1):PVCCIN_CPU0_PVCC
   37  PVCCIN_CPU0_LSET7   LSET  @S9S_MB_2U_LIB.S9S_MB_2U(SCH_1):PVCCIN_CPU0_LSET7
   38  PVCCIN_CPU0_IMON7   IOUT  @S9S_MB_2U_LIB.S9S_MB_2U(SCH_1):PVCCIN_CPU0_IMON7
   36  PVCCIN_CPU0_ATSEN  TOUT_FLT  @S9S_MB_2U_LIB.S9S_MB_2U(SCH_1):PVCCIN_CPU0_ATSEN
   41  NC               GL2  NC
    6  NC               GL1  NC
   31  NC               DNC  NC
   40  GND            PGND3  @S9S_MB_2U_LIB.S9S_MB_2U(SCH_1):GND
  7_9-20_24  GND            PGND2  @S9S_MB_2U_LIB.S9S_MB_2U(SCH_1):GND
    5  GND            PGND1  @S9S_MB_2U_LIB.S9S_MB_2U(SCH_1):GND
    2  GND             AGND  @S9S_MB_2U_LIB.S9S_MB_2U(SCH_1):GND

ISL99390FRZTR5935  I62  PU8_P0_6  [ISL99390FRZTR5935-ISL99390FRZ-A]
  10_19  SW_PVCCIN_CPU0_SW6     SW  @S9S_MB_2U_LIB.S9S_MB_2U(SCH_1):SW_PVCCIN_CPU0_SW6
   32  SW_PVCCIN_CPU0_BOOTR6  PHASE  @S9S_MB_2U_LIB.S9S_MB_2U(SCH_1):SW_PVCCIN_CPU0_BOOTR6
   33  SW_PVCCIN_CPU0_BOOT6   BOOT  @S9S_MB_2U_LIB.S9S_MB_2U(SCH_1):SW_PVCCIN_CPU0_BOOT6
   30  SW_P12V_PVCCIN_CPU0_FLT   VIN2  @S9S_MB_2U_LIB.S9S_MB_2U(SCH_1):SW_P12V_PVCCIN_CPU0_FLT
  25_29  SW_P12V_PVCCIN_CPU0_FLT   VIN1  @S9S_MB_2U_LIB.S9S_MB_2U(SCH_1):SW_P12V_PVCCIN_CPU0_FLT
   39  PVCCIN_CPU0_VREF  REFIN  @S9S_MB_2U_LIB.S9S_MB_2U(SCH_1):PVCCIN_CPU0_VREF
    1  PVCCIN_CPU0_VOS6    VOS  @S9S_MB_2U_LIB.S9S_MB_2U(SCH_1):PVCCIN_CPU0_VOS6
    3  PVCCIN_CPU0_VDD6    VCC  @S9S_MB_2U_LIB.S9S_MB_2U(SCH_1):PVCCIN_CPU0_VDD6
   35  PVCCIN_CPU0_VDD6     EN  @S9S_MB_2U_LIB.S9S_MB_2U(SCH_1):PVCCIN_CPU0_VDD6
   34  PVCCIN_CPU0_PWM6    PWM  @S9S_MB_2U_LIB.S9S_MB_2U(SCH_1):PVCCIN_CPU0_PWM6
    4  PVCCIN_CPU0_PVCC   PVCC  @S9S_MB_2U_LIB.S9S_MB_2U(SCH_1):PVCCIN_CPU0_PVCC
   37  PVCCIN_CPU0_LSET6   LSET  @S9S_MB_2U_LIB.S9S_MB_2U(SCH_1):PVCCIN_CPU0_LSET6
   38  PVCCIN_CPU0_IMON6   IOUT  @S9S_MB_2U_LIB.S9S_MB_2U(SCH_1):PVCCIN_CPU0_IMON6
   36  PVCCIN_CPU0_ATSEN  TOUT_FLT  @S9S_MB_2U_LIB.S9S_MB_2U(SCH_1):PVCCIN_CPU0_ATSEN
   41  NC               GL2  NC
    6  NC               GL1  NC
   31  NC               DNC  NC
   40  GND            PGND3  @S9S_MB_2U_LIB.S9S_MB_2U(SCH_1):GND
  7_9-20_24  GND            PGND2  @S9S_MB_2U_LIB.S9S_MB_2U(SCH_1):GND
    5  GND            PGND1  @S9S_MB_2U_LIB.S9S_MB_2U(SCH_1):GND
    2  GND             AGND  @S9S_MB_2U_LIB.S9S_MB_2U(SCH_1):GND

NCP3284MNTXG  I23  PU9    [NCP3284MNTXG-NCP3284MNTXG,SMLFA]
  11_18  SW_P3V3_AUX_SW     SW  @S9S_MB_2U_LIB.S9S_MB_2U(SCH_1):SW_P3V3_AUX_SW
  20_24  SW_P3V3_AUX_FLT   PVIN  @S9S_MB_2U_LIB.S9S_MB_2U(SCH_1):SW_P3V3_AUX_FLT
   25  SW_P3V3_AUX_BOOTR  PHASE  @S9S_MB_2U_LIB.S9S_MB_2U(SCH_1):SW_P3V3_AUX_BOOTR
   26  SW_P3V3_AUX_BOOT   BOOT  @S9S_MB_2U_LIB.S9S_MB_2U(SCH_1):SW_P3V3_AUX_BOOT
   27  PWRGD_P5V_AUX     EN  @S9S_MB_2U_LIB.S9S_MB_2U(SCH_1):PWRGD_P5V_AUX
    2  PWRGD_P3V3_AUX  PGOOD  @S9S_MB_2U_LIB.S9S_MB_2U(SCH_1):PWRGD_P3V3_AUX
    3  P5V_AUX          VIN  @S9S_MB_2U_LIB.S9S_MB_2U(SCH_1):P5V_AUX
    5  P5V_AUX         VDRV  @S9S_MB_2U_LIB.S9S_MB_2U(SCH_1):P5V_AUX
   28  P3V3_AUX_VOS     VOS  @S9S_MB_2U_LIB.S9S_MB_2U(SCH_1):P3V3_AUX_VOS
    4  P3V3_AUX_VCC     VCC  @S9S_MB_2U_LIB.S9S_MB_2U(SCH_1):P3V3_AUX_VCC
   29  P3V3_AUX_SS       SS  @S9S_MB_2U_LIB.S9S_MB_2U(SCH_1):P3V3_AUX_SS
   36  P3V3_AUX_MODE  MODE||FSET  @S9S_MB_2U_LIB.S9S_MB_2U(SCH_1):P3V3_AUX_MODE
    1  P3V3_AUX_ILIM   ILIM  @S9S_MB_2U_LIB.S9S_MB_2U(SCH_1):P3V3_AUX_ILIM
   30  P3V3_AUX_FB       FB  @S9S_MB_2U_LIB.S9S_MB_2U(SCH_1):P3V3_AUX_FB
   37  NC               GL2  NC
    6  NC               GL1  NC
   34  NC               NC2  NC
   33  NC               NC1  NC
   35  NC             HICCUP#  NC
   31  GND            VSNS-  @S9S_MB_2U_LIB.S9S_MB_2U(SCH_1):GND
  7_10-19  GND             PGND  @S9S_MB_2U_LIB.S9S_MB_2U(SCH_1):GND
   32  GND             AGND  @S9S_MB_2U_LIB.S9S_MB_2U(SCH_1):GND

ISL99390FRZTR5935  I31  PU9_P0_5  [ISL99390FRZTR5935-ISL99390FRZ-A]
  10_19  SW_PVCCIN_CPU0_SW5     SW  @S9S_MB_2U_LIB.S9S_MB_2U(SCH_1):SW_PVCCIN_CPU0_SW5
   32  SW_PVCCIN_CPU0_BOOTR5  PHASE  @S9S_MB_2U_LIB.S9S_MB_2U(SCH_1):SW_PVCCIN_CPU0_BOOTR5
   33  SW_PVCCIN_CPU0_BOOT5   BOOT  @S9S_MB_2U_LIB.S9S_MB_2U(SCH_1):SW_PVCCIN_CPU0_BOOT5
   30  SW_P12V_PVCCIN_CPU0_FLT   VIN2  @S9S_MB_2U_LIB.S9S_MB_2U(SCH_1):SW_P12V_PVCCIN_CPU0_FLT
  25_29  SW_P12V_PVCCIN_CPU0_FLT   VIN1  @S9S_MB_2U_LIB.S9S_MB_2U(SCH_1):SW_P12V_PVCCIN_CPU0_FLT
   39  PVCCIN_CPU0_VREF  REFIN  @S9S_MB_2U_LIB.S9S_MB_2U(SCH_1):PVCCIN_CPU0_VREF
    1  PVCCIN_CPU0_VOS5    VOS  @S9S_MB_2U_LIB.S9S_MB_2U(SCH_1):PVCCIN_CPU0_VOS5
    3  PVCCIN_CPU0_VDD5    VCC  @S9S_MB_2U_LIB.S9S_MB_2U(SCH_1):PVCCIN_CPU0_VDD5
   35  PVCCIN_CPU0_VDD5     EN  @S9S_MB_2U_LIB.S9S_MB_2U(SCH_1):PVCCIN_CPU0_VDD5
   34  PVCCIN_CPU0_PWM5    PWM  @S9S_MB_2U_LIB.S9S_MB_2U(SCH_1):PVCCIN_CPU0_PWM5
    4  PVCCIN_CPU0_PVCC   PVCC  @S9S_MB_2U_LIB.S9S_MB_2U(SCH_1):PVCCIN_CPU0_PVCC
   37  PVCCIN_CPU0_LSET5   LSET  @S9S_MB_2U_LIB.S9S_MB_2U(SCH_1):PVCCIN_CPU0_LSET5
   38  PVCCIN_CPU0_IMON5   IOUT  @S9S_MB_2U_LIB.S9S_MB_2U(SCH_1):PVCCIN_CPU0_IMON5
   36  PVCCIN_CPU0_ATSEN  TOUT_FLT  @S9S_MB_2U_LIB.S9S_MB_2U(SCH_1):PVCCIN_CPU0_ATSEN
   41  NC               GL2  NC
    6  NC               GL1  NC
   31  NC               DNC  NC
   40  GND            PGND3  @S9S_MB_2U_LIB.S9S_MB_2U(SCH_1):GND
  7_9-20_24  GND            PGND2  @S9S_MB_2U_LIB.S9S_MB_2U(SCH_1):GND
    5  GND            PGND1  @S9S_MB_2U_LIB.S9S_MB_2U(SCH_1):GND
    2  GND             AGND  @S9S_MB_2U_LIB.S9S_MB_2U(SCH_1):GND

ISL99390FRZTR5935  I14  PU10_P0_4  [ISL99390FRZTR5935-ISL99390FRZ-A]
  10_19  SW_PVCCIN_CPU0_SW4     SW  @S9S_MB_2U_LIB.S9S_MB_2U(SCH_1):SW_PVCCIN_CPU0_SW4
   32  SW_PVCCIN_CPU0_BOOTR4  PHASE  @S9S_MB_2U_LIB.S9S_MB_2U(SCH_1):SW_PVCCIN_CPU0_BOOTR4
   33  SW_PVCCIN_CPU0_BOOT4   BOOT  @S9S_MB_2U_LIB.S9S_MB_2U(SCH_1):SW_PVCCIN_CPU0_BOOT4
   30  SW_P12V_PVCCIN_CPU0_FLT   VIN2  @S9S_MB_2U_LIB.S9S_MB_2U(SCH_1):SW_P12V_PVCCIN_CPU0_FLT
  25_29  SW_P12V_PVCCIN_CPU0_FLT   VIN1  @S9S_MB_2U_LIB.S9S_MB_2U(SCH_1):SW_P12V_PVCCIN_CPU0_FLT
   39  PVCCIN_CPU0_VREF  REFIN  @S9S_MB_2U_LIB.S9S_MB_2U(SCH_1):PVCCIN_CPU0_VREF
    1  PVCCIN_CPU0_VOS4    VOS  @S9S_MB_2U_LIB.S9S_MB_2U(SCH_1):PVCCIN_CPU0_VOS4
    3  PVCCIN_CPU0_VDD4    VCC  @S9S_MB_2U_LIB.S9S_MB_2U(SCH_1):PVCCIN_CPU0_VDD4
   35  PVCCIN_CPU0_VDD4     EN  @S9S_MB_2U_LIB.S9S_MB_2U(SCH_1):PVCCIN_CPU0_VDD4
   34  PVCCIN_CPU0_PWM4    PWM  @S9S_MB_2U_LIB.S9S_MB_2U(SCH_1):PVCCIN_CPU0_PWM4
    4  PVCCIN_CPU0_PVCC   PVCC  @S9S_MB_2U_LIB.S9S_MB_2U(SCH_1):PVCCIN_CPU0_PVCC
   37  PVCCIN_CPU0_LSET4   LSET  @S9S_MB_2U_LIB.S9S_MB_2U(SCH_1):PVCCIN_CPU0_LSET4
   38  PVCCIN_CPU0_IMON4   IOUT  @S9S_MB_2U_LIB.S9S_MB_2U(SCH_1):PVCCIN_CPU0_IMON4
   36  PVCCIN_CPU0_ATSEN  TOUT_FLT  @S9S_MB_2U_LIB.S9S_MB_2U(SCH_1):PVCCIN_CPU0_ATSEN
   41  NC               GL2  NC
    6  NC               GL1  NC
   31  NC               DNC  NC
   40  GND            PGND3  @S9S_MB_2U_LIB.S9S_MB_2U(SCH_1):GND
  7_9-20_24  GND            PGND2  @S9S_MB_2U_LIB.S9S_MB_2U(SCH_1):GND
    5  GND            PGND1  @S9S_MB_2U_LIB.S9S_MB_2U(SCH_1):GND
    2  GND             AGND  @S9S_MB_2U_LIB.S9S_MB_2U(SCH_1):GND

ISL99390FRZTR5935  I30  PU11_P0_3  [ISL99390FRZTR5935-ISL99390FRZ-A]
  10_19  SW_PVCCIN_CPU0_SW3     SW  @S9S_MB_2U_LIB.S9S_MB_2U(SCH_1):SW_PVCCIN_CPU0_SW3
   32  SW_PVCCIN_CPU0_BOOTR3  PHASE  @S9S_MB_2U_LIB.S9S_MB_2U(SCH_1):SW_PVCCIN_CPU0_BOOTR3
   33  SW_PVCCIN_CPU0_BOOT3   BOOT  @S9S_MB_2U_LIB.S9S_MB_2U(SCH_1):SW_PVCCIN_CPU0_BOOT3
   30  SW_P12V_PVCCIN_CPU0_FLT   VIN2  @S9S_MB_2U_LIB.S9S_MB_2U(SCH_1):SW_P12V_PVCCIN_CPU0_FLT
  25_29  SW_P12V_PVCCIN_CPU0_FLT   VIN1  @S9S_MB_2U_LIB.S9S_MB_2U(SCH_1):SW_P12V_PVCCIN_CPU0_FLT
   39  PVCCIN_CPU0_VREF  REFIN  @S9S_MB_2U_LIB.S9S_MB_2U(SCH_1):PVCCIN_CPU0_VREF
    1  PVCCIN_CPU0_VOS3    VOS  @S9S_MB_2U_LIB.S9S_MB_2U(SCH_1):PVCCIN_CPU0_VOS3
    3  PVCCIN_CPU0_VDD3    VCC  @S9S_MB_2U_LIB.S9S_MB_2U(SCH_1):PVCCIN_CPU0_VDD3
   35  PVCCIN_CPU0_VDD3     EN  @S9S_MB_2U_LIB.S9S_MB_2U(SCH_1):PVCCIN_CPU0_VDD3
   34  PVCCIN_CPU0_PWM3    PWM  @S9S_MB_2U_LIB.S9S_MB_2U(SCH_1):PVCCIN_CPU0_PWM3
    4  PVCCIN_CPU0_PVCC   PVCC  @S9S_MB_2U_LIB.S9S_MB_2U(SCH_1):PVCCIN_CPU0_PVCC
   37  PVCCIN_CPU0_LSET3   LSET  @S9S_MB_2U_LIB.S9S_MB_2U(SCH_1):PVCCIN_CPU0_LSET3
   38  PVCCIN_CPU0_IMON3   IOUT  @S9S_MB_2U_LIB.S9S_MB_2U(SCH_1):PVCCIN_CPU0_IMON3
   36  PVCCIN_CPU0_ATSEN  TOUT_FLT  @S9S_MB_2U_LIB.S9S_MB_2U(SCH_1):PVCCIN_CPU0_ATSEN
   41  NC               GL2  NC
    6  NC               GL1  NC
   31  NC               DNC  NC
   40  GND            PGND3  @S9S_MB_2U_LIB.S9S_MB_2U(SCH_1):GND
  7_9-20_24  GND            PGND2  @S9S_MB_2U_LIB.S9S_MB_2U(SCH_1):GND
    5  GND            PGND1  @S9S_MB_2U_LIB.S9S_MB_2U(SCH_1):GND
    2  GND             AGND  @S9S_MB_2U_LIB.S9S_MB_2U(SCH_1):GND

ISL99390FRZTR5935  I87  PU12_P0_2  [ISL99390FRZTR5935-ISL99390FRZ-A]
  10_19  SW_PVCCIN_CPU0_SW2     SW  @S9S_MB_2U_LIB.S9S_MB_2U(SCH_1):SW_PVCCIN_CPU0_SW2
   32  SW_PVCCIN_CPU0_BOOTR2  PHASE  @S9S_MB_2U_LIB.S9S_MB_2U(SCH_1):SW_PVCCIN_CPU0_BOOTR2
   33  SW_PVCCIN_CPU0_BOOT2   BOOT  @S9S_MB_2U_LIB.S9S_MB_2U(SCH_1):SW_PVCCIN_CPU0_BOOT2
   30  SW_P12V_PVCCIN_CPU0_FLT   VIN2  @S9S_MB_2U_LIB.S9S_MB_2U(SCH_1):SW_P12V_PVCCIN_CPU0_FLT
  25_29  SW_P12V_PVCCIN_CPU0_FLT   VIN1  @S9S_MB_2U_LIB.S9S_MB_2U(SCH_1):SW_P12V_PVCCIN_CPU0_FLT
   39  PVCCIN_CPU0_VREF  REFIN  @S9S_MB_2U_LIB.S9S_MB_2U(SCH_1):PVCCIN_CPU0_VREF
    1  PVCCIN_CPU0_VOS2    VOS  @S9S_MB_2U_LIB.S9S_MB_2U(SCH_1):PVCCIN_CPU0_VOS2
    3  PVCCIN_CPU0_VDD2    VCC  @S9S_MB_2U_LIB.S9S_MB_2U(SCH_1):PVCCIN_CPU0_VDD2
   35  PVCCIN_CPU0_VDD2     EN  @S9S_MB_2U_LIB.S9S_MB_2U(SCH_1):PVCCIN_CPU0_VDD2
   34  PVCCIN_CPU0_PWM2    PWM  @S9S_MB_2U_LIB.S9S_MB_2U(SCH_1):PVCCIN_CPU0_PWM2
    4  PVCCIN_CPU0_PVCC   PVCC  @S9S_MB_2U_LIB.S9S_MB_2U(SCH_1):PVCCIN_CPU0_PVCC
   37  PVCCIN_CPU0_LSET2   LSET  @S9S_MB_2U_LIB.S9S_MB_2U(SCH_1):PVCCIN_CPU0_LSET2
   38  PVCCIN_CPU0_IMON2   IOUT  @S9S_MB_2U_LIB.S9S_MB_2U(SCH_1):PVCCIN_CPU0_IMON2
   36  PVCCIN_CPU0_ATSEN  TOUT_FLT  @S9S_MB_2U_LIB.S9S_MB_2U(SCH_1):PVCCIN_CPU0_ATSEN
   41  NC               GL2  NC
    6  NC               GL1  NC
   31  NC               DNC  NC
   40  GND            PGND3  @S9S_MB_2U_LIB.S9S_MB_2U(SCH_1):GND
  7_9-20_24  GND            PGND2  @S9S_MB_2U_LIB.S9S_MB_2U(SCH_1):GND
    5  GND            PGND1  @S9S_MB_2U_LIB.S9S_MB_2U(SCH_1):GND
    2  GND             AGND  @S9S_MB_2U_LIB.S9S_MB_2U(SCH_1):GND

ISL99390FRZTR5935  I21  PU13_P0_1  [ISL99390FRZTR5935-ISL99390FRZ-A]
  10_19  SW_PVCCIN_CPU0_SW1     SW  @S9S_MB_2U_LIB.S9S_MB_2U(SCH_1):SW_PVCCIN_CPU0_SW1
   32  SW_PVCCIN_CPU0_BOOTR1  PHASE  @S9S_MB_2U_LIB.S9S_MB_2U(SCH_1):SW_PVCCIN_CPU0_BOOTR1
   33  SW_PVCCIN_CPU0_BOOT1   BOOT  @S9S_MB_2U_LIB.S9S_MB_2U(SCH_1):SW_PVCCIN_CPU0_BOOT1
   30  SW_P12V_PVCCIN_CPU0_FLT   VIN2  @S9S_MB_2U_LIB.S9S_MB_2U(SCH_1):SW_P12V_PVCCIN_CPU0_FLT
  25_29  SW_P12V_PVCCIN_CPU0_FLT   VIN1  @S9S_MB_2U_LIB.S9S_MB_2U(SCH_1):SW_P12V_PVCCIN_CPU0_FLT
   39  PVCCIN_CPU0_VREF  REFIN  @S9S_MB_2U_LIB.S9S_MB_2U(SCH_1):PVCCIN_CPU0_VREF
    1  PVCCIN_CPU0_VOS1    VOS  @S9S_MB_2U_LIB.S9S_MB_2U(SCH_1):PVCCIN_CPU0_VOS1
    3  PVCCIN_CPU0_VDD1    VCC  @S9S_MB_2U_LIB.S9S_MB_2U(SCH_1):PVCCIN_CPU0_VDD1
   35  PVCCIN_CPU0_VDD1     EN  @S9S_MB_2U_LIB.S9S_MB_2U(SCH_1):PVCCIN_CPU0_VDD1
   34  PVCCIN_CPU0_PWM1    PWM  @S9S_MB_2U_LIB.S9S_MB_2U(SCH_1):PVCCIN_CPU0_PWM1
    4  PVCCIN_CPU0_PVCC   PVCC  @S9S_MB_2U_LIB.S9S_MB_2U(SCH_1):PVCCIN_CPU0_PVCC
   37  PVCCIN_CPU0_LSET1   LSET  @S9S_MB_2U_LIB.S9S_MB_2U(SCH_1):PVCCIN_CPU0_LSET1
   38  PVCCIN_CPU0_IMON1   IOUT  @S9S_MB_2U_LIB.S9S_MB_2U(SCH_1):PVCCIN_CPU0_IMON1
   36  PVCCIN_CPU0_ATSEN  TOUT_FLT  @S9S_MB_2U_LIB.S9S_MB_2U(SCH_1):PVCCIN_CPU0_ATSEN
   41  NC               GL2  NC
    6  NC               GL1  NC
   31  NC               DNC  NC
   40  GND            PGND3  @S9S_MB_2U_LIB.S9S_MB_2U(SCH_1):GND
  7_9-20_24  GND            PGND2  @S9S_MB_2U_LIB.S9S_MB_2U(SCH_1):GND
    5  GND            PGND1  @S9S_MB_2U_LIB.S9S_MB_2U(SCH_1):GND
    2  GND             AGND  @S9S_MB_2U_LIB.S9S_MB_2U(SCH_1):GND

RAA229126GNPHA0  I48  PU14   [RAA229126GNPHA0-RAA229126GNP#HA]
   26  VSENSE_PVCCIN_CPU0_DN  RGND0  @S9S_MB_2U_LIB.S9S_MB_2U(SCH_1):VSENSE_PVCCIN_CPU0_DN
   39  VSENSE_PVCCFA_EHV_FIVRA_CPU0_DN  RGND1  @S9S_MB_2U_LIB.S9S_MB_2U(SCH_1):VSENSE_PVCCFA_EHV_FIVRA_CPU0_DN
   22  SVID_DIO_PVCCIN_CPU0_R  SVDATA  @S9S_MB_2U_LIB.S9S_MB_2U(SCH_1):SVID_DIO_PVCCIN_CPU0_R
   21  SVID_CLK_PVCCIN_CPU0_R  SVCLK  @S9S_MB_2U_LIB.S9S_MB_2U(SCH_1):SVID_CLK_PVCCIN_CPU0_R
   23  SVID_ALERT_PVCCIN_CPU0_R  NSVALERT  @S9S_MB_2U_LIB.S9S_MB_2U(SCH_1):SVID_ALERT_PVCCIN_CPU0_R
   13  SMB_DIO_PVCCIN_CPU0  PMSDA  @S9S_MB_2U_LIB.S9S_MB_2U(SCH_1):SMB_DIO_PVCCIN_CPU0
   14  SMB_CLK_PVCCIN_CPU0  PMSCL  @S9S_MB_2U_LIB.S9S_MB_2U(SCH_1):SMB_CLK_PVCCIN_CPU0
   25  SH_PVCCIN_CPU0_R  VSEN0  @S9S_MB_2U_LIB.S9S_MB_2U(SCH_1):SH_PVCCIN_CPU0_R
   40  SH_PVCCFA_EHV_FIVRA_CPU0_R  VSEN1  @S9S_MB_2U_LIB.S9S_MB_2U(SCH_1):SH_PVCCFA_EHV_FIVRA_CPU0_R
   16  PWRGD_PVCCIN_CPU0_R    PG0  @S9S_MB_2U_LIB.S9S_MB_2U(SCH_1):PWRGD_PVCCIN_CPU0_R
   20  PWRGD_PVCCFA_EHV_FIVRA_CPU0_R    PG1  @S9S_MB_2U_LIB.S9S_MB_2U(SCH_1):PWRGD_PVCCFA_EHV_FIVRA_CPU0_R
   41  PVCCIN_CPU0_VR_FAULT    CFP  @S9S_MB_2U_LIB.S9S_MB_2U(SCH_1):PVCCIN_CPU0_VR_FAULT
   48  PVCCIN_CPU0_VREF   VCCS  @S9S_MB_2U_LIB.S9S_MB_2U(SCH_1):PVCCIN_CPU0_VREF
   46  PVCCIN_CPU0_VIN_CSNIN  VINSEN||VSYS  @S9S_MB_2U_LIB.S9S_MB_2U(SCH_1):PVCCIN_CPU0_VIN_CSNIN
   47  PVCCIN_CPU0_VCC    VCC  @S9S_MB_2U_LIB.S9S_MB_2U(SCH_1):PVCCIN_CPU0_VCC
    5  PVCCIN_CPU0_PWM8   PWM4  @S9S_MB_2U_LIB.S9S_MB_2U(SCH_1):PVCCIN_CPU0_PWM8
    6  PVCCIN_CPU0_PWM7   PWM5  @S9S_MB_2U_LIB.S9S_MB_2U(SCH_1):PVCCIN_CPU0_PWM7
    7  PVCCIN_CPU0_PWM6   PWM6  @S9S_MB_2U_LIB.S9S_MB_2U(SCH_1):PVCCIN_CPU0_PWM6
    8  PVCCIN_CPU0_PWM5   PWM7  @S9S_MB_2U_LIB.S9S_MB_2U(SCH_1):PVCCIN_CPU0_PWM5
    9  PVCCIN_CPU0_PWM4   PWM8  @S9S_MB_2U_LIB.S9S_MB_2U(SCH_1):PVCCIN_CPU0_PWM4
   10  PVCCIN_CPU0_PWM3   PWM9  @S9S_MB_2U_LIB.S9S_MB_2U(SCH_1):PVCCIN_CPU0_PWM3
   11  PVCCIN_CPU0_PWM2  PWM10  @S9S_MB_2U_LIB.S9S_MB_2U(SCH_1):PVCCIN_CPU0_PWM2
   12  PVCCIN_CPU0_PWM1  PWM11  @S9S_MB_2U_LIB.S9S_MB_2U(SCH_1):PVCCIN_CPU0_PWM1
   19  PVCCIN_CPU0_PIN_ALERT  NPINALERT||NPSYS_CRIT  @S9S_MB_2U_LIB.S9S_MB_2U(SCH_1):PVCCIN_CPU0_PIN_ALERT
   44  PVCCIN_CPU0_ISYS_R  TEMP1||ISYS  @S9S_MB_2U_LIB.S9S_MB_2U(SCH_1):PVCCIN_CPU0_ISYS_R
   34  PVCCIN_CPU0_IMON8    CS4  @S9S_MB_2U_LIB.S9S_MB_2U(SCH_1):PVCCIN_CPU0_IMON8
   33  PVCCIN_CPU0_IMON7    CS5  @S9S_MB_2U_LIB.S9S_MB_2U(SCH_1):PVCCIN_CPU0_IMON7
   32  PVCCIN_CPU0_IMON6    CS6  @S9S_MB_2U_LIB.S9S_MB_2U(SCH_1):PVCCIN_CPU0_IMON6
   31  PVCCIN_CPU0_IMON5    CS7  @S9S_MB_2U_LIB.S9S_MB_2U(SCH_1):PVCCIN_CPU0_IMON5
   30  PVCCIN_CPU0_IMON4    CS8  @S9S_MB_2U_LIB.S9S_MB_2U(SCH_1):PVCCIN_CPU0_IMON4
   29  PVCCIN_CPU0_IMON3    CS9  @S9S_MB_2U_LIB.S9S_MB_2U(SCH_1):PVCCIN_CPU0_IMON3
   28  PVCCIN_CPU0_IMON2   CS10  @S9S_MB_2U_LIB.S9S_MB_2U(SCH_1):PVCCIN_CPU0_IMON2
   27  PVCCIN_CPU0_IMON1   CS11  @S9S_MB_2U_LIB.S9S_MB_2U(SCH_1):PVCCIN_CPU0_IMON1
   17  PVCCIN_CPU0_EN_R    EN0  @S9S_MB_2U_LIB.S9S_MB_2U(SCH_1):PVCCIN_CPU0_EN_R
   45  PVCCIN_CPU0_CSPIN  VMON||IINSEN||VSYS||ISYS  @S9S_MB_2U_LIB.S9S_MB_2U(SCH_1):PVCCIN_CPU0_CSPIN
   43  PVCCIN_CPU0_ATSEN  TEMP0  @S9S_MB_2U_LIB.S9S_MB_2U(SCH_1):PVCCIN_CPU0_ATSEN
   42  PVCCIN_CPU0_ADDR  ADDR_CFG  @S9S_MB_2U_LIB.S9S_MB_2U(SCH_1):PVCCIN_CPU0_ADDR
    2  PVCCFA_EHV_FIVRA_CPU0_PWM2   PWM1  @S9S_MB_2U_LIB.S9S_MB_2U(SCH_1):PVCCFA_EHV_FIVRA_CPU0_PWM2
    1  PVCCFA_EHV_FIVRA_CPU0_PWM1   PWM0  @S9S_MB_2U_LIB.S9S_MB_2U(SCH_1):PVCCFA_EHV_FIVRA_CPU0_PWM1
   37  PVCCFA_EHV_FIVRA_CPU0_IMON2    CS1  @S9S_MB_2U_LIB.S9S_MB_2U(SCH_1):PVCCFA_EHV_FIVRA_CPU0_IMON2
   38  PVCCFA_EHV_FIVRA_CPU0_IMON1    CS0  @S9S_MB_2U_LIB.S9S_MB_2U(SCH_1):PVCCFA_EHV_FIVRA_CPU0_IMON1
   24  PVCCFA_EHV_FIVRA_CPU0_EN_R    EN1  @S9S_MB_2U_LIB.S9S_MB_2U(SCH_1):PVCCFA_EHV_FIVRA_CPU0_EN_R
   15  NC             NPMALERT  NC
    4  NC              PWM3  NC
    3  NC              PWM2  NC
   35  NC               CS3  NC
   36  NC               CS2  NC
   18  IRQ_CPU0_VRHOT_N  NVRHOT  @S9S_MB_2U_LIB.S9S_MB_2U(SCH_1):IRQ_CPU0_VRHOT_N
   TH  GND            TH_GND  @S9S_MB_2U_LIB.S9S_MB_2U(SCH_1):GND

RAA2213404GNPHB0  I38  PU17   [RAA2213404GNPHB0-RAA2213404GNPA]
  8_12  SW_PVCCD_HV_CPU1_SW1     SW  @S9S_MB_2U_LIB.S9S_MB_2U(SCH_1):SW_PVCCD_HV_CPU1_SW1
   19  SW_PVCCD_HV_CPU1_BOOTR1  PHASE  @S9S_MB_2U_LIB.S9S_MB_2U(SCH_1):SW_PVCCD_HV_CPU1_BOOTR1
   20  SW_PVCCD_HV_CPU1_BOOT1   BOOT  @S9S_MB_2U_LIB.S9S_MB_2U(SCH_1):SW_PVCCD_HV_CPU1_BOOT1
  16_18-28  SW_P12V_PVCCINFAON_CPU1_FLT    VIN  @S9S_MB_2U_LIB.S9S_MB_2U(SCH_1):SW_P12V_PVCCINFAON_CPU1_FLT
   24  PVCCD_HV_CPU1_VREF  REFIN  @S9S_MB_2U_LIB.S9S_MB_2U(SCH_1):PVCCD_HV_CPU1_VREF
    4  PVCCD_HV_CPU1_VDD1    VCC  @S9S_MB_2U_LIB.S9S_MB_2U(SCH_1):PVCCD_HV_CPU1_VDD1
   22  PVCCD_HV_CPU1_VDD1    NC1  @S9S_MB_2U_LIB.S9S_MB_2U(SCH_1):PVCCD_HV_CPU1_VDD1
    3  PVCCD_HV_CPU1_NC1  LGCTRL  @S9S_MB_2U_LIB.S9S_MB_2U(SCH_1):PVCCD_HV_CPU1_NC1
    5  PVCCD_HV_CPU1_LSET1    GL1  @S9S_MB_2U_LIB.S9S_MB_2U(SCH_1):PVCCD_HV_CPU1_LSET1
    1  PVCCD_HV_CPU1_ATSEN   TMON  @S9S_MB_2U_LIB.S9S_MB_2U(SCH_1):PVCCD_HV_CPU1_ATSEN
   21  PVCCD_HV_CPU1_APWM1    PWM  @S9S_MB_2U_LIB.S9S_MB_2U(SCH_1):PVCCD_HV_CPU1_APWM1
   25  PVCCD_HV_CPU1_ACSP1   IMON  @S9S_MB_2U_LIB.S9S_MB_2U(SCH_1):PVCCD_HV_CPU1_ACSP1
   27  NC               GL2  NC
   26  GND             GND3  @S9S_MB_2U_LIB.S9S_MB_2U(SCH_1):GND
   23  GND             GND2  @S9S_MB_2U_LIB.S9S_MB_2U(SCH_1):GND
  6_7-13_15-29  GND             GND1  @S9S_MB_2U_LIB.S9S_MB_2U(SCH_1):GND
    2  GND            FAULT#  @S9S_MB_2U_LIB.S9S_MB_2U(SCH_1):GND

ISL69260IRAZT  I243  PU18   [ISL69260IRAZT-ISL69260IRAZ-T,SA]
   22  VSENSE_PVCCD_HV_CPU1_DN  RGND0  @S9S_MB_2U_LIB.S9S_MB_2U(SCH_1):VSENSE_PVCCD_HV_CPU1_DN
   18  SVID_DIO_PVCCD_HV_CPU1_R  SVDATA  @S9S_MB_2U_LIB.S9S_MB_2U(SCH_1):SVID_DIO_PVCCD_HV_CPU1_R
   17  SVID_CLK_PVCCD_HV_CPU1_R  SVCLK  @S9S_MB_2U_LIB.S9S_MB_2U(SCH_1):SVID_CLK_PVCCD_HV_CPU1_R
   19  SVID_ALERT_PVCCD_HV_CPU1_R  NSVALERT  @S9S_MB_2U_LIB.S9S_MB_2U(SCH_1):SVID_ALERT_PVCCD_HV_CPU1_R
    9  SMB_DIO_PVCCD_HV_CPU1  PMSDA  @S9S_MB_2U_LIB.S9S_MB_2U(SCH_1):SMB_DIO_PVCCD_HV_CPU1
   10  SMB_CLK_PVCCD_HV_CPU1  PMSCL  @S9S_MB_2U_LIB.S9S_MB_2U(SCH_1):SMB_CLK_PVCCD_HV_CPU1
   21  SH_PVCCD_HV_CPU1_R  VSEN0  @S9S_MB_2U_LIB.S9S_MB_2U(SCH_1):SH_PVCCD_HV_CPU1_R
   12  PWRGD_PVCCD_HV_CPU1_R    PG0  @S9S_MB_2U_LIB.S9S_MB_2U(SCH_1):PWRGD_PVCCD_HV_CPU1_R
   40  PVCCD_HV_CPU1_VREF   VCCS  @S9S_MB_2U_LIB.S9S_MB_2U(SCH_1):PVCCD_HV_CPU1_VREF
   39  PVCCD_HV_CPU1_VCC    VCC  @S9S_MB_2U_LIB.S9S_MB_2U(SCH_1):PVCCD_HV_CPU1_VCC
   15  PVCCD_HV_CPU1_PIN_ALT  NPINALERT||NPSYSCRIT  @S9S_MB_2U_LIB.S9S_MB_2U(SCH_1):PVCCD_HV_CPU1_PIN_ALT
   36  PVCCD_HV_CPU1_ISYS_R  TEMP1||ISYS  @S9S_MB_2U_LIB.S9S_MB_2U(SCH_1):PVCCD_HV_CPU1_ISYS_R
   37  PVCCD_HV_CPU1_ISENSE_P  IINSEN||VMON||VSYS  @S9S_MB_2U_LIB.S9S_MB_2U(SCH_1):PVCCD_HV_CPU1_ISENSE_P
   38  PVCCD_HV_CPU1_ISENSE_N  VINSEN  @S9S_MB_2U_LIB.S9S_MB_2U(SCH_1):PVCCD_HV_CPU1_ISENSE_N
   33  PVCCD_HV_CPU1_FAULT    CFP  @S9S_MB_2U_LIB.S9S_MB_2U(SCH_1):PVCCD_HV_CPU1_FAULT
   13  PVCCD_HV_CPU1_EN_R    EN0  @S9S_MB_2U_LIB.S9S_MB_2U(SCH_1):PVCCD_HV_CPU1_EN_R
   35  PVCCD_HV_CPU1_ATSEN  TEMP0  @S9S_MB_2U_LIB.S9S_MB_2U(SCH_1):PVCCD_HV_CPU1_ATSEN
    8  PVCCD_HV_CPU1_APWM1   PWM7  @S9S_MB_2U_LIB.S9S_MB_2U(SCH_1):PVCCD_HV_CPU1_APWM1
   34  PVCCD_HV_CPU1_ADDR  ADDR_CFG  @S9S_MB_2U_LIB.S9S_MB_2U(SCH_1):PVCCD_HV_CPU1_ADDR
   23  PVCCD_HV_CPU1_ACSP1    CS7  @S9S_MB_2U_LIB.S9S_MB_2U(SCH_1):PVCCD_HV_CPU1_ACSP1
   11  NC             NPMALERT  NC
   16  NC               PG1  NC
    1  NC              PWM0  NC
    2  NC              PWM1  NC
    3  NC              PWM2  NC
    4  NC              PWM3  NC
    5  NC              PWM4  NC
    6  NC              PWM5  NC
    7  NC              PWM6  NC
   30  NC               CS0  NC
   29  NC               CS1  NC
   28  NC               CS2  NC
   27  NC               CS3  NC
   26  NC               CS4  NC
   25  NC               CS5  NC
   24  NC               CS6  NC
   14  IRQ_PVCCD_CPU1_VRHOT_LVC3_N  NVRHOT  @S9S_MB_2U_LIB.S9S_MB_2U(SCH_1):IRQ_PVCCD_CPU1_VRHOT_LVC3_N
   32  GND            VSEN1  @S9S_MB_2U_LIB.S9S_MB_2U(SCH_1):GND
   TH  GND            TH_GND  @S9S_MB_2U_LIB.S9S_MB_2U(SCH_1):GND
   31  GND            RGND1  @S9S_MB_2U_LIB.S9S_MB_2U(SCH_1):GND
   20  GND              EN1  @S9S_MB_2U_LIB.S9S_MB_2U(SCH_1):GND

ISL69260IRAZT  I61  PU22   [ISL69260IRAZT-ISL69260IRAZ-T,SA]
   22  VSENSE_PVCCINFAON_CPU1_DN  RGND0  @S9S_MB_2U_LIB.S9S_MB_2U(SCH_1):VSENSE_PVCCINFAON_CPU1_DN
   31  VSENSE_PVCCFA_EHV_CPU1_DN  RGND1  @S9S_MB_2U_LIB.S9S_MB_2U(SCH_1):VSENSE_PVCCFA_EHV_CPU1_DN
   18  SVID_DIO_PVCCINFAON_CPU1_R  SVDATA  @S9S_MB_2U_LIB.S9S_MB_2U(SCH_1):SVID_DIO_PVCCINFAON_CPU1_R
   17  SVID_CLK_PVCCINFAON_CPU1_R  SVCLK  @S9S_MB_2U_LIB.S9S_MB_2U(SCH_1):SVID_CLK_PVCCINFAON_CPU1_R
   19  SVID_ALERT_PVCCINFAON_CPU1_R  NSVALERT  @S9S_MB_2U_LIB.S9S_MB_2U(SCH_1):SVID_ALERT_PVCCINFAON_CPU1_R
    9  SMB_DIO_PVCCINFAON_CPU1  PMSDA  @S9S_MB_2U_LIB.S9S_MB_2U(SCH_1):SMB_DIO_PVCCINFAON_CPU1
   10  SMB_CLK_PVCCINFAON_CPU1  PMSCL  @S9S_MB_2U_LIB.S9S_MB_2U(SCH_1):SMB_CLK_PVCCINFAON_CPU1
   21  SH_PVCCINFAON_CPU1_R  VSEN0  @S9S_MB_2U_LIB.S9S_MB_2U(SCH_1):SH_PVCCINFAON_CPU1_R
   32  SH_PVCCFA_EHV_CPU1_R  VSEN1  @S9S_MB_2U_LIB.S9S_MB_2U(SCH_1):SH_PVCCFA_EHV_CPU1_R
   12  PWRGD_PVCCINFAON_CPU1_R    PG0  @S9S_MB_2U_LIB.S9S_MB_2U(SCH_1):PWRGD_PVCCINFAON_CPU1_R
   16  PWRGD_PVCCFA_EHV_CPU1_R    PG1  @S9S_MB_2U_LIB.S9S_MB_2U(SCH_1):PWRGD_PVCCFA_EHV_CPU1_R
   33  PVCCINFAON_CPU1_VR_FAULT    CFP  @S9S_MB_2U_LIB.S9S_MB_2U(SCH_1):PVCCINFAON_CPU1_VR_FAULT
   40  PVCCINFAON_CPU1_VREF   VCCS  @S9S_MB_2U_LIB.S9S_MB_2U(SCH_1):PVCCINFAON_CPU1_VREF
   38  PVCCINFAON_CPU1_VIN_CSNIN  VINSEN  @S9S_MB_2U_LIB.S9S_MB_2U(SCH_1):PVCCINFAON_CPU1_VIN_CSNIN
   39  PVCCINFAON_CPU1_VCC    VCC  @S9S_MB_2U_LIB.S9S_MB_2U(SCH_1):PVCCINFAON_CPU1_VCC
   15  PVCCINFAON_CPU1_PIN_ALERT  NPINALERT||NPSYSCRIT  @S9S_MB_2U_LIB.S9S_MB_2U(SCH_1):PVCCINFAON_CPU1_PIN_ALERT
   13  PVCCINFAON_CPU1_EN_R    EN0  @S9S_MB_2U_LIB.S9S_MB_2U(SCH_1):PVCCINFAON_CPU1_EN_R
   37  PVCCINFAON_CPU1_CSPIN  IINSEN||VMON||VSYS  @S9S_MB_2U_LIB.S9S_MB_2U(SCH_1):PVCCINFAON_CPU1_CSPIN
   35  PVCCINFAON_CPU1_ATSEN  TEMP0  @S9S_MB_2U_LIB.S9S_MB_2U(SCH_1):PVCCINFAON_CPU1_ATSEN
    7  PVCCINFAON_CPU1_APWM2   PWM6  @S9S_MB_2U_LIB.S9S_MB_2U(SCH_1):PVCCINFAON_CPU1_APWM2
    8  PVCCINFAON_CPU1_APWM1   PWM7  @S9S_MB_2U_LIB.S9S_MB_2U(SCH_1):PVCCINFAON_CPU1_APWM1
   34  PVCCINFAON_CPU1_ADDR  ADDR_CFG  @S9S_MB_2U_LIB.S9S_MB_2U(SCH_1):PVCCINFAON_CPU1_ADDR
   24  PVCCINFAON_CPU1_ACSP2    CS6  @S9S_MB_2U_LIB.S9S_MB_2U(SCH_1):PVCCINFAON_CPU1_ACSP2
   23  PVCCINFAON_CPU1_ACSP1    CS7  @S9S_MB_2U_LIB.S9S_MB_2U(SCH_1):PVCCINFAON_CPU1_ACSP1
   20  PVCCFA_EHV_CPU1_EN_R    EN1  @S9S_MB_2U_LIB.S9S_MB_2U(SCH_1):PVCCFA_EHV_CPU1_EN_R
   36  PVCCFA_EHV_CPU1_BTSEN  TEMP1||ISYS  @S9S_MB_2U_LIB.S9S_MB_2U(SCH_1):PVCCFA_EHV_CPU1_BTSEN
    1  PVCCFA_EHV_CPU1_BPWM1   PWM0  @S9S_MB_2U_LIB.S9S_MB_2U(SCH_1):PVCCFA_EHV_CPU1_BPWM1
   30  PVCCFA_EHV_CPU1_BCSP1    CS0  @S9S_MB_2U_LIB.S9S_MB_2U(SCH_1):PVCCFA_EHV_CPU1_BCSP1
   11  NC             NPMALERT  NC
    2  NC              PWM1  NC
    3  NC              PWM2  NC
    4  NC              PWM3  NC
    5  NC              PWM4  NC
    6  NC              PWM5  NC
   29  NC               CS1  NC
   28  NC               CS2  NC
   27  NC               CS3  NC
   26  NC               CS4  NC
   25  NC               CS5  NC
   14  IRQ_CPU1_VRHOT_N  NVRHOT  @S9S_MB_2U_LIB.S9S_MB_2U(SCH_1):IRQ_CPU1_VRHOT_N
   TH  GND            TH_GND  @S9S_MB_2U_LIB.S9S_MB_2U(SCH_1):GND

ISL99390FRZTR5935  I9   PU23_P1_8  [ISL99390FRZTR5935-ISL99390FRZ-A]
  10_19  SW_PVCCIN_CPU1_SW8     SW  @S9S_MB_2U_LIB.S9S_MB_2U(SCH_1):SW_PVCCIN_CPU1_SW8
   32  SW_PVCCIN_CPU1_BOOTR8  PHASE  @S9S_MB_2U_LIB.S9S_MB_2U(SCH_1):SW_PVCCIN_CPU1_BOOTR8
   33  SW_PVCCIN_CPU1_BOOT8   BOOT  @S9S_MB_2U_LIB.S9S_MB_2U(SCH_1):SW_PVCCIN_CPU1_BOOT8
   30  SW_P12V_PVCCIN_CPU1_FLT   VIN2  @S9S_MB_2U_LIB.S9S_MB_2U(SCH_1):SW_P12V_PVCCIN_CPU1_FLT
  25_29  SW_P12V_PVCCIN_CPU1_FLT   VIN1  @S9S_MB_2U_LIB.S9S_MB_2U(SCH_1):SW_P12V_PVCCIN_CPU1_FLT
   39  PVCCIN_CPU1_VREF  REFIN  @S9S_MB_2U_LIB.S9S_MB_2U(SCH_1):PVCCIN_CPU1_VREF
    1  PVCCIN_CPU1_VOS8    VOS  @S9S_MB_2U_LIB.S9S_MB_2U(SCH_1):PVCCIN_CPU1_VOS8
    3  PVCCIN_CPU1_VDD8    VCC  @S9S_MB_2U_LIB.S9S_MB_2U(SCH_1):PVCCIN_CPU1_VDD8
   35  PVCCIN_CPU1_VDD8     EN  @S9S_MB_2U_LIB.S9S_MB_2U(SCH_1):PVCCIN_CPU1_VDD8
   34  PVCCIN_CPU1_PWM8    PWM  @S9S_MB_2U_LIB.S9S_MB_2U(SCH_1):PVCCIN_CPU1_PWM8
    4  PVCCIN_CPU1_PVCC   PVCC  @S9S_MB_2U_LIB.S9S_MB_2U(SCH_1):PVCCIN_CPU1_PVCC
   37  PVCCIN_CPU1_LSET8   LSET  @S9S_MB_2U_LIB.S9S_MB_2U(SCH_1):PVCCIN_CPU1_LSET8
   38  PVCCIN_CPU1_IMON8   IOUT  @S9S_MB_2U_LIB.S9S_MB_2U(SCH_1):PVCCIN_CPU1_IMON8
   36  PVCCIN_CPU1_ATSEN  TOUT_FLT  @S9S_MB_2U_LIB.S9S_MB_2U(SCH_1):PVCCIN_CPU1_ATSEN
   41  NC               GL2  NC
    6  NC               GL1  NC
   31  NC               DNC  NC
   40  GND            PGND3  @S9S_MB_2U_LIB.S9S_MB_2U(SCH_1):GND
  7_9-20_24  GND            PGND2  @S9S_MB_2U_LIB.S9S_MB_2U(SCH_1):GND
    5  GND            PGND1  @S9S_MB_2U_LIB.S9S_MB_2U(SCH_1):GND
    2  GND             AGND  @S9S_MB_2U_LIB.S9S_MB_2U(SCH_1):GND

ISL99390FRZTR5935  I37  PU24_P1_7  [ISL99390FRZTR5935-ISL99390FRZ-A]
  10_19  SW_PVCCIN_CPU1_SW7     SW  @S9S_MB_2U_LIB.S9S_MB_2U(SCH_1):SW_PVCCIN_CPU1_SW7
   32  SW_PVCCIN_CPU1_BOOTR7  PHASE  @S9S_MB_2U_LIB.S9S_MB_2U(SCH_1):SW_PVCCIN_CPU1_BOOTR7
   33  SW_PVCCIN_CPU1_BOOT7   BOOT  @S9S_MB_2U_LIB.S9S_MB_2U(SCH_1):SW_PVCCIN_CPU1_BOOT7
   30  SW_P12V_PVCCIN_CPU1_FLT   VIN2  @S9S_MB_2U_LIB.S9S_MB_2U(SCH_1):SW_P12V_PVCCIN_CPU1_FLT
  25_29  SW_P12V_PVCCIN_CPU1_FLT   VIN1  @S9S_MB_2U_LIB.S9S_MB_2U(SCH_1):SW_P12V_PVCCIN_CPU1_FLT
   39  PVCCIN_CPU1_VREF  REFIN  @S9S_MB_2U_LIB.S9S_MB_2U(SCH_1):PVCCIN_CPU1_VREF
    1  PVCCIN_CPU1_VOS7    VOS  @S9S_MB_2U_LIB.S9S_MB_2U(SCH_1):PVCCIN_CPU1_VOS7
    3  PVCCIN_CPU1_VDD7    VCC  @S9S_MB_2U_LIB.S9S_MB_2U(SCH_1):PVCCIN_CPU1_VDD7
   35  PVCCIN_CPU1_VDD7     EN  @S9S_MB_2U_LIB.S9S_MB_2U(SCH_1):PVCCIN_CPU1_VDD7
   34  PVCCIN_CPU1_PWM7    PWM  @S9S_MB_2U_LIB.S9S_MB_2U(SCH_1):PVCCIN_CPU1_PWM7
    4  PVCCIN_CPU1_PVCC   PVCC  @S9S_MB_2U_LIB.S9S_MB_2U(SCH_1):PVCCIN_CPU1_PVCC
   37  PVCCIN_CPU1_LSET7   LSET  @S9S_MB_2U_LIB.S9S_MB_2U(SCH_1):PVCCIN_CPU1_LSET7
   38  PVCCIN_CPU1_IMON7   IOUT  @S9S_MB_2U_LIB.S9S_MB_2U(SCH_1):PVCCIN_CPU1_IMON7
   36  PVCCIN_CPU1_ATSEN  TOUT_FLT  @S9S_MB_2U_LIB.S9S_MB_2U(SCH_1):PVCCIN_CPU1_ATSEN
   41  NC               GL2  NC
    6  NC               GL1  NC
   31  NC               DNC  NC
   40  GND            PGND3  @S9S_MB_2U_LIB.S9S_MB_2U(SCH_1):GND
  7_9-20_24  GND            PGND2  @S9S_MB_2U_LIB.S9S_MB_2U(SCH_1):GND
    5  GND            PGND1  @S9S_MB_2U_LIB.S9S_MB_2U(SCH_1):GND
    2  GND             AGND  @S9S_MB_2U_LIB.S9S_MB_2U(SCH_1):GND

ISL99390FRZTR5935  I23  PU25_P1_6  [ISL99390FRZTR5935-ISL99390FRZ-A]
  10_19  SW_PVCCIN_CPU1_SW6     SW  @S9S_MB_2U_LIB.S9S_MB_2U(SCH_1):SW_PVCCIN_CPU1_SW6
   32  SW_PVCCIN_CPU1_BOOTR6  PHASE  @S9S_MB_2U_LIB.S9S_MB_2U(SCH_1):SW_PVCCIN_CPU1_BOOTR6
   33  SW_PVCCIN_CPU1_BOOT6   BOOT  @S9S_MB_2U_LIB.S9S_MB_2U(SCH_1):SW_PVCCIN_CPU1_BOOT6
   30  SW_P12V_PVCCIN_CPU1_FLT   VIN2  @S9S_MB_2U_LIB.S9S_MB_2U(SCH_1):SW_P12V_PVCCIN_CPU1_FLT
  25_29  SW_P12V_PVCCIN_CPU1_FLT   VIN1  @S9S_MB_2U_LIB.S9S_MB_2U(SCH_1):SW_P12V_PVCCIN_CPU1_FLT
   39  PVCCIN_CPU1_VREF  REFIN  @S9S_MB_2U_LIB.S9S_MB_2U(SCH_1):PVCCIN_CPU1_VREF
    1  PVCCIN_CPU1_VOS6    VOS  @S9S_MB_2U_LIB.S9S_MB_2U(SCH_1):PVCCIN_CPU1_VOS6
    3  PVCCIN_CPU1_VDD6    VCC  @S9S_MB_2U_LIB.S9S_MB_2U(SCH_1):PVCCIN_CPU1_VDD6
   35  PVCCIN_CPU1_VDD6     EN  @S9S_MB_2U_LIB.S9S_MB_2U(SCH_1):PVCCIN_CPU1_VDD6
   34  PVCCIN_CPU1_PWM6    PWM  @S9S_MB_2U_LIB.S9S_MB_2U(SCH_1):PVCCIN_CPU1_PWM6
    4  PVCCIN_CPU1_PVCC   PVCC  @S9S_MB_2U_LIB.S9S_MB_2U(SCH_1):PVCCIN_CPU1_PVCC
   37  PVCCIN_CPU1_LSET6   LSET  @S9S_MB_2U_LIB.S9S_MB_2U(SCH_1):PVCCIN_CPU1_LSET6
   38  PVCCIN_CPU1_IMON6   IOUT  @S9S_MB_2U_LIB.S9S_MB_2U(SCH_1):PVCCIN_CPU1_IMON6
   36  PVCCIN_CPU1_ATSEN  TOUT_FLT  @S9S_MB_2U_LIB.S9S_MB_2U(SCH_1):PVCCIN_CPU1_ATSEN
   41  NC               GL2  NC
    6  NC               GL1  NC
   31  NC               DNC  NC
   40  GND            PGND3  @S9S_MB_2U_LIB.S9S_MB_2U(SCH_1):GND
  7_9-20_24  GND            PGND2  @S9S_MB_2U_LIB.S9S_MB_2U(SCH_1):GND
    5  GND            PGND1  @S9S_MB_2U_LIB.S9S_MB_2U(SCH_1):GND
    2  GND             AGND  @S9S_MB_2U_LIB.S9S_MB_2U(SCH_1):GND

ISL99390FRZTR5935  I32  PU26_P1_5  [ISL99390FRZTR5935-ISL99390FRZ-A]
  10_19  SW_PVCCIN_CPU1_SW5     SW  @S9S_MB_2U_LIB.S9S_MB_2U(SCH_1):SW_PVCCIN_CPU1_SW5
   32  SW_PVCCIN_CPU1_BOOTR5  PHASE  @S9S_MB_2U_LIB.S9S_MB_2U(SCH_1):SW_PVCCIN_CPU1_BOOTR5
   33  SW_PVCCIN_CPU1_BOOT5   BOOT  @S9S_MB_2U_LIB.S9S_MB_2U(SCH_1):SW_PVCCIN_CPU1_BOOT5
   30  SW_P12V_PVCCIN_CPU1_FLT   VIN2  @S9S_MB_2U_LIB.S9S_MB_2U(SCH_1):SW_P12V_PVCCIN_CPU1_FLT
  25_29  SW_P12V_PVCCIN_CPU1_FLT   VIN1  @S9S_MB_2U_LIB.S9S_MB_2U(SCH_1):SW_P12V_PVCCIN_CPU1_FLT
   39  PVCCIN_CPU1_VREF  REFIN  @S9S_MB_2U_LIB.S9S_MB_2U(SCH_1):PVCCIN_CPU1_VREF
    1  PVCCIN_CPU1_VOS5    VOS  @S9S_MB_2U_LIB.S9S_MB_2U(SCH_1):PVCCIN_CPU1_VOS5
    3  PVCCIN_CPU1_VDD5    VCC  @S9S_MB_2U_LIB.S9S_MB_2U(SCH_1):PVCCIN_CPU1_VDD5
   35  PVCCIN_CPU1_VDD5     EN  @S9S_MB_2U_LIB.S9S_MB_2U(SCH_1):PVCCIN_CPU1_VDD5
   34  PVCCIN_CPU1_PWM5    PWM  @S9S_MB_2U_LIB.S9S_MB_2U(SCH_1):PVCCIN_CPU1_PWM5
    4  PVCCIN_CPU1_PVCC   PVCC  @S9S_MB_2U_LIB.S9S_MB_2U(SCH_1):PVCCIN_CPU1_PVCC
   37  PVCCIN_CPU1_LSET5   LSET  @S9S_MB_2U_LIB.S9S_MB_2U(SCH_1):PVCCIN_CPU1_LSET5
   38  PVCCIN_CPU1_IMON5   IOUT  @S9S_MB_2U_LIB.S9S_MB_2U(SCH_1):PVCCIN_CPU1_IMON5
   36  PVCCIN_CPU1_ATSEN  TOUT_FLT  @S9S_MB_2U_LIB.S9S_MB_2U(SCH_1):PVCCIN_CPU1_ATSEN
   41  NC               GL2  NC
    6  NC               GL1  NC
   31  NC               DNC  NC
   40  GND            PGND3  @S9S_MB_2U_LIB.S9S_MB_2U(SCH_1):GND
  7_9-20_24  GND            PGND2  @S9S_MB_2U_LIB.S9S_MB_2U(SCH_1):GND
    5  GND            PGND1  @S9S_MB_2U_LIB.S9S_MB_2U(SCH_1):GND
    2  GND             AGND  @S9S_MB_2U_LIB.S9S_MB_2U(SCH_1):GND

ISL99390FRZTR5935  I9   PU27_P1_4  [ISL99390FRZTR5935-ISL99390FRZ-A]
  10_19  SW_PVCCIN_CPU1_SW4     SW  @S9S_MB_2U_LIB.S9S_MB_2U(SCH_1):SW_PVCCIN_CPU1_SW4
   32  SW_PVCCIN_CPU1_BOOTR4  PHASE  @S9S_MB_2U_LIB.S9S_MB_2U(SCH_1):SW_PVCCIN_CPU1_BOOTR4
   33  SW_PVCCIN_CPU1_BOOT4   BOOT  @S9S_MB_2U_LIB.S9S_MB_2U(SCH_1):SW_PVCCIN_CPU1_BOOT4
   30  SW_P12V_PVCCIN_CPU1_FLT   VIN2  @S9S_MB_2U_LIB.S9S_MB_2U(SCH_1):SW_P12V_PVCCIN_CPU1_FLT
  25_29  SW_P12V_PVCCIN_CPU1_FLT   VIN1  @S9S_MB_2U_LIB.S9S_MB_2U(SCH_1):SW_P12V_PVCCIN_CPU1_FLT
   39  PVCCIN_CPU1_VREF  REFIN  @S9S_MB_2U_LIB.S9S_MB_2U(SCH_1):PVCCIN_CPU1_VREF
    1  PVCCIN_CPU1_VOS4    VOS  @S9S_MB_2U_LIB.S9S_MB_2U(SCH_1):PVCCIN_CPU1_VOS4
    3  PVCCIN_CPU1_VDD4    VCC  @S9S_MB_2U_LIB.S9S_MB_2U(SCH_1):PVCCIN_CPU1_VDD4
   35  PVCCIN_CPU1_VDD4     EN  @S9S_MB_2U_LIB.S9S_MB_2U(SCH_1):PVCCIN_CPU1_VDD4
   34  PVCCIN_CPU1_PWM4    PWM  @S9S_MB_2U_LIB.S9S_MB_2U(SCH_1):PVCCIN_CPU1_PWM4
    4  PVCCIN_CPU1_PVCC   PVCC  @S9S_MB_2U_LIB.S9S_MB_2U(SCH_1):PVCCIN_CPU1_PVCC
   37  PVCCIN_CPU1_LSET4   LSET  @S9S_MB_2U_LIB.S9S_MB_2U(SCH_1):PVCCIN_CPU1_LSET4
   38  PVCCIN_CPU1_IMON4   IOUT  @S9S_MB_2U_LIB.S9S_MB_2U(SCH_1):PVCCIN_CPU1_IMON4
   36  PVCCIN_CPU1_ATSEN  TOUT_FLT  @S9S_MB_2U_LIB.S9S_MB_2U(SCH_1):PVCCIN_CPU1_ATSEN
   41  NC               GL2  NC
    6  NC               GL1  NC
   31  NC               DNC  NC
   40  GND            PGND3  @S9S_MB_2U_LIB.S9S_MB_2U(SCH_1):GND
  7_9-20_24  GND            PGND2  @S9S_MB_2U_LIB.S9S_MB_2U(SCH_1):GND
    5  GND            PGND1  @S9S_MB_2U_LIB.S9S_MB_2U(SCH_1):GND
    2  GND             AGND  @S9S_MB_2U_LIB.S9S_MB_2U(SCH_1):GND

ISL99390FRZTR5935  I18  PU28_P1_3  [ISL99390FRZTR5935-ISL99390FRZ-A]
  10_19  SW_PVCCIN_CPU1_SW3     SW  @S9S_MB_2U_LIB.S9S_MB_2U(SCH_1):SW_PVCCIN_CPU1_SW3
   32  SW_PVCCIN_CPU1_BOOTR3  PHASE  @S9S_MB_2U_LIB.S9S_MB_2U(SCH_1):SW_PVCCIN_CPU1_BOOTR3
   33  SW_PVCCIN_CPU1_BOOT3   BOOT  @S9S_MB_2U_LIB.S9S_MB_2U(SCH_1):SW_PVCCIN_CPU1_BOOT3
   30  SW_P12V_PVCCIN_CPU1_FLT   VIN2  @S9S_MB_2U_LIB.S9S_MB_2U(SCH_1):SW_P12V_PVCCIN_CPU1_FLT
  25_29  SW_P12V_PVCCIN_CPU1_FLT   VIN1  @S9S_MB_2U_LIB.S9S_MB_2U(SCH_1):SW_P12V_PVCCIN_CPU1_FLT
   39  PVCCIN_CPU1_VREF  REFIN  @S9S_MB_2U_LIB.S9S_MB_2U(SCH_1):PVCCIN_CPU1_VREF
    1  PVCCIN_CPU1_VOS3    VOS  @S9S_MB_2U_LIB.S9S_MB_2U(SCH_1):PVCCIN_CPU1_VOS3
    3  PVCCIN_CPU1_VDD3    VCC  @S9S_MB_2U_LIB.S9S_MB_2U(SCH_1):PVCCIN_CPU1_VDD3
   35  PVCCIN_CPU1_VDD3     EN  @S9S_MB_2U_LIB.S9S_MB_2U(SCH_1):PVCCIN_CPU1_VDD3
   34  PVCCIN_CPU1_PWM3    PWM  @S9S_MB_2U_LIB.S9S_MB_2U(SCH_1):PVCCIN_CPU1_PWM3
    4  PVCCIN_CPU1_PVCC   PVCC  @S9S_MB_2U_LIB.S9S_MB_2U(SCH_1):PVCCIN_CPU1_PVCC
   37  PVCCIN_CPU1_LSET3   LSET  @S9S_MB_2U_LIB.S9S_MB_2U(SCH_1):PVCCIN_CPU1_LSET3
   38  PVCCIN_CPU1_IMON3   IOUT  @S9S_MB_2U_LIB.S9S_MB_2U(SCH_1):PVCCIN_CPU1_IMON3
   36  PVCCIN_CPU1_ATSEN  TOUT_FLT  @S9S_MB_2U_LIB.S9S_MB_2U(SCH_1):PVCCIN_CPU1_ATSEN
   41  NC               GL2  NC
    6  NC               GL1  NC
   31  NC               DNC  NC
   40  GND            PGND3  @S9S_MB_2U_LIB.S9S_MB_2U(SCH_1):GND
  7_9-20_24  GND            PGND2  @S9S_MB_2U_LIB.S9S_MB_2U(SCH_1):GND
    5  GND            PGND1  @S9S_MB_2U_LIB.S9S_MB_2U(SCH_1):GND
    2  GND             AGND  @S9S_MB_2U_LIB.S9S_MB_2U(SCH_1):GND

RAA229126GNPHA0  I211  PU29   [RAA229126GNPHA0-RAA229126GNP#HA]
   26  VSENSE_PVCCIN_CPU1_DN  RGND0  @S9S_MB_2U_LIB.S9S_MB_2U(SCH_1):VSENSE_PVCCIN_CPU1_DN
   39  VSENSE_PVCCFA_EHV_FIVRA_CPU1_DN  RGND1  @S9S_MB_2U_LIB.S9S_MB_2U(SCH_1):VSENSE_PVCCFA_EHV_FIVRA_CPU1_DN
   22  SVID_DIO_PVCCIN_CPU1_R  SVDATA  @S9S_MB_2U_LIB.S9S_MB_2U(SCH_1):SVID_DIO_PVCCIN_CPU1_R
   21  SVID_CLK_PVCCIN_CPU1_R  SVCLK  @S9S_MB_2U_LIB.S9S_MB_2U(SCH_1):SVID_CLK_PVCCIN_CPU1_R
   23  SVID_ALERT_PVCCIN_CPU1_R  NSVALERT  @S9S_MB_2U_LIB.S9S_MB_2U(SCH_1):SVID_ALERT_PVCCIN_CPU1_R
   13  SMB_DIO_PVCCIN_CPU1  PMSDA  @S9S_MB_2U_LIB.S9S_MB_2U(SCH_1):SMB_DIO_PVCCIN_CPU1
   14  SMB_CLK_PVCCIN_CPU1  PMSCL  @S9S_MB_2U_LIB.S9S_MB_2U(SCH_1):SMB_CLK_PVCCIN_CPU1
   25  SH_PVCCIN_CPU1_R  VSEN0  @S9S_MB_2U_LIB.S9S_MB_2U(SCH_1):SH_PVCCIN_CPU1_R
   40  SH_PVCCFA_EHV_FIVRA_CPU1_R  VSEN1  @S9S_MB_2U_LIB.S9S_MB_2U(SCH_1):SH_PVCCFA_EHV_FIVRA_CPU1_R
   16  PWRGD_PVCCIN_CPU1_R    PG0  @S9S_MB_2U_LIB.S9S_MB_2U(SCH_1):PWRGD_PVCCIN_CPU1_R
   20  PWRGD_PVCCFA_EHV_FIVRA_CPU1_R    PG1  @S9S_MB_2U_LIB.S9S_MB_2U(SCH_1):PWRGD_PVCCFA_EHV_FIVRA_CPU1_R
   41  PVCCIN_CPU1_VR_FAULT    CFP  @S9S_MB_2U_LIB.S9S_MB_2U(SCH_1):PVCCIN_CPU1_VR_FAULT
   48  PVCCIN_CPU1_VREF   VCCS  @S9S_MB_2U_LIB.S9S_MB_2U(SCH_1):PVCCIN_CPU1_VREF
   46  PVCCIN_CPU1_VIN_CSNIN  VINSEN||VSYS  @S9S_MB_2U_LIB.S9S_MB_2U(SCH_1):PVCCIN_CPU1_VIN_CSNIN
   47  PVCCIN_CPU1_VCC    VCC  @S9S_MB_2U_LIB.S9S_MB_2U(SCH_1):PVCCIN_CPU1_VCC
    5  PVCCIN_CPU1_PWM8   PWM4  @S9S_MB_2U_LIB.S9S_MB_2U(SCH_1):PVCCIN_CPU1_PWM8
    6  PVCCIN_CPU1_PWM7   PWM5  @S9S_MB_2U_LIB.S9S_MB_2U(SCH_1):PVCCIN_CPU1_PWM7
    7  PVCCIN_CPU1_PWM6   PWM6  @S9S_MB_2U_LIB.S9S_MB_2U(SCH_1):PVCCIN_CPU1_PWM6
    8  PVCCIN_CPU1_PWM5   PWM7  @S9S_MB_2U_LIB.S9S_MB_2U(SCH_1):PVCCIN_CPU1_PWM5
    9  PVCCIN_CPU1_PWM4   PWM8  @S9S_MB_2U_LIB.S9S_MB_2U(SCH_1):PVCCIN_CPU1_PWM4
   10  PVCCIN_CPU1_PWM3   PWM9  @S9S_MB_2U_LIB.S9S_MB_2U(SCH_1):PVCCIN_CPU1_PWM3
   11  PVCCIN_CPU1_PWM2  PWM10  @S9S_MB_2U_LIB.S9S_MB_2U(SCH_1):PVCCIN_CPU1_PWM2
   12  PVCCIN_CPU1_PWM1  PWM11  @S9S_MB_2U_LIB.S9S_MB_2U(SCH_1):PVCCIN_CPU1_PWM1
   19  PVCCIN_CPU1_PIN_ALERT  NPINALERT||NPSYS_CRIT  @S9S_MB_2U_LIB.S9S_MB_2U(SCH_1):PVCCIN_CPU1_PIN_ALERT
   44  PVCCIN_CPU1_ISYS_R  TEMP1||ISYS  @S9S_MB_2U_LIB.S9S_MB_2U(SCH_1):PVCCIN_CPU1_ISYS_R
   34  PVCCIN_CPU1_IMON8    CS4  @S9S_MB_2U_LIB.S9S_MB_2U(SCH_1):PVCCIN_CPU1_IMON8
   33  PVCCIN_CPU1_IMON7    CS5  @S9S_MB_2U_LIB.S9S_MB_2U(SCH_1):PVCCIN_CPU1_IMON7
   32  PVCCIN_CPU1_IMON6    CS6  @S9S_MB_2U_LIB.S9S_MB_2U(SCH_1):PVCCIN_CPU1_IMON6
   31  PVCCIN_CPU1_IMON5    CS7  @S9S_MB_2U_LIB.S9S_MB_2U(SCH_1):PVCCIN_CPU1_IMON5
   30  PVCCIN_CPU1_IMON4    CS8  @S9S_MB_2U_LIB.S9S_MB_2U(SCH_1):PVCCIN_CPU1_IMON4
   29  PVCCIN_CPU1_IMON3    CS9  @S9S_MB_2U_LIB.S9S_MB_2U(SCH_1):PVCCIN_CPU1_IMON3
   28  PVCCIN_CPU1_IMON2   CS10  @S9S_MB_2U_LIB.S9S_MB_2U(SCH_1):PVCCIN_CPU1_IMON2
   27  PVCCIN_CPU1_IMON1   CS11  @S9S_MB_2U_LIB.S9S_MB_2U(SCH_1):PVCCIN_CPU1_IMON1
   17  PVCCIN_CPU1_EN_R    EN0  @S9S_MB_2U_LIB.S9S_MB_2U(SCH_1):PVCCIN_CPU1_EN_R
   45  PVCCIN_CPU1_CSPIN  VMON||IINSEN||VSYS||ISYS  @S9S_MB_2U_LIB.S9S_MB_2U(SCH_1):PVCCIN_CPU1_CSPIN
   43  PVCCIN_CPU1_ATSEN  TEMP0  @S9S_MB_2U_LIB.S9S_MB_2U(SCH_1):PVCCIN_CPU1_ATSEN
   42  PVCCIN_CPU1_ADDR  ADDR_CFG  @S9S_MB_2U_LIB.S9S_MB_2U(SCH_1):PVCCIN_CPU1_ADDR
    4  PVCCFA_EHV_FIVRA_CPU1_PWM4   PWM3  @S9S_MB_2U_LIB.S9S_MB_2U(SCH_1):PVCCFA_EHV_FIVRA_CPU1_PWM4
    3  PVCCFA_EHV_FIVRA_CPU1_PWM3   PWM2  @S9S_MB_2U_LIB.S9S_MB_2U(SCH_1):PVCCFA_EHV_FIVRA_CPU1_PWM3
    2  PVCCFA_EHV_FIVRA_CPU1_PWM2   PWM1  @S9S_MB_2U_LIB.S9S_MB_2U(SCH_1):PVCCFA_EHV_FIVRA_CPU1_PWM2
    1  PVCCFA_EHV_FIVRA_CPU1_PWM1   PWM0  @S9S_MB_2U_LIB.S9S_MB_2U(SCH_1):PVCCFA_EHV_FIVRA_CPU1_PWM1
   35  PVCCFA_EHV_FIVRA_CPU1_IMON4    CS3  @S9S_MB_2U_LIB.S9S_MB_2U(SCH_1):PVCCFA_EHV_FIVRA_CPU1_IMON4
   36  PVCCFA_EHV_FIVRA_CPU1_IMON3    CS2  @S9S_MB_2U_LIB.S9S_MB_2U(SCH_1):PVCCFA_EHV_FIVRA_CPU1_IMON3
   37  PVCCFA_EHV_FIVRA_CPU1_IMON2    CS1  @S9S_MB_2U_LIB.S9S_MB_2U(SCH_1):PVCCFA_EHV_FIVRA_CPU1_IMON2
   38  PVCCFA_EHV_FIVRA_CPU1_IMON1    CS0  @S9S_MB_2U_LIB.S9S_MB_2U(SCH_1):PVCCFA_EHV_FIVRA_CPU1_IMON1
   24  PVCCFA_EHV_FIVRA_CPU1_EN_R    EN1  @S9S_MB_2U_LIB.S9S_MB_2U(SCH_1):PVCCFA_EHV_FIVRA_CPU1_EN_R
   15  NC             NPMALERT  NC
   18  IRQ_CPU1_VRHOT_N  NVRHOT  @S9S_MB_2U_LIB.S9S_MB_2U(SCH_1):IRQ_CPU1_VRHOT_N
   TH  GND            TH_GND  @S9S_MB_2U_LIB.S9S_MB_2U(SCH_1):GND

ISL99390FRZTR5935  I18  PU30_P1_2  [ISL99390FRZTR5935-ISL99390FRZ-A]
  10_19  SW_PVCCIN_CPU1_SW2     SW  @S9S_MB_2U_LIB.S9S_MB_2U(SCH_1):SW_PVCCIN_CPU1_SW2
   32  SW_PVCCIN_CPU1_BOOTR2  PHASE  @S9S_MB_2U_LIB.S9S_MB_2U(SCH_1):SW_PVCCIN_CPU1_BOOTR2
   33  SW_PVCCIN_CPU1_BOOT2   BOOT  @S9S_MB_2U_LIB.S9S_MB_2U(SCH_1):SW_PVCCIN_CPU1_BOOT2
   30  SW_P12V_PVCCIN_CPU1_FLT   VIN2  @S9S_MB_2U_LIB.S9S_MB_2U(SCH_1):SW_P12V_PVCCIN_CPU1_FLT
  25_29  SW_P12V_PVCCIN_CPU1_FLT   VIN1  @S9S_MB_2U_LIB.S9S_MB_2U(SCH_1):SW_P12V_PVCCIN_CPU1_FLT
   39  PVCCIN_CPU1_VREF  REFIN  @S9S_MB_2U_LIB.S9S_MB_2U(SCH_1):PVCCIN_CPU1_VREF
    1  PVCCIN_CPU1_VOS2    VOS  @S9S_MB_2U_LIB.S9S_MB_2U(SCH_1):PVCCIN_CPU1_VOS2
    3  PVCCIN_CPU1_VDD2    VCC  @S9S_MB_2U_LIB.S9S_MB_2U(SCH_1):PVCCIN_CPU1_VDD2
   35  PVCCIN_CPU1_VDD2     EN  @S9S_MB_2U_LIB.S9S_MB_2U(SCH_1):PVCCIN_CPU1_VDD2
   34  PVCCIN_CPU1_PWM2    PWM  @S9S_MB_2U_LIB.S9S_MB_2U(SCH_1):PVCCIN_CPU1_PWM2
    4  PVCCIN_CPU1_PVCC   PVCC  @S9S_MB_2U_LIB.S9S_MB_2U(SCH_1):PVCCIN_CPU1_PVCC
   37  PVCCIN_CPU1_LSET2   LSET  @S9S_MB_2U_LIB.S9S_MB_2U(SCH_1):PVCCIN_CPU1_LSET2
   38  PVCCIN_CPU1_IMON2   IOUT  @S9S_MB_2U_LIB.S9S_MB_2U(SCH_1):PVCCIN_CPU1_IMON2
   36  PVCCIN_CPU1_ATSEN  TOUT_FLT  @S9S_MB_2U_LIB.S9S_MB_2U(SCH_1):PVCCIN_CPU1_ATSEN
   41  NC               GL2  NC
    6  NC               GL1  NC
   31  NC               DNC  NC
   40  GND            PGND3  @S9S_MB_2U_LIB.S9S_MB_2U(SCH_1):GND
  7_9-20_24  GND            PGND2  @S9S_MB_2U_LIB.S9S_MB_2U(SCH_1):GND
    5  GND            PGND1  @S9S_MB_2U_LIB.S9S_MB_2U(SCH_1):GND
    2  GND             AGND  @S9S_MB_2U_LIB.S9S_MB_2U(SCH_1):GND

ISL99390FRZTR5935  I20  PU31_P1_1  [ISL99390FRZTR5935-ISL99390FRZ-A]
  10_19  SW_PVCCIN_CPU1_SW1     SW  @S9S_MB_2U_LIB.S9S_MB_2U(SCH_1):SW_PVCCIN_CPU1_SW1
   32  SW_PVCCIN_CPU1_BOOTR1  PHASE  @S9S_MB_2U_LIB.S9S_MB_2U(SCH_1):SW_PVCCIN_CPU1_BOOTR1
   33  SW_PVCCIN_CPU1_BOOT1   BOOT  @S9S_MB_2U_LIB.S9S_MB_2U(SCH_1):SW_PVCCIN_CPU1_BOOT1
   30  SW_P12V_PVCCIN_CPU1_FLT   VIN2  @S9S_MB_2U_LIB.S9S_MB_2U(SCH_1):SW_P12V_PVCCIN_CPU1_FLT
  25_29  SW_P12V_PVCCIN_CPU1_FLT   VIN1  @S9S_MB_2U_LIB.S9S_MB_2U(SCH_1):SW_P12V_PVCCIN_CPU1_FLT
   39  PVCCIN_CPU1_VREF  REFIN  @S9S_MB_2U_LIB.S9S_MB_2U(SCH_1):PVCCIN_CPU1_VREF
    1  PVCCIN_CPU1_VOS1    VOS  @S9S_MB_2U_LIB.S9S_MB_2U(SCH_1):PVCCIN_CPU1_VOS1
    3  PVCCIN_CPU1_VDD1    VCC  @S9S_MB_2U_LIB.S9S_MB_2U(SCH_1):PVCCIN_CPU1_VDD1
   35  PVCCIN_CPU1_VDD1     EN  @S9S_MB_2U_LIB.S9S_MB_2U(SCH_1):PVCCIN_CPU1_VDD1
   34  PVCCIN_CPU1_PWM1    PWM  @S9S_MB_2U_LIB.S9S_MB_2U(SCH_1):PVCCIN_CPU1_PWM1
    4  PVCCIN_CPU1_PVCC   PVCC  @S9S_MB_2U_LIB.S9S_MB_2U(SCH_1):PVCCIN_CPU1_PVCC
   37  PVCCIN_CPU1_LSET1   LSET  @S9S_MB_2U_LIB.S9S_MB_2U(SCH_1):PVCCIN_CPU1_LSET1
   38  PVCCIN_CPU1_IMON1   IOUT  @S9S_MB_2U_LIB.S9S_MB_2U(SCH_1):PVCCIN_CPU1_IMON1
   36  PVCCIN_CPU1_ATSEN  TOUT_FLT  @S9S_MB_2U_LIB.S9S_MB_2U(SCH_1):PVCCIN_CPU1_ATSEN
   41  NC               GL2  NC
    6  NC               GL1  NC
   31  NC               DNC  NC
   40  GND            PGND3  @S9S_MB_2U_LIB.S9S_MB_2U(SCH_1):GND
  7_9-20_24  GND            PGND2  @S9S_MB_2U_LIB.S9S_MB_2U(SCH_1):GND
    5  GND            PGND1  @S9S_MB_2U_LIB.S9S_MB_2U(SCH_1):GND
    2  GND             AGND  @S9S_MB_2U_LIB.S9S_MB_2U(SCH_1):GND

ISL69260IRAZT  I51  PU35   [ISL69260IRAZT-ISL69260IRAZ-T,SA]
   22  VSENSE_PVCCD_HV_CPU0_DN  RGND0  @S9S_MB_2U_LIB.S9S_MB_2U(SCH_1):VSENSE_PVCCD_HV_CPU0_DN
   18  SVID_DIO_PVCCD_HV_CPU0_R  SVDATA  @S9S_MB_2U_LIB.S9S_MB_2U(SCH_1):SVID_DIO_PVCCD_HV_CPU0_R
   17  SVID_CLK_PVCCD_HV_CPU0_R  SVCLK  @S9S_MB_2U_LIB.S9S_MB_2U(SCH_1):SVID_CLK_PVCCD_HV_CPU0_R
   19  SVID_ALERT_PVCCD_HV_CPU0_R  NSVALERT  @S9S_MB_2U_LIB.S9S_MB_2U(SCH_1):SVID_ALERT_PVCCD_HV_CPU0_R
    9  SMB_DIO_PVCCD_HV_CPU0  PMSDA  @S9S_MB_2U_LIB.S9S_MB_2U(SCH_1):SMB_DIO_PVCCD_HV_CPU0
   10  SMB_CLK_PVCCD_HV_CPU0  PMSCL  @S9S_MB_2U_LIB.S9S_MB_2U(SCH_1):SMB_CLK_PVCCD_HV_CPU0
   21  SH_PVCCD_HV_CPU0_R  VSEN0  @S9S_MB_2U_LIB.S9S_MB_2U(SCH_1):SH_PVCCD_HV_CPU0_R
   12  PWRGD_PVCCD_HV_CPU0_R    PG0  @S9S_MB_2U_LIB.S9S_MB_2U(SCH_1):PWRGD_PVCCD_HV_CPU0_R
   40  PVCCD_HV_CPU0_VREF   VCCS  @S9S_MB_2U_LIB.S9S_MB_2U(SCH_1):PVCCD_HV_CPU0_VREF
   39  PVCCD_HV_CPU0_VCC    VCC  @S9S_MB_2U_LIB.S9S_MB_2U(SCH_1):PVCCD_HV_CPU0_VCC
   15  PVCCD_HV_CPU0_PIN_ALT  NPINALERT||NPSYSCRIT  @S9S_MB_2U_LIB.S9S_MB_2U(SCH_1):PVCCD_HV_CPU0_PIN_ALT
   36  PVCCD_HV_CPU0_ISYS_R  TEMP1||ISYS  @S9S_MB_2U_LIB.S9S_MB_2U(SCH_1):PVCCD_HV_CPU0_ISYS_R
   37  PVCCD_HV_CPU0_ISENSE_P  IINSEN||VMON||VSYS  @S9S_MB_2U_LIB.S9S_MB_2U(SCH_1):PVCCD_HV_CPU0_ISENSE_P
   38  PVCCD_HV_CPU0_ISENSE_N  VINSEN  @S9S_MB_2U_LIB.S9S_MB_2U(SCH_1):PVCCD_HV_CPU0_ISENSE_N
   33  PVCCD_HV_CPU0_FAULT    CFP  @S9S_MB_2U_LIB.S9S_MB_2U(SCH_1):PVCCD_HV_CPU0_FAULT
   13  PVCCD_HV_CPU0_EN_R    EN0  @S9S_MB_2U_LIB.S9S_MB_2U(SCH_1):PVCCD_HV_CPU0_EN_R
   35  PVCCD_HV_CPU0_ATSEN  TEMP0  @S9S_MB_2U_LIB.S9S_MB_2U(SCH_1):PVCCD_HV_CPU0_ATSEN
    8  PVCCD_HV_CPU0_APWM1   PWM7  @S9S_MB_2U_LIB.S9S_MB_2U(SCH_1):PVCCD_HV_CPU0_APWM1
   34  PVCCD_HV_CPU0_ADDR  ADDR_CFG  @S9S_MB_2U_LIB.S9S_MB_2U(SCH_1):PVCCD_HV_CPU0_ADDR
   23  PVCCD_HV_CPU0_ACSP1    CS7  @S9S_MB_2U_LIB.S9S_MB_2U(SCH_1):PVCCD_HV_CPU0_ACSP1
   11  NC             NPMALERT  NC
   16  NC               PG1  NC
    1  NC              PWM0  NC
    2  NC              PWM1  NC
    3  NC              PWM2  NC
    4  NC              PWM3  NC
    5  NC              PWM4  NC
    6  NC              PWM5  NC
    7  NC              PWM6  NC
   30  NC               CS0  NC
   29  NC               CS1  NC
   28  NC               CS2  NC
   27  NC               CS3  NC
   26  NC               CS4  NC
   25  NC               CS5  NC
   24  NC               CS6  NC
   14  IRQ_PVCCD_CPU0_VRHOT_LVC3_N  NVRHOT  @S9S_MB_2U_LIB.S9S_MB_2U(SCH_1):IRQ_PVCCD_CPU0_VRHOT_LVC3_N
   32  GND            VSEN1  @S9S_MB_2U_LIB.S9S_MB_2U(SCH_1):GND
   TH  GND            TH_GND  @S9S_MB_2U_LIB.S9S_MB_2U(SCH_1):GND
   31  GND            RGND1  @S9S_MB_2U_LIB.S9S_MB_2U(SCH_1):GND
   20  GND              EN1  @S9S_MB_2U_LIB.S9S_MB_2U(SCH_1):GND

RAA2213404GNPHB0  I333  PU36   [RAA2213404GNPHB0-RAA2213404GNPA]
  8_12  SW_PVCCD_HV_CPU0_SW1     SW  @S9S_MB_2U_LIB.S9S_MB_2U(SCH_1):SW_PVCCD_HV_CPU0_SW1
   19  SW_PVCCD_HV_CPU0_BOOTR1  PHASE  @S9S_MB_2U_LIB.S9S_MB_2U(SCH_1):SW_PVCCD_HV_CPU0_BOOTR1
   20  SW_PVCCD_HV_CPU0_BOOT1   BOOT  @S9S_MB_2U_LIB.S9S_MB_2U(SCH_1):SW_PVCCD_HV_CPU0_BOOT1
  16_18-28  SW_P12V_PVCCINFAON_CPU0_FLT    VIN  @S9S_MB_2U_LIB.S9S_MB_2U(SCH_1):SW_P12V_PVCCINFAON_CPU0_FLT
   24  PVCCD_HV_CPU0_VREF  REFIN  @S9S_MB_2U_LIB.S9S_MB_2U(SCH_1):PVCCD_HV_CPU0_VREF
    4  PVCCD_HV_CPU0_VDD1    VCC  @S9S_MB_2U_LIB.S9S_MB_2U(SCH_1):PVCCD_HV_CPU0_VDD1
   22  PVCCD_HV_CPU0_VDD1    NC1  @S9S_MB_2U_LIB.S9S_MB_2U(SCH_1):PVCCD_HV_CPU0_VDD1
    3  PVCCD_HV_CPU0_NC1  LGCTRL  @S9S_MB_2U_LIB.S9S_MB_2U(SCH_1):PVCCD_HV_CPU0_NC1
    5  PVCCD_HV_CPU0_LSET1    GL1  @S9S_MB_2U_LIB.S9S_MB_2U(SCH_1):PVCCD_HV_CPU0_LSET1
    1  PVCCD_HV_CPU0_ATSEN   TMON  @S9S_MB_2U_LIB.S9S_MB_2U(SCH_1):PVCCD_HV_CPU0_ATSEN
   21  PVCCD_HV_CPU0_APWM1    PWM  @S9S_MB_2U_LIB.S9S_MB_2U(SCH_1):PVCCD_HV_CPU0_APWM1
   25  PVCCD_HV_CPU0_ACSP1   IMON  @S9S_MB_2U_LIB.S9S_MB_2U(SCH_1):PVCCD_HV_CPU0_ACSP1
   27  NC               GL2  NC
   26  GND             GND3  @S9S_MB_2U_LIB.S9S_MB_2U(SCH_1):GND
   23  GND             GND2  @S9S_MB_2U_LIB.S9S_MB_2U(SCH_1):GND
  6_7-13_15-29  GND             GND1  @S9S_MB_2U_LIB.S9S_MB_2U(SCH_1):GND
    2  GND            FAULT#  @S9S_MB_2U_LIB.S9S_MB_2U(SCH_1):GND

RAA2213404GNPHB0  I11  PU42   [RAA2213404GNPHB0-RAA2213404GNPA]
  8_12  SW_PVCCFA_EHV_CPU0_SW1     SW  @S9S_MB_2U_LIB.S9S_MB_2U(SCH_1):SW_PVCCFA_EHV_CPU0_SW1
   19  SW_PVCCFA_EHV_CPU0_BOOTR1  PHASE  @S9S_MB_2U_LIB.S9S_MB_2U(SCH_1):SW_PVCCFA_EHV_CPU0_BOOTR1
   20  SW_PVCCFA_EHV_CPU0_BOOT1   BOOT  @S9S_MB_2U_LIB.S9S_MB_2U(SCH_1):SW_PVCCFA_EHV_CPU0_BOOT1
  16_18-28  SW_P12V_PVCCINFAON_CPU0_FLT    VIN  @S9S_MB_2U_LIB.S9S_MB_2U(SCH_1):SW_P12V_PVCCINFAON_CPU0_FLT
   24  PVCCINFAON_CPU0_VREF  REFIN  @S9S_MB_2U_LIB.S9S_MB_2U(SCH_1):PVCCINFAON_CPU0_VREF
    4  PVCCFA_EHV_CPU0_VDD1    VCC  @S9S_MB_2U_LIB.S9S_MB_2U(SCH_1):PVCCFA_EHV_CPU0_VDD1
   22  PVCCFA_EHV_CPU0_VDD1    NC1  @S9S_MB_2U_LIB.S9S_MB_2U(SCH_1):PVCCFA_EHV_CPU0_VDD1
    3  PVCCFA_EHV_CPU0_NC1  LGCTRL  @S9S_MB_2U_LIB.S9S_MB_2U(SCH_1):PVCCFA_EHV_CPU0_NC1
    5  PVCCFA_EHV_CPU0_LSET1    GL1  @S9S_MB_2U_LIB.S9S_MB_2U(SCH_1):PVCCFA_EHV_CPU0_LSET1
    1  PVCCFA_EHV_CPU0_BTSEN   TMON  @S9S_MB_2U_LIB.S9S_MB_2U(SCH_1):PVCCFA_EHV_CPU0_BTSEN
   21  PVCCFA_EHV_CPU0_BPWM1    PWM  @S9S_MB_2U_LIB.S9S_MB_2U(SCH_1):PVCCFA_EHV_CPU0_BPWM1
   25  PVCCFA_EHV_CPU0_BCSP1   IMON  @S9S_MB_2U_LIB.S9S_MB_2U(SCH_1):PVCCFA_EHV_CPU0_BCSP1
   27  NC               GL2  NC
   26  GND             GND3  @S9S_MB_2U_LIB.S9S_MB_2U(SCH_1):GND
   23  GND             GND2  @S9S_MB_2U_LIB.S9S_MB_2U(SCH_1):GND
  6_7-13_15-29  GND             GND1  @S9S_MB_2U_LIB.S9S_MB_2U(SCH_1):GND
    2  GND            FAULT#  @S9S_MB_2U_LIB.S9S_MB_2U(SCH_1):GND

RAA2213404GNPHB0  I166  PU43_P0_1  [RAA2213404GNPHB0-RAA2213404GNPA]
  8_12  SW_PVCCINFAON_CPU0_SW1     SW  @S9S_MB_2U_LIB.S9S_MB_2U(SCH_1):SW_PVCCINFAON_CPU0_SW1
   19  SW_PVCCINFAON_CPU0_BOOTR1  PHASE  @S9S_MB_2U_LIB.S9S_MB_2U(SCH_1):SW_PVCCINFAON_CPU0_BOOTR1
   20  SW_PVCCINFAON_CPU0_BOOT1   BOOT  @S9S_MB_2U_LIB.S9S_MB_2U(SCH_1):SW_PVCCINFAON_CPU0_BOOT1
  16_18-28  SW_P12V_PVCCINFAON_CPU0_FLT    VIN  @S9S_MB_2U_LIB.S9S_MB_2U(SCH_1):SW_P12V_PVCCINFAON_CPU0_FLT
   24  PVCCINFAON_CPU0_VREF  REFIN  @S9S_MB_2U_LIB.S9S_MB_2U(SCH_1):PVCCINFAON_CPU0_VREF
    4  PVCCINFAON_CPU0_VDD1    VCC  @S9S_MB_2U_LIB.S9S_MB_2U(SCH_1):PVCCINFAON_CPU0_VDD1
   22  PVCCINFAON_CPU0_VDD1    NC1  @S9S_MB_2U_LIB.S9S_MB_2U(SCH_1):PVCCINFAON_CPU0_VDD1
    3  PVCCINFAON_CPU0_PH1_NC1  LGCTRL  @S9S_MB_2U_LIB.S9S_MB_2U(SCH_1):PVCCINFAON_CPU0_PH1_NC1
    5  PVCCINFAON_CPU0_LSET1    GL1  @S9S_MB_2U_LIB.S9S_MB_2U(SCH_1):PVCCINFAON_CPU0_LSET1
    1  PVCCINFAON_CPU0_ATSEN   TMON  @S9S_MB_2U_LIB.S9S_MB_2U(SCH_1):PVCCINFAON_CPU0_ATSEN
   21  PVCCINFAON_CPU0_APWM1    PWM  @S9S_MB_2U_LIB.S9S_MB_2U(SCH_1):PVCCINFAON_CPU0_APWM1
   25  PVCCINFAON_CPU0_ACSP1   IMON  @S9S_MB_2U_LIB.S9S_MB_2U(SCH_1):PVCCINFAON_CPU0_ACSP1
   27  NC               GL2  NC
   26  GND             GND3  @S9S_MB_2U_LIB.S9S_MB_2U(SCH_1):GND
   23  GND             GND2  @S9S_MB_2U_LIB.S9S_MB_2U(SCH_1):GND
  6_7-13_15-29  GND             GND1  @S9S_MB_2U_LIB.S9S_MB_2U(SCH_1):GND
    2  GND            FAULT#  @S9S_MB_2U_LIB.S9S_MB_2U(SCH_1):GND

RAA2213404GNPHB0  I164  PU44_P0_2  [RAA2213404GNPHB0-RAA2213404GNPA]
  8_12  SW_PVCCINFAON_CPU0_SW2     SW  @S9S_MB_2U_LIB.S9S_MB_2U(SCH_1):SW_PVCCINFAON_CPU0_SW2
   19  SW_PVCCINFAON_CPU0_BOOTR2  PHASE  @S9S_MB_2U_LIB.S9S_MB_2U(SCH_1):SW_PVCCINFAON_CPU0_BOOTR2
   20  SW_PVCCINFAON_CPU0_BOOT2   BOOT  @S9S_MB_2U_LIB.S9S_MB_2U(SCH_1):SW_PVCCINFAON_CPU0_BOOT2
  16_18-28  SW_P12V_PVCCINFAON_CPU0_FLT    VIN  @S9S_MB_2U_LIB.S9S_MB_2U(SCH_1):SW_P12V_PVCCINFAON_CPU0_FLT
   24  PVCCINFAON_CPU0_VREF  REFIN  @S9S_MB_2U_LIB.S9S_MB_2U(SCH_1):PVCCINFAON_CPU0_VREF
    4  PVCCINFAON_CPU0_VDD2    VCC  @S9S_MB_2U_LIB.S9S_MB_2U(SCH_1):PVCCINFAON_CPU0_VDD2
   22  PVCCINFAON_CPU0_VDD2    NC1  @S9S_MB_2U_LIB.S9S_MB_2U(SCH_1):PVCCINFAON_CPU0_VDD2
    3  PVCCINFAON_CPU0_PH2_NC1  LGCTRL  @S9S_MB_2U_LIB.S9S_MB_2U(SCH_1):PVCCINFAON_CPU0_PH2_NC1
    5  PVCCINFAON_CPU0_LSET2    GL1  @S9S_MB_2U_LIB.S9S_MB_2U(SCH_1):PVCCINFAON_CPU0_LSET2
    1  PVCCINFAON_CPU0_ATSEN   TMON  @S9S_MB_2U_LIB.S9S_MB_2U(SCH_1):PVCCINFAON_CPU0_ATSEN
   21  PVCCINFAON_CPU0_APWM2    PWM  @S9S_MB_2U_LIB.S9S_MB_2U(SCH_1):PVCCINFAON_CPU0_APWM2
   25  PVCCINFAON_CPU0_ACSP2   IMON  @S9S_MB_2U_LIB.S9S_MB_2U(SCH_1):PVCCINFAON_CPU0_ACSP2
   27  NC               GL2  NC
   26  GND             GND3  @S9S_MB_2U_LIB.S9S_MB_2U(SCH_1):GND
   23  GND             GND2  @S9S_MB_2U_LIB.S9S_MB_2U(SCH_1):GND
  6_7-13_15-29  GND             GND1  @S9S_MB_2U_LIB.S9S_MB_2U(SCH_1):GND
    2  GND            FAULT#  @S9S_MB_2U_LIB.S9S_MB_2U(SCH_1):GND

RAA2213404GNPHB0  I14  PU49   [RAA2213404GNPHB0-RAA2213404GNPA]
  8_12  SW_PVCCFA_EHV_CPU1_SW1     SW  @S9S_MB_2U_LIB.S9S_MB_2U(SCH_1):SW_PVCCFA_EHV_CPU1_SW1
   19  SW_PVCCFA_EHV_CPU1_BOOTR1  PHASE  @S9S_MB_2U_LIB.S9S_MB_2U(SCH_1):SW_PVCCFA_EHV_CPU1_BOOTR1
   20  SW_PVCCFA_EHV_CPU1_BOOT1   BOOT  @S9S_MB_2U_LIB.S9S_MB_2U(SCH_1):SW_PVCCFA_EHV_CPU1_BOOT1
  16_18-28  SW_P12V_PVCCINFAON_CPU1_FLT    VIN  @S9S_MB_2U_LIB.S9S_MB_2U(SCH_1):SW_P12V_PVCCINFAON_CPU1_FLT
   24  PVCCINFAON_CPU1_VREF  REFIN  @S9S_MB_2U_LIB.S9S_MB_2U(SCH_1):PVCCINFAON_CPU1_VREF
    4  PVCCFA_EHV_CPU1_VDD1    VCC  @S9S_MB_2U_LIB.S9S_MB_2U(SCH_1):PVCCFA_EHV_CPU1_VDD1
   22  PVCCFA_EHV_CPU1_VDD1    NC1  @S9S_MB_2U_LIB.S9S_MB_2U(SCH_1):PVCCFA_EHV_CPU1_VDD1
    3  PVCCFA_EHV_CPU1_NC1  LGCTRL  @S9S_MB_2U_LIB.S9S_MB_2U(SCH_1):PVCCFA_EHV_CPU1_NC1
    5  PVCCFA_EHV_CPU1_LSET1    GL1  @S9S_MB_2U_LIB.S9S_MB_2U(SCH_1):PVCCFA_EHV_CPU1_LSET1
    1  PVCCFA_EHV_CPU1_BTSEN   TMON  @S9S_MB_2U_LIB.S9S_MB_2U(SCH_1):PVCCFA_EHV_CPU1_BTSEN
   21  PVCCFA_EHV_CPU1_BPWM1    PWM  @S9S_MB_2U_LIB.S9S_MB_2U(SCH_1):PVCCFA_EHV_CPU1_BPWM1
   25  PVCCFA_EHV_CPU1_BCSP1   IMON  @S9S_MB_2U_LIB.S9S_MB_2U(SCH_1):PVCCFA_EHV_CPU1_BCSP1
   27  NC               GL2  NC
   26  GND             GND3  @S9S_MB_2U_LIB.S9S_MB_2U(SCH_1):GND
   23  GND             GND2  @S9S_MB_2U_LIB.S9S_MB_2U(SCH_1):GND
  6_7-13_15-29  GND             GND1  @S9S_MB_2U_LIB.S9S_MB_2U(SCH_1):GND
    2  GND            FAULT#  @S9S_MB_2U_LIB.S9S_MB_2U(SCH_1):GND

RAA2213404GNPHB0  I17  PU50_P1_1  [RAA2213404GNPHB0-RAA2213404GNPA]
  8_12  SW_PVCCINFAON_CPU1_SW1     SW  @S9S_MB_2U_LIB.S9S_MB_2U(SCH_1):SW_PVCCINFAON_CPU1_SW1
   19  SW_PVCCINFAON_CPU1_BOOTR1  PHASE  @S9S_MB_2U_LIB.S9S_MB_2U(SCH_1):SW_PVCCINFAON_CPU1_BOOTR1
   20  SW_PVCCINFAON_CPU1_BOOT1   BOOT  @S9S_MB_2U_LIB.S9S_MB_2U(SCH_1):SW_PVCCINFAON_CPU1_BOOT1
  16_18-28  SW_P12V_PVCCINFAON_CPU1_FLT    VIN  @S9S_MB_2U_LIB.S9S_MB_2U(SCH_1):SW_P12V_PVCCINFAON_CPU1_FLT
   24  PVCCINFAON_CPU1_VREF  REFIN  @S9S_MB_2U_LIB.S9S_MB_2U(SCH_1):PVCCINFAON_CPU1_VREF
    4  PVCCINFAON_CPU1_VDD1    VCC  @S9S_MB_2U_LIB.S9S_MB_2U(SCH_1):PVCCINFAON_CPU1_VDD1
   22  PVCCINFAON_CPU1_VDD1    NC1  @S9S_MB_2U_LIB.S9S_MB_2U(SCH_1):PVCCINFAON_CPU1_VDD1
    3  PVCCINFAON_CPU1_PH1_NC1  LGCTRL  @S9S_MB_2U_LIB.S9S_MB_2U(SCH_1):PVCCINFAON_CPU1_PH1_NC1
    5  PVCCINFAON_CPU1_LSET1    GL1  @S9S_MB_2U_LIB.S9S_MB_2U(SCH_1):PVCCINFAON_CPU1_LSET1
    1  PVCCINFAON_CPU1_ATSEN   TMON  @S9S_MB_2U_LIB.S9S_MB_2U(SCH_1):PVCCINFAON_CPU1_ATSEN
   21  PVCCINFAON_CPU1_APWM1    PWM  @S9S_MB_2U_LIB.S9S_MB_2U(SCH_1):PVCCINFAON_CPU1_APWM1
   25  PVCCINFAON_CPU1_ACSP1   IMON  @S9S_MB_2U_LIB.S9S_MB_2U(SCH_1):PVCCINFAON_CPU1_ACSP1
   27  NC               GL2  NC
   26  GND             GND3  @S9S_MB_2U_LIB.S9S_MB_2U(SCH_1):GND
   23  GND             GND2  @S9S_MB_2U_LIB.S9S_MB_2U(SCH_1):GND
  6_7-13_15-29  GND             GND1  @S9S_MB_2U_LIB.S9S_MB_2U(SCH_1):GND
    2  GND            FAULT#  @S9S_MB_2U_LIB.S9S_MB_2U(SCH_1):GND

RAA2213404GNPHB0  I12  PU51_P1_2  [RAA2213404GNPHB0-RAA2213404GNPA]
  8_12  SW_PVCCINFAON_CPU1_SW2     SW  @S9S_MB_2U_LIB.S9S_MB_2U(SCH_1):SW_PVCCINFAON_CPU1_SW2
   19  SW_PVCCINFAON_CPU1_BOOTR2  PHASE  @S9S_MB_2U_LIB.S9S_MB_2U(SCH_1):SW_PVCCINFAON_CPU1_BOOTR2
   20  SW_PVCCINFAON_CPU1_BOOT2   BOOT  @S9S_MB_2U_LIB.S9S_MB_2U(SCH_1):SW_PVCCINFAON_CPU1_BOOT2
  16_18-28  SW_P12V_PVCCINFAON_CPU1_FLT    VIN  @S9S_MB_2U_LIB.S9S_MB_2U(SCH_1):SW_P12V_PVCCINFAON_CPU1_FLT
   24  PVCCINFAON_CPU1_VREF  REFIN  @S9S_MB_2U_LIB.S9S_MB_2U(SCH_1):PVCCINFAON_CPU1_VREF
    4  PVCCINFAON_CPU1_VDD2    VCC  @S9S_MB_2U_LIB.S9S_MB_2U(SCH_1):PVCCINFAON_CPU1_VDD2
   22  PVCCINFAON_CPU1_VDD2    NC1  @S9S_MB_2U_LIB.S9S_MB_2U(SCH_1):PVCCINFAON_CPU1_VDD2
    3  PVCCINFAON_CPU1_PH2_NC1  LGCTRL  @S9S_MB_2U_LIB.S9S_MB_2U(SCH_1):PVCCINFAON_CPU1_PH2_NC1
    5  PVCCINFAON_CPU1_LSET2    GL1  @S9S_MB_2U_LIB.S9S_MB_2U(SCH_1):PVCCINFAON_CPU1_LSET2
    1  PVCCINFAON_CPU1_ATSEN   TMON  @S9S_MB_2U_LIB.S9S_MB_2U(SCH_1):PVCCINFAON_CPU1_ATSEN
   21  PVCCINFAON_CPU1_APWM2    PWM  @S9S_MB_2U_LIB.S9S_MB_2U(SCH_1):PVCCINFAON_CPU1_APWM2
   25  PVCCINFAON_CPU1_ACSP2   IMON  @S9S_MB_2U_LIB.S9S_MB_2U(SCH_1):PVCCINFAON_CPU1_ACSP2
   27  NC               GL2  NC
   26  GND             GND3  @S9S_MB_2U_LIB.S9S_MB_2U(SCH_1):GND
   23  GND             GND2  @S9S_MB_2U_LIB.S9S_MB_2U(SCH_1):GND
  6_7-13_15-29  GND             GND1  @S9S_MB_2U_LIB.S9S_MB_2U(SCH_1):GND
    2  GND            FAULT#  @S9S_MB_2U_LIB.S9S_MB_2U(SCH_1):GND

ISL99390FRZTR5935  I35  PU69_P0_1  [ISL99390FRZTR5935-ISL99390FRZ-A]
  10_19  SW_PVCCFA_EHV_FIVRA_CPU0_SW1     SW  @S9S_MB_2U_LIB.S9S_MB_2U(SCH_1):SW_PVCCFA_EHV_FIVRA_CPU0_SW1
   32  SW_PVCCFA_EHV_FIVRA_CPU0_BOOTR1  PHASE  @S9S_MB_2U_LIB.S9S_MB_2U(SCH_1):SW_PVCCFA_EHV_FIVRA_CPU0_BOOTR1
   33  SW_PVCCFA_EHV_FIVRA_CPU0_BOOT1   BOOT  @S9S_MB_2U_LIB.S9S_MB_2U(SCH_1):SW_PVCCFA_EHV_FIVRA_CPU0_BOOT1
   30  SW_P12V_PVCCFA_EHV_FIVRA_CPU0_R   VIN2  @S9S_MB_2U_LIB.S9S_MB_2U(SCH_1):SW_P12V_PVCCFA_EHV_FIVRA_CPU0_R
  25_29  SW_P12V_PVCCFA_EHV_FIVRA_CPU0_R   VIN1  @S9S_MB_2U_LIB.S9S_MB_2U(SCH_1):SW_P12V_PVCCFA_EHV_FIVRA_CPU0_R
   39  PVCCIN_CPU0_VREF  REFIN  @S9S_MB_2U_LIB.S9S_MB_2U(SCH_1):PVCCIN_CPU0_VREF
   36  PVCCIN_CPU0_ATSEN  TOUT_FLT  @S9S_MB_2U_LIB.S9S_MB_2U(SCH_1):PVCCIN_CPU0_ATSEN
    1  PVCCFA_EHV_FIVRA_CPU0_VOS1    VOS  @S9S_MB_2U_LIB.S9S_MB_2U(SCH_1):PVCCFA_EHV_FIVRA_CPU0_VOS1
    3  PVCCFA_EHV_FIVRA_CPU0_VDD1    VCC  @S9S_MB_2U_LIB.S9S_MB_2U(SCH_1):PVCCFA_EHV_FIVRA_CPU0_VDD1
   35  PVCCFA_EHV_FIVRA_CPU0_VDD1     EN  @S9S_MB_2U_LIB.S9S_MB_2U(SCH_1):PVCCFA_EHV_FIVRA_CPU0_VDD1
   34  PVCCFA_EHV_FIVRA_CPU0_PWM1    PWM  @S9S_MB_2U_LIB.S9S_MB_2U(SCH_1):PVCCFA_EHV_FIVRA_CPU0_PWM1
    4  PVCCFA_EHV_FIVRA_CPU0_PVCC1   PVCC  @S9S_MB_2U_LIB.S9S_MB_2U(SCH_1):PVCCFA_EHV_FIVRA_CPU0_PVCC1
   37  PVCCFA_EHV_FIVRA_CPU0_LSET1   LSET  @S9S_MB_2U_LIB.S9S_MB_2U(SCH_1):PVCCFA_EHV_FIVRA_CPU0_LSET1
   38  PVCCFA_EHV_FIVRA_CPU0_IMON1   IOUT  @S9S_MB_2U_LIB.S9S_MB_2U(SCH_1):PVCCFA_EHV_FIVRA_CPU0_IMON1
   41  NC               GL2  NC
    6  NC               GL1  NC
   31  NC               DNC  NC
   40  GND            PGND3  @S9S_MB_2U_LIB.S9S_MB_2U(SCH_1):GND
  7_9-20_24  GND            PGND2  @S9S_MB_2U_LIB.S9S_MB_2U(SCH_1):GND
    5  GND            PGND1  @S9S_MB_2U_LIB.S9S_MB_2U(SCH_1):GND
    2  GND             AGND  @S9S_MB_2U_LIB.S9S_MB_2U(SCH_1):GND

ISL99390FRZTR5935  I30  PU70_P0_2  [ISL99390FRZTR5935-ISL99390FRZ-A]
  10_19  SW_PVCCFA_EHV_FIVRA_CPU0_SW2     SW  @S9S_MB_2U_LIB.S9S_MB_2U(SCH_1):SW_PVCCFA_EHV_FIVRA_CPU0_SW2
   32  SW_PVCCFA_EHV_FIVRA_CPU0_BOOTR2  PHASE  @S9S_MB_2U_LIB.S9S_MB_2U(SCH_1):SW_PVCCFA_EHV_FIVRA_CPU0_BOOTR2
   33  SW_PVCCFA_EHV_FIVRA_CPU0_BOOT2   BOOT  @S9S_MB_2U_LIB.S9S_MB_2U(SCH_1):SW_PVCCFA_EHV_FIVRA_CPU0_BOOT2
   30  SW_P12V_PVCCFA_EHV_FIVRA_CPU0_L   VIN2  @S9S_MB_2U_LIB.S9S_MB_2U(SCH_1):SW_P12V_PVCCFA_EHV_FIVRA_CPU0_L
  25_29  SW_P12V_PVCCFA_EHV_FIVRA_CPU0_L   VIN1  @S9S_MB_2U_LIB.S9S_MB_2U(SCH_1):SW_P12V_PVCCFA_EHV_FIVRA_CPU0_L
   39  PVCCIN_CPU0_VREF  REFIN  @S9S_MB_2U_LIB.S9S_MB_2U(SCH_1):PVCCIN_CPU0_VREF
   36  PVCCIN_CPU0_ATSEN  TOUT_FLT  @S9S_MB_2U_LIB.S9S_MB_2U(SCH_1):PVCCIN_CPU0_ATSEN
    1  PVCCFA_EHV_FIVRA_CPU0_VOS2    VOS  @S9S_MB_2U_LIB.S9S_MB_2U(SCH_1):PVCCFA_EHV_FIVRA_CPU0_VOS2
    3  PVCCFA_EHV_FIVRA_CPU0_VDD2    VCC  @S9S_MB_2U_LIB.S9S_MB_2U(SCH_1):PVCCFA_EHV_FIVRA_CPU0_VDD2
   35  PVCCFA_EHV_FIVRA_CPU0_VDD2     EN  @S9S_MB_2U_LIB.S9S_MB_2U(SCH_1):PVCCFA_EHV_FIVRA_CPU0_VDD2
   34  PVCCFA_EHV_FIVRA_CPU0_PWM2    PWM  @S9S_MB_2U_LIB.S9S_MB_2U(SCH_1):PVCCFA_EHV_FIVRA_CPU0_PWM2
    4  PVCCFA_EHV_FIVRA_CPU0_PVCC2   PVCC  @S9S_MB_2U_LIB.S9S_MB_2U(SCH_1):PVCCFA_EHV_FIVRA_CPU0_PVCC2
   37  PVCCFA_EHV_FIVRA_CPU0_LSET2   LSET  @S9S_MB_2U_LIB.S9S_MB_2U(SCH_1):PVCCFA_EHV_FIVRA_CPU0_LSET2
   38  PVCCFA_EHV_FIVRA_CPU0_IMON2   IOUT  @S9S_MB_2U_LIB.S9S_MB_2U(SCH_1):PVCCFA_EHV_FIVRA_CPU0_IMON2
   41  NC               GL2  NC
    6  NC               GL1  NC
   31  NC               DNC  NC
   40  GND            PGND3  @S9S_MB_2U_LIB.S9S_MB_2U(SCH_1):GND
  7_9-20_24  GND            PGND2  @S9S_MB_2U_LIB.S9S_MB_2U(SCH_1):GND
    5  GND            PGND1  @S9S_MB_2U_LIB.S9S_MB_2U(SCH_1):GND
    2  GND             AGND  @S9S_MB_2U_LIB.S9S_MB_2U(SCH_1):GND

ISL99390FRZTR5935  I40  PU71_P0_3  [ISL99390FRZTR5935-ISL99390FRZ-B]
  10_19  SW_PVCCFA_EHV_FIVRA_CPU0_SW3     SW  @S9S_MB_2U_LIB.S9S_MB_2U(SCH_1):SW_PVCCFA_EHV_FIVRA_CPU0_SW3
   32  SW_PVCCFA_EHV_FIVRA_CPU0_BOOTR3  PHASE  @S9S_MB_2U_LIB.S9S_MB_2U(SCH_1):SW_PVCCFA_EHV_FIVRA_CPU0_BOOTR3
   33  SW_PVCCFA_EHV_FIVRA_CPU0_BOOT3   BOOT  @S9S_MB_2U_LIB.S9S_MB_2U(SCH_1):SW_PVCCFA_EHV_FIVRA_CPU0_BOOT3
   30  SW_P12V_PVCCFA_EHV_FIVRA_CPU0_R   VIN2  @S9S_MB_2U_LIB.S9S_MB_2U(SCH_1):SW_P12V_PVCCFA_EHV_FIVRA_CPU0_R
  25_29  SW_P12V_PVCCFA_EHV_FIVRA_CPU0_R   VIN1  @S9S_MB_2U_LIB.S9S_MB_2U(SCH_1):SW_P12V_PVCCFA_EHV_FIVRA_CPU0_R
   39  PVCCIN_CPU0_VREF  REFIN  @S9S_MB_2U_LIB.S9S_MB_2U(SCH_1):PVCCIN_CPU0_VREF
   36  PVCCIN_CPU0_ATSEN  TOUT_FLT  @S9S_MB_2U_LIB.S9S_MB_2U(SCH_1):PVCCIN_CPU0_ATSEN
    1  PVCCFA_EHV_FIVRA_CPU0_VOS3    VOS  @S9S_MB_2U_LIB.S9S_MB_2U(SCH_1):PVCCFA_EHV_FIVRA_CPU0_VOS3
    3  PVCCFA_EHV_FIVRA_CPU0_VDD3    VCC  @S9S_MB_2U_LIB.S9S_MB_2U(SCH_1):PVCCFA_EHV_FIVRA_CPU0_VDD3
   35  PVCCFA_EHV_FIVRA_CPU0_VDD3     EN  @S9S_MB_2U_LIB.S9S_MB_2U(SCH_1):PVCCFA_EHV_FIVRA_CPU0_VDD3
   34  NC               PWM  NC
    4  PVCCFA_EHV_FIVRA_CPU0_PVCC1   PVCC  @S9S_MB_2U_LIB.S9S_MB_2U(SCH_1):PVCCFA_EHV_FIVRA_CPU0_PVCC1
   37  PVCCFA_EHV_FIVRA_CPU0_LSET3   LSET  @S9S_MB_2U_LIB.S9S_MB_2U(SCH_1):PVCCFA_EHV_FIVRA_CPU0_LSET3
   38  NC              IOUT  NC
   41  NC               GL2  NC
    6  NC               GL1  NC
   31  NC               DNC  NC
   40  GND            PGND3  @S9S_MB_2U_LIB.S9S_MB_2U(SCH_1):GND
  7_9-20_24  GND            PGND2  @S9S_MB_2U_LIB.S9S_MB_2U(SCH_1):GND
    5  GND            PGND1  @S9S_MB_2U_LIB.S9S_MB_2U(SCH_1):GND
    2  GND             AGND  @S9S_MB_2U_LIB.S9S_MB_2U(SCH_1):GND

ISL99390FRZTR5935  I24  PU72_P0_4  [ISL99390FRZTR5935-ISL99390FRZ-B]
  10_19  SW_PVCCFA_EHV_FIVRA_CPU0_SW4     SW  @S9S_MB_2U_LIB.S9S_MB_2U(SCH_1):SW_PVCCFA_EHV_FIVRA_CPU0_SW4
   32  SW_PVCCFA_EHV_FIVRA_CPU0_BOOTR4  PHASE  @S9S_MB_2U_LIB.S9S_MB_2U(SCH_1):SW_PVCCFA_EHV_FIVRA_CPU0_BOOTR4
   33  SW_PVCCFA_EHV_FIVRA_CPU0_BOOT4   BOOT  @S9S_MB_2U_LIB.S9S_MB_2U(SCH_1):SW_PVCCFA_EHV_FIVRA_CPU0_BOOT4
   30  SW_P12V_PVCCFA_EHV_FIVRA_CPU0_L   VIN2  @S9S_MB_2U_LIB.S9S_MB_2U(SCH_1):SW_P12V_PVCCFA_EHV_FIVRA_CPU0_L
  25_29  SW_P12V_PVCCFA_EHV_FIVRA_CPU0_L   VIN1  @S9S_MB_2U_LIB.S9S_MB_2U(SCH_1):SW_P12V_PVCCFA_EHV_FIVRA_CPU0_L
   39  PVCCIN_CPU0_VREF  REFIN  @S9S_MB_2U_LIB.S9S_MB_2U(SCH_1):PVCCIN_CPU0_VREF
   36  PVCCIN_CPU0_ATSEN  TOUT_FLT  @S9S_MB_2U_LIB.S9S_MB_2U(SCH_1):PVCCIN_CPU0_ATSEN
    1  PVCCFA_EHV_FIVRA_CPU0_VOS4    VOS  @S9S_MB_2U_LIB.S9S_MB_2U(SCH_1):PVCCFA_EHV_FIVRA_CPU0_VOS4
    3  PVCCFA_EHV_FIVRA_CPU0_VDD4    VCC  @S9S_MB_2U_LIB.S9S_MB_2U(SCH_1):PVCCFA_EHV_FIVRA_CPU0_VDD4
   35  PVCCFA_EHV_FIVRA_CPU0_VDD4     EN  @S9S_MB_2U_LIB.S9S_MB_2U(SCH_1):PVCCFA_EHV_FIVRA_CPU0_VDD4
   34  NC               PWM  NC
    4  PVCCFA_EHV_FIVRA_CPU0_PVCC2   PVCC  @S9S_MB_2U_LIB.S9S_MB_2U(SCH_1):PVCCFA_EHV_FIVRA_CPU0_PVCC2
   37  PVCCFA_EHV_FIVRA_CPU0_LSET4   LSET  @S9S_MB_2U_LIB.S9S_MB_2U(SCH_1):PVCCFA_EHV_FIVRA_CPU0_LSET4
   38  NC              IOUT  NC
   41  NC               GL2  NC
    6  NC               GL1  NC
   31  NC               DNC  NC
   40  GND            PGND3  @S9S_MB_2U_LIB.S9S_MB_2U(SCH_1):GND
  7_9-20_24  GND            PGND2  @S9S_MB_2U_LIB.S9S_MB_2U(SCH_1):GND
    5  GND            PGND1  @S9S_MB_2U_LIB.S9S_MB_2U(SCH_1):GND
    2  GND             AGND  @S9S_MB_2U_LIB.S9S_MB_2U(SCH_1):GND

MPQ8633BGLEC838Z  I34  PU73   [MPQ8633BGLEC838Z-MPQ8633BGLE-CA]
   20  SW_P1V05_PCH_AUX_SW     SW  @S9S_MB_2U_LIB.S9S_MB_2U(SCH_1):SW_P1V05_PCH_AUX_SW
    1  SW_P1V05_PCH_AUX_BST    BST  @S9S_MB_2U_LIB.S9S_MB_2U(SCH_1):SW_P1V05_PCH_AUX_BST
   21  SW_P12V_AUX_P1V05_PCH_AUX_FLT   VIN2  @S9S_MB_2U_LIB.S9S_MB_2U(SCH_1):SW_P12V_AUX_P1V05_PCH_AUX_FLT
   10  SW_P12V_AUX_P1V05_PCH_AUX_FLT   VIN1  @S9S_MB_2U_LIB.S9S_MB_2U(SCH_1):SW_P12V_AUX_P1V05_PCH_AUX_FLT
    6  SH_P1V05_PCH_AUX_N   RGND  @S9S_MB_2U_LIB.S9S_MB_2U(SCH_1):SH_P1V05_PCH_AUX_N
    9  PWRGD_P1V05_PCH_AUX_R  PGOOD  @S9S_MB_2U_LIB.S9S_MB_2U(SCH_1):PWRGD_P1V05_PCH_AUX_R
   19  P1V05_PCH_AUX_VCC    VCC  @S9S_MB_2U_LIB.S9S_MB_2U(SCH_1):P1V05_PCH_AUX_VCC
    4  P1V05_PCH_AUX_VCC   MODE  @S9S_MB_2U_LIB.S9S_MB_2U(SCH_1):P1V05_PCH_AUX_VCC
    5  P1V05_PCH_AUX_REF  TRK_REF  @S9S_MB_2U_LIB.S9S_MB_2U(SCH_1):P1V05_PCH_AUX_REF
    7  P1V05_PCH_AUX_FB     FB  @S9S_MB_2U_LIB.S9S_MB_2U(SCH_1):P1V05_PCH_AUX_FB
    3  P1V05_PCH_AUX_CS     CS  @S9S_MB_2U_LIB.S9S_MB_2U(SCH_1):P1V05_PCH_AUX_CS
  11_18  GND             PGND  @S9S_MB_2U_LIB.S9S_MB_2U(SCH_1):GND
    2  GND             AGND  @S9S_MB_2U_LIB.S9S_MB_2U(SCH_1):GND
    8  FM_P1V05_PCH_AUX_R_EN     EN  @S9S_MB_2U_LIB.S9S_MB_2U(SCH_1):FM_P1V05_PCH_AUX_R_EN

NB695GDZ  I20  PU74   [NB695GDZ-NB695GD-Z,SMLF,IC,AL0A]
    8  SW_P1V8_PCH_AUX_SW     SW  @S9S_MB_2U_LIB.S9S_MB_2U(SCH_1):SW_P1V8_PCH_AUX_SW
    1  SW_P1V8_PCH_AUX_FLT    VIN  @S9S_MB_2U_LIB.S9S_MB_2U(SCH_1):SW_P1V8_PCH_AUX_FLT
    9  SW_P1V8_PCH_AUX_BST    BST  @S9S_MB_2U_LIB.S9S_MB_2U(SCH_1):SW_P1V8_PCH_AUX_BST
   13  PWRGD_P1V8_PCH_AUX_R     PG  @S9S_MB_2U_LIB.S9S_MB_2U(SCH_1):PWRGD_P1V8_PCH_AUX_R
    6  P1V8_PCH_AUX_VCC    LP#  @S9S_MB_2U_LIB.S9S_MB_2U(SCH_1):P1V8_PCH_AUX_VCC
    3  P1V8_PCH_AUX_VCC     C1  @S9S_MB_2U_LIB.S9S_MB_2U(SCH_1):P1V8_PCH_AUX_VCC
   10  P1V8_PCH_AUX_VCC    3V3  @S9S_MB_2U_LIB.S9S_MB_2U(SCH_1):P1V8_PCH_AUX_VCC
    7  P1V8_PCH_AUX_MODE   MODE  @S9S_MB_2U_LIB.S9S_MB_2U(SCH_1):P1V8_PCH_AUX_MODE
   12  P1V8_PCH_AUX    VOUT  @S9S_MB_2U_LIB.S9S_MB_2U(SCH_1):P1V8_PCH_AUX
    2  GND             PGND  @S9S_MB_2U_LIB.S9S_MB_2U(SCH_1):GND
    4  GND               C0  @S9S_MB_2U_LIB.S9S_MB_2U(SCH_1):GND
   11  GND             AGND  @S9S_MB_2U_LIB.S9S_MB_2U(SCH_1):GND
    5  FM_PCH_P1V8_AUX_EN_R     EN  @S9S_MB_2U_LIB.S9S_MB_2U(SCH_1):FM_PCH_P1V8_AUX_EN_R

ISL99390FRZTR5935  I278  PU75_P1_1  [ISL99390FRZTR5935-ISL99390FRZ-A]
  10_19  SW_PVCCFA_EHV_FIVRA_CPU1_SW1     SW  @S9S_MB_2U_LIB.S9S_MB_2U(SCH_1):SW_PVCCFA_EHV_FIVRA_CPU1_SW1
   32  SW_PVCCFA_EHV_FIVRA_CPU1_BOOTR1  PHASE  @S9S_MB_2U_LIB.S9S_MB_2U(SCH_1):SW_PVCCFA_EHV_FIVRA_CPU1_BOOTR1
   33  SW_PVCCFA_EHV_FIVRA_CPU1_BOOT1   BOOT  @S9S_MB_2U_LIB.S9S_MB_2U(SCH_1):SW_PVCCFA_EHV_FIVRA_CPU1_BOOT1
   30  SW_P12V_PVCCFA_EHV_FIVRA_CPU1_R   VIN2  @S9S_MB_2U_LIB.S9S_MB_2U(SCH_1):SW_P12V_PVCCFA_EHV_FIVRA_CPU1_R
  25_29  SW_P12V_PVCCFA_EHV_FIVRA_CPU1_R   VIN1  @S9S_MB_2U_LIB.S9S_MB_2U(SCH_1):SW_P12V_PVCCFA_EHV_FIVRA_CPU1_R
   39  PVCCIN_CPU1_VREF  REFIN  @S9S_MB_2U_LIB.S9S_MB_2U(SCH_1):PVCCIN_CPU1_VREF
   36  PVCCIN_CPU1_ATSEN  TOUT_FLT  @S9S_MB_2U_LIB.S9S_MB_2U(SCH_1):PVCCIN_CPU1_ATSEN
    1  PVCCFA_EHV_FIVRA_CPU1_VOS1    VOS  @S9S_MB_2U_LIB.S9S_MB_2U(SCH_1):PVCCFA_EHV_FIVRA_CPU1_VOS1
    3  PVCCFA_EHV_FIVRA_CPU1_VDD1    VCC  @S9S_MB_2U_LIB.S9S_MB_2U(SCH_1):PVCCFA_EHV_FIVRA_CPU1_VDD1
   35  PVCCFA_EHV_FIVRA_CPU1_VDD1     EN  @S9S_MB_2U_LIB.S9S_MB_2U(SCH_1):PVCCFA_EHV_FIVRA_CPU1_VDD1
   34  PVCCFA_EHV_FIVRA_CPU1_PWM1    PWM  @S9S_MB_2U_LIB.S9S_MB_2U(SCH_1):PVCCFA_EHV_FIVRA_CPU1_PWM1
    4  PVCCFA_EHV_FIVRA_CPU1_PVCC1   PVCC  @S9S_MB_2U_LIB.S9S_MB_2U(SCH_1):PVCCFA_EHV_FIVRA_CPU1_PVCC1
   37  PVCCFA_EHV_FIVRA_CPU1_LSET1   LSET  @S9S_MB_2U_LIB.S9S_MB_2U(SCH_1):PVCCFA_EHV_FIVRA_CPU1_LSET1
   38  PVCCFA_EHV_FIVRA_CPU1_IMON1   IOUT  @S9S_MB_2U_LIB.S9S_MB_2U(SCH_1):PVCCFA_EHV_FIVRA_CPU1_IMON1
   41  NC               GL2  NC
    6  NC               GL1  NC
   31  NC               DNC  NC
   40  GND            PGND3  @S9S_MB_2U_LIB.S9S_MB_2U(SCH_1):GND
  7_9-20_24  GND            PGND2  @S9S_MB_2U_LIB.S9S_MB_2U(SCH_1):GND
    5  GND            PGND1  @S9S_MB_2U_LIB.S9S_MB_2U(SCH_1):GND
    2  GND             AGND  @S9S_MB_2U_LIB.S9S_MB_2U(SCH_1):GND

ISL99390FRZTR5935  I221  PU76_P1_2  [ISL99390FRZTR5935-ISL99390FRZ-A]
  10_19  SW_PVCCFA_EHV_FIVRA_CPU1_SW2     SW  @S9S_MB_2U_LIB.S9S_MB_2U(SCH_1):SW_PVCCFA_EHV_FIVRA_CPU1_SW2
   32  SW_PVCCFA_EHV_FIVRA_CPU1_BOOTR2  PHASE  @S9S_MB_2U_LIB.S9S_MB_2U(SCH_1):SW_PVCCFA_EHV_FIVRA_CPU1_BOOTR2
   33  SW_PVCCFA_EHV_FIVRA_CPU1_BOOT2   BOOT  @S9S_MB_2U_LIB.S9S_MB_2U(SCH_1):SW_PVCCFA_EHV_FIVRA_CPU1_BOOT2
   30  SW_P12V_PVCCFA_EHV_FIVRA_CPU1_L   VIN2  @S9S_MB_2U_LIB.S9S_MB_2U(SCH_1):SW_P12V_PVCCFA_EHV_FIVRA_CPU1_L
  25_29  SW_P12V_PVCCFA_EHV_FIVRA_CPU1_L   VIN1  @S9S_MB_2U_LIB.S9S_MB_2U(SCH_1):SW_P12V_PVCCFA_EHV_FIVRA_CPU1_L
   39  PVCCIN_CPU1_VREF  REFIN  @S9S_MB_2U_LIB.S9S_MB_2U(SCH_1):PVCCIN_CPU1_VREF
   36  PVCCIN_CPU1_ATSEN  TOUT_FLT  @S9S_MB_2U_LIB.S9S_MB_2U(SCH_1):PVCCIN_CPU1_ATSEN
    1  PVCCFA_EHV_FIVRA_CPU1_VOS2    VOS  @S9S_MB_2U_LIB.S9S_MB_2U(SCH_1):PVCCFA_EHV_FIVRA_CPU1_VOS2
    3  PVCCFA_EHV_FIVRA_CPU1_VDD2    VCC  @S9S_MB_2U_LIB.S9S_MB_2U(SCH_1):PVCCFA_EHV_FIVRA_CPU1_VDD2
   35  PVCCFA_EHV_FIVRA_CPU1_VDD2     EN  @S9S_MB_2U_LIB.S9S_MB_2U(SCH_1):PVCCFA_EHV_FIVRA_CPU1_VDD2
   34  PVCCFA_EHV_FIVRA_CPU1_PWM2    PWM  @S9S_MB_2U_LIB.S9S_MB_2U(SCH_1):PVCCFA_EHV_FIVRA_CPU1_PWM2
    4  PVCCFA_EHV_FIVRA_CPU1_PVCC2   PVCC  @S9S_MB_2U_LIB.S9S_MB_2U(SCH_1):PVCCFA_EHV_FIVRA_CPU1_PVCC2
   37  PVCCFA_EHV_FIVRA_CPU1_LSET2   LSET  @S9S_MB_2U_LIB.S9S_MB_2U(SCH_1):PVCCFA_EHV_FIVRA_CPU1_LSET2
   38  PVCCFA_EHV_FIVRA_CPU1_IMON2   IOUT  @S9S_MB_2U_LIB.S9S_MB_2U(SCH_1):PVCCFA_EHV_FIVRA_CPU1_IMON2
   41  NC               GL2  NC
    6  NC               GL1  NC
   31  NC               DNC  NC
   40  GND            PGND3  @S9S_MB_2U_LIB.S9S_MB_2U(SCH_1):GND
  7_9-20_24  GND            PGND2  @S9S_MB_2U_LIB.S9S_MB_2U(SCH_1):GND
    5  GND            PGND1  @S9S_MB_2U_LIB.S9S_MB_2U(SCH_1):GND
    2  GND             AGND  @S9S_MB_2U_LIB.S9S_MB_2U(SCH_1):GND

ISL99390FRZTR5935  I27  PU77_P1_3  [ISL99390FRZTR5935-ISL99390FRZ-A]
  10_19  SW_PVCCFA_EHV_FIVRA_CPU1_SW3     SW  @S9S_MB_2U_LIB.S9S_MB_2U(SCH_1):SW_PVCCFA_EHV_FIVRA_CPU1_SW3
   32  SW_PVCCFA_EHV_FIVRA_CPU1_BOOTR3  PHASE  @S9S_MB_2U_LIB.S9S_MB_2U(SCH_1):SW_PVCCFA_EHV_FIVRA_CPU1_BOOTR3
   33  SW_PVCCFA_EHV_FIVRA_CPU1_BOOT3   BOOT  @S9S_MB_2U_LIB.S9S_MB_2U(SCH_1):SW_PVCCFA_EHV_FIVRA_CPU1_BOOT3
   30  SW_P12V_PVCCFA_EHV_FIVRA_CPU1_R   VIN2  @S9S_MB_2U_LIB.S9S_MB_2U(SCH_1):SW_P12V_PVCCFA_EHV_FIVRA_CPU1_R
  25_29  SW_P12V_PVCCFA_EHV_FIVRA_CPU1_R   VIN1  @S9S_MB_2U_LIB.S9S_MB_2U(SCH_1):SW_P12V_PVCCFA_EHV_FIVRA_CPU1_R
   39  PVCCIN_CPU1_VREF  REFIN  @S9S_MB_2U_LIB.S9S_MB_2U(SCH_1):PVCCIN_CPU1_VREF
   36  PVCCIN_CPU1_ATSEN  TOUT_FLT  @S9S_MB_2U_LIB.S9S_MB_2U(SCH_1):PVCCIN_CPU1_ATSEN
    1  PVCCFA_EHV_FIVRA_CPU1_VOS3    VOS  @S9S_MB_2U_LIB.S9S_MB_2U(SCH_1):PVCCFA_EHV_FIVRA_CPU1_VOS3
    3  PVCCFA_EHV_FIVRA_CPU1_VDD3    VCC  @S9S_MB_2U_LIB.S9S_MB_2U(SCH_1):PVCCFA_EHV_FIVRA_CPU1_VDD3
   35  PVCCFA_EHV_FIVRA_CPU1_VDD3     EN  @S9S_MB_2U_LIB.S9S_MB_2U(SCH_1):PVCCFA_EHV_FIVRA_CPU1_VDD3
   34  PVCCFA_EHV_FIVRA_CPU1_PWM3    PWM  @S9S_MB_2U_LIB.S9S_MB_2U(SCH_1):PVCCFA_EHV_FIVRA_CPU1_PWM3
    4  PVCCFA_EHV_FIVRA_CPU1_PVCC1   PVCC  @S9S_MB_2U_LIB.S9S_MB_2U(SCH_1):PVCCFA_EHV_FIVRA_CPU1_PVCC1
   37  PVCCFA_EHV_FIVRA_CPU1_LSET3   LSET  @S9S_MB_2U_LIB.S9S_MB_2U(SCH_1):PVCCFA_EHV_FIVRA_CPU1_LSET3
   38  PVCCFA_EHV_FIVRA_CPU1_IMON3   IOUT  @S9S_MB_2U_LIB.S9S_MB_2U(SCH_1):PVCCFA_EHV_FIVRA_CPU1_IMON3
   41  NC               GL2  NC
    6  NC               GL1  NC
   31  NC               DNC  NC
   40  GND            PGND3  @S9S_MB_2U_LIB.S9S_MB_2U(SCH_1):GND
  7_9-20_24  GND            PGND2  @S9S_MB_2U_LIB.S9S_MB_2U(SCH_1):GND
    5  GND            PGND1  @S9S_MB_2U_LIB.S9S_MB_2U(SCH_1):GND
    2  GND             AGND  @S9S_MB_2U_LIB.S9S_MB_2U(SCH_1):GND

ISL99390FRZTR5935  I24  PU78_P1_4  [ISL99390FRZTR5935-ISL99390FRZ-A]
  10_19  SW_PVCCFA_EHV_FIVRA_CPU1_SW4     SW  @S9S_MB_2U_LIB.S9S_MB_2U(SCH_1):SW_PVCCFA_EHV_FIVRA_CPU1_SW4
   32  SW_PVCCFA_EHV_FIVRA_CPU1_BOOTR4  PHASE  @S9S_MB_2U_LIB.S9S_MB_2U(SCH_1):SW_PVCCFA_EHV_FIVRA_CPU1_BOOTR4
   33  SW_PVCCFA_EHV_FIVRA_CPU1_BOOT4   BOOT  @S9S_MB_2U_LIB.S9S_MB_2U(SCH_1):SW_PVCCFA_EHV_FIVRA_CPU1_BOOT4
   30  SW_P12V_PVCCFA_EHV_FIVRA_CPU1_L   VIN2  @S9S_MB_2U_LIB.S9S_MB_2U(SCH_1):SW_P12V_PVCCFA_EHV_FIVRA_CPU1_L
  25_29  SW_P12V_PVCCFA_EHV_FIVRA_CPU1_L   VIN1  @S9S_MB_2U_LIB.S9S_MB_2U(SCH_1):SW_P12V_PVCCFA_EHV_FIVRA_CPU1_L
   39  PVCCIN_CPU1_VREF  REFIN  @S9S_MB_2U_LIB.S9S_MB_2U(SCH_1):PVCCIN_CPU1_VREF
   36  PVCCIN_CPU1_ATSEN  TOUT_FLT  @S9S_MB_2U_LIB.S9S_MB_2U(SCH_1):PVCCIN_CPU1_ATSEN
    1  PVCCFA_EHV_FIVRA_CPU1_VOS4    VOS  @S9S_MB_2U_LIB.S9S_MB_2U(SCH_1):PVCCFA_EHV_FIVRA_CPU1_VOS4
    3  PVCCFA_EHV_FIVRA_CPU1_VDD4    VCC  @S9S_MB_2U_LIB.S9S_MB_2U(SCH_1):PVCCFA_EHV_FIVRA_CPU1_VDD4
   35  PVCCFA_EHV_FIVRA_CPU1_VDD4     EN  @S9S_MB_2U_LIB.S9S_MB_2U(SCH_1):PVCCFA_EHV_FIVRA_CPU1_VDD4
   34  PVCCFA_EHV_FIVRA_CPU1_PWM4    PWM  @S9S_MB_2U_LIB.S9S_MB_2U(SCH_1):PVCCFA_EHV_FIVRA_CPU1_PWM4
    4  PVCCFA_EHV_FIVRA_CPU1_PVCC2   PVCC  @S9S_MB_2U_LIB.S9S_MB_2U(SCH_1):PVCCFA_EHV_FIVRA_CPU1_PVCC2
   37  PVCCFA_EHV_FIVRA_CPU1_LSET4   LSET  @S9S_MB_2U_LIB.S9S_MB_2U(SCH_1):PVCCFA_EHV_FIVRA_CPU1_LSET4
   38  PVCCFA_EHV_FIVRA_CPU1_IMON4   IOUT  @S9S_MB_2U_LIB.S9S_MB_2U(SCH_1):PVCCFA_EHV_FIVRA_CPU1_IMON4
   41  NC               GL2  NC
    6  NC               GL1  NC
   31  NC               DNC  NC
   40  GND            PGND3  @S9S_MB_2U_LIB.S9S_MB_2U(SCH_1):GND
  7_9-20_24  GND            PGND2  @S9S_MB_2U_LIB.S9S_MB_2U(SCH_1):GND
    5  GND            PGND1  @S9S_MB_2U_LIB.S9S_MB_2U(SCH_1):GND
    2  GND             AGND  @S9S_MB_2U_LIB.S9S_MB_2U(SCH_1):GND

MPQ8633AGLEC807Z  I13  PU79   [MPQ8633AGLEC807Z-MPQ8633AGLE-CA]
   20  SW_PVPP_HBM_CPU0_SW     SW  @S9S_MB_2U_LIB.S9S_MB_2U(SCH_1):SW_PVPP_HBM_CPU0_SW
    1  SW_PVPP_HBM_CPU0_BST    BST  @S9S_MB_2U_LIB.S9S_MB_2U(SCH_1):SW_PVPP_HBM_CPU0_BST
   21  SW_P12V_PVCCIN_CPU0_FLT   VIN2  @S9S_MB_2U_LIB.S9S_MB_2U(SCH_1):SW_P12V_PVCCIN_CPU0_FLT
   10  SW_P12V_PVCCIN_CPU0_FLT   VIN1  @S9S_MB_2U_LIB.S9S_MB_2U(SCH_1):SW_P12V_PVCCIN_CPU0_FLT
    6  SH_PVPP_HBM_CPU0_N   RGND  @S9S_MB_2U_LIB.S9S_MB_2U(SCH_1):SH_PVPP_HBM_CPU0_N
    9  PWRGD_PVPP_HBM_CPU0_R  PGOOD  @S9S_MB_2U_LIB.S9S_MB_2U(SCH_1):PWRGD_PVPP_HBM_CPU0_R
   19  PVPP_HBM_CPU0_VCC    VCC  @S9S_MB_2U_LIB.S9S_MB_2U(SCH_1):PVPP_HBM_CPU0_VCC
    4  PVPP_HBM_CPU0_VCC   MODE  @S9S_MB_2U_LIB.S9S_MB_2U(SCH_1):PVPP_HBM_CPU0_VCC
    5  PVPP_HBM_CPU0_REF  TRK_REF  @S9S_MB_2U_LIB.S9S_MB_2U(SCH_1):PVPP_HBM_CPU0_REF
    7  PVPP_HBM_CPU0_FB     FB  @S9S_MB_2U_LIB.S9S_MB_2U(SCH_1):PVPP_HBM_CPU0_FB
    3  PVPP_HBM_CPU0_CS     CS  @S9S_MB_2U_LIB.S9S_MB_2U(SCH_1):PVPP_HBM_CPU0_CS
  11_18  GND             PGND  @S9S_MB_2U_LIB.S9S_MB_2U(SCH_1):GND
    2  GND             AGND  @S9S_MB_2U_LIB.S9S_MB_2U(SCH_1):GND
    8  FM_PVPP_HBM_CPU0_EN     EN  @S9S_MB_2U_LIB.S9S_MB_2U(SCH_1):FM_PVPP_HBM_CPU0_EN

MPQ8633AGLEC807Z  I15  PU80   [MPQ8633AGLEC807Z-MPQ8633AGLE-CB]
   20  SW_PVPP_HBM_CPU1_SW     SW  @S9S_MB_2U_LIB.S9S_MB_2U(SCH_1):SW_PVPP_HBM_CPU1_SW
    1  SW_PVPP_HBM_CPU1_BST    BST  @S9S_MB_2U_LIB.S9S_MB_2U(SCH_1):SW_PVPP_HBM_CPU1_BST
   21  SW_P12V_PVCCIN_CPU1_FLT   VIN2  @S9S_MB_2U_LIB.S9S_MB_2U(SCH_1):SW_P12V_PVCCIN_CPU1_FLT
   10  SW_P12V_PVCCIN_CPU1_FLT   VIN1  @S9S_MB_2U_LIB.S9S_MB_2U(SCH_1):SW_P12V_PVCCIN_CPU1_FLT
    6  SH_PVPP_HBM_CPU1_N   RGND  @S9S_MB_2U_LIB.S9S_MB_2U(SCH_1):SH_PVPP_HBM_CPU1_N
    9  PWRGD_PVPP_HBM_CPU1_R  PGOOD  @S9S_MB_2U_LIB.S9S_MB_2U(SCH_1):PWRGD_PVPP_HBM_CPU1_R
   19  PVPP_HBM_CPU1_VCC    VCC  @S9S_MB_2U_LIB.S9S_MB_2U(SCH_1):PVPP_HBM_CPU1_VCC
    4  PVPP_HBM_CPU1_VCC   MODE  @S9S_MB_2U_LIB.S9S_MB_2U(SCH_1):PVPP_HBM_CPU1_VCC
    5  PVPP_HBM_CPU1_REF  TRK_REF  @S9S_MB_2U_LIB.S9S_MB_2U(SCH_1):PVPP_HBM_CPU1_REF
    7  PVPP_HBM_CPU1_FB     FB  @S9S_MB_2U_LIB.S9S_MB_2U(SCH_1):PVPP_HBM_CPU1_FB
    3  PVPP_HBM_CPU1_CS     CS  @S9S_MB_2U_LIB.S9S_MB_2U(SCH_1):PVPP_HBM_CPU1_CS
  11_18  GND             PGND  @S9S_MB_2U_LIB.S9S_MB_2U(SCH_1):GND
    2  GND             AGND  @S9S_MB_2U_LIB.S9S_MB_2U(SCH_1):GND
    8  FM_PVPP_HBM_CPU1_EN     EN  @S9S_MB_2U_LIB.S9S_MB_2U(SCH_1):FM_PVPP_HBM_CPU1_EN

MPQ8626GDZ  I190  PU81   [MPQ8626GDZ-MPQ8626GD-Z,SMLF,ICA]
   11  SW_PVNN_MAIN_CPU0_SW    SW2  @S9S_MB_2U_LIB.S9S_MB_2U(SCH_1):SW_PVNN_MAIN_CPU0_SW
    2  SW_PVNN_MAIN_CPU0_SW    SW1  @S9S_MB_2U_LIB.S9S_MB_2U(SCH_1):SW_PVNN_MAIN_CPU0_SW
   10  SW_PVNN_MAIN_CPU0_BST    BST  @S9S_MB_2U_LIB.S9S_MB_2U(SCH_1):SW_PVNN_MAIN_CPU0_BST
    3  SW_P12V_PVCCINFAON_CPU0_FLT    VIN  @S9S_MB_2U_LIB.S9S_MB_2U(SCH_1):SW_P12V_PVCCINFAON_CPU0_FLT
    9  PWRGD_PVNN_MAIN_CPU0_R  PGOOD  @S9S_MB_2U_LIB.S9S_MB_2U(SCH_1):PWRGD_PVNN_MAIN_CPU0_R
   13  PVNN_MAIN_CPU0_VCC    VCC  @S9S_MB_2U_LIB.S9S_MB_2U(SCH_1):PVNN_MAIN_CPU0_VCC
    8  PVNN_MAIN_CPU0_REF  TRK_REF  @S9S_MB_2U_LIB.S9S_MB_2U(SCH_1):PVNN_MAIN_CPU0_REF
   12  PVNN_MAIN_CPU0_MODE   MODE  @S9S_MB_2U_LIB.S9S_MB_2U(SCH_1):PVNN_MAIN_CPU0_MODE
    6  PVNN_MAIN_CPU0_FB_RC     FB  @S9S_MB_2U_LIB.S9S_MB_2U(SCH_1):PVNN_MAIN_CPU0_FB_RC
    4  PVNN_MAIN_CPU0_CS     CS  @S9S_MB_2U_LIB.S9S_MB_2U(SCH_1):PVNN_MAIN_CPU0_CS
   14  GND            PGND2  @S9S_MB_2U_LIB.S9S_MB_2U(SCH_1):GND
    1  GND            PGND1  @S9S_MB_2U_LIB.S9S_MB_2U(SCH_1):GND
    7  GND             AGND  @S9S_MB_2U_LIB.S9S_MB_2U(SCH_1):GND
    5  FM_PVNN_MAIN_CPU0_EN     EN  @S9S_MB_2U_LIB.S9S_MB_2U(SCH_1):FM_PVNN_MAIN_CPU0_EN

MPQ8626GDZ  I198  PU82   [MPQ8626GDZ-MPQ8626GD-Z,SMLF,ICA]
   11  SW_PVNN_MAIN_CPU1_SW    SW2  @S9S_MB_2U_LIB.S9S_MB_2U(SCH_1):SW_PVNN_MAIN_CPU1_SW
    2  SW_PVNN_MAIN_CPU1_SW    SW1  @S9S_MB_2U_LIB.S9S_MB_2U(SCH_1):SW_PVNN_MAIN_CPU1_SW
   10  SW_PVNN_MAIN_CPU1_BST    BST  @S9S_MB_2U_LIB.S9S_MB_2U(SCH_1):SW_PVNN_MAIN_CPU1_BST
    3  SW_P12V_PVCCINFAON_CPU1_FLT    VIN  @S9S_MB_2U_LIB.S9S_MB_2U(SCH_1):SW_P12V_PVCCINFAON_CPU1_FLT
    9  PWRGD_PVNN_MAIN_CPU1_R  PGOOD  @S9S_MB_2U_LIB.S9S_MB_2U(SCH_1):PWRGD_PVNN_MAIN_CPU1_R
   13  PVNN_MAIN_CPU1_VCC    VCC  @S9S_MB_2U_LIB.S9S_MB_2U(SCH_1):PVNN_MAIN_CPU1_VCC
    8  PVNN_MAIN_CPU1_REF  TRK_REF  @S9S_MB_2U_LIB.S9S_MB_2U(SCH_1):PVNN_MAIN_CPU1_REF
   12  PVNN_MAIN_CPU1_MODE   MODE  @S9S_MB_2U_LIB.S9S_MB_2U(SCH_1):PVNN_MAIN_CPU1_MODE
    6  PVNN_MAIN_CPU1_FB_RC     FB  @S9S_MB_2U_LIB.S9S_MB_2U(SCH_1):PVNN_MAIN_CPU1_FB_RC
    4  PVNN_MAIN_CPU1_CS     CS  @S9S_MB_2U_LIB.S9S_MB_2U(SCH_1):PVNN_MAIN_CPU1_CS
   14  GND            PGND2  @S9S_MB_2U_LIB.S9S_MB_2U(SCH_1):GND
    1  GND            PGND1  @S9S_MB_2U_LIB.S9S_MB_2U(SCH_1):GND
    7  GND             AGND  @S9S_MB_2U_LIB.S9S_MB_2U(SCH_1):GND
    5  FM_PVNN_MAIN_CPU1_EN     EN  @S9S_MB_2U_LIB.S9S_MB_2U(SCH_1):FM_PVNN_MAIN_CPU1_EN

MPQ8633BGLEC838Z  I19  PU181  [MPQ8633BGLEC838Z-MPQ8633BGLE-CA]
   20  SW_P5V_AUX_SW     SW  @S9S_MB_2U_LIB.S9S_MB_2U(SCH_1):SW_P5V_AUX_SW
   21  SW_P5V_AUX_FLT   VIN2  @S9S_MB_2U_LIB.S9S_MB_2U(SCH_1):SW_P5V_AUX_FLT
   10  SW_P5V_AUX_FLT   VIN1  @S9S_MB_2U_LIB.S9S_MB_2U(SCH_1):SW_P5V_AUX_FLT
    1  SW_P5V_AUX_BST    BST  @S9S_MB_2U_LIB.S9S_MB_2U(SCH_1):SW_P5V_AUX_BST
    9  PWRGD_P5V_AUX  PGOOD  @S9S_MB_2U_LIB.S9S_MB_2U(SCH_1):PWRGD_P5V_AUX
   19  P5V_AUX_VCC      VCC  @S9S_MB_2U_LIB.S9S_MB_2U(SCH_1):P5V_AUX_VCC
    4  P5V_AUX_VCC     MODE  @S9S_MB_2U_LIB.S9S_MB_2U(SCH_1):P5V_AUX_VCC
    5  P5V_AUX_REF    TRK_REF  @S9S_MB_2U_LIB.S9S_MB_2U(SCH_1):P5V_AUX_REF
    7  P5V_AUX_FB        FB  @S9S_MB_2U_LIB.S9S_MB_2U(SCH_1):P5V_AUX_FB
    8  P5V_AUX_EN        EN  @S9S_MB_2U_LIB.S9S_MB_2U(SCH_1):P5V_AUX_EN
    3  P5V_AUX_CS        CS  @S9S_MB_2U_LIB.S9S_MB_2U(SCH_1):P5V_AUX_CS
    6  GND             RGND  @S9S_MB_2U_LIB.S9S_MB_2U(SCH_1):GND
  11_18  GND             PGND  @S9S_MB_2U_LIB.S9S_MB_2U(SCH_1):GND
    2  GND             AGND  @S9S_MB_2U_LIB.S9S_MB_2U(SCH_1):GND

MOSFET_NCH_DUAL  I9   Q15    [MOSFET_NCH_DUAL-2N7002KDW,SMLFA]
    4  GND               S2  @S9S_MB_2U_LIB.S9S_MB_2U(SCH_1):GND
    5  FM_SMB_CPU0_ALERT_R1     G2  @S9S_MB_2U_LIB.S9S_MB_2U(SCH_1):FM_SMB_CPU0_ALERT_R1
    3  FM_PEHPCPU0_ALERT_N     D2  @S9S_MB_2U_LIB.S9S_MB_2U(SCH_1):FM_PEHPCPU0_ALERT_N

MOSFET_NCH_DUAL  I36  Q15    [MOSFET_NCH_DUAL-2N7002KDW,SMLFA]
    1  GND               S1  @S9S_MB_2U_LIB.S9S_MB_2U(SCH_1):GND
    2  FM_SMB_PEHPCPU0_PCIE_ALERT_R_N     G1  @S9S_MB_2U_LIB.S9S_MB_2U(SCH_1):FM_SMB_PEHPCPU0_PCIE_ALERT_R_N
    6  FM_SMB_CPU0_ALERT_R1     D1  @S9S_MB_2U_LIB.S9S_MB_2U(SCH_1):FM_SMB_CPU0_ALERT_R1

MOSFET_NCH_DUAL  I66  Q16    [MOSFET_NCH_DUAL-2N7002KDW,SMLFA]
    4  GND               S2  @S9S_MB_2U_LIB.S9S_MB_2U(SCH_1):GND
    5  FM_SMB_CPU1_ALERT_R1     G2  @S9S_MB_2U_LIB.S9S_MB_2U(SCH_1):FM_SMB_CPU1_ALERT_R1
    3  FM_PEHPCPU1_ALERT_N     D2  @S9S_MB_2U_LIB.S9S_MB_2U(SCH_1):FM_PEHPCPU1_ALERT_N

MOSFET_NCH_DUAL  I68  Q16    [MOSFET_NCH_DUAL-2N7002KDW,SMLFA]
    1  GND               S1  @S9S_MB_2U_LIB.S9S_MB_2U(SCH_1):GND
    2  FM_SMB_PEHPCPU1_PCIE_ALERT_R_N     G1  @S9S_MB_2U_LIB.S9S_MB_2U(SCH_1):FM_SMB_PEHPCPU1_PCIE_ALERT_R_N
    6  FM_SMB_CPU1_ALERT_R1     D1  @S9S_MB_2U_LIB.S9S_MB_2U(SCH_1):FM_SMB_CPU1_ALERT_R1

MOSFET_PCH_GDS_ESD_PROTECTED  I242  Q33    [MOSFET_PCH_GDS_ESD_PROTECTED-PA]
    D  P3V3_AUX           D  @S9S_MB_2U_LIB.S9S_MB_2U(SCH_1):P3V3_AUX
    S  LED_CPU_RMCA_CATERR_R      S  @S9S_MB_2U_LIB.S9S_MB_2U(SCH_1):LED_CPU_RMCA_CATERR_R
    G  CPU_RMCA_CATERR_LVT3_N      G  @S9S_MB_2U_LIB.S9S_MB_2U(SCH_1):CPU_RMCA_CATERR_LVT3_N

MOSFET_N_GSD  I81  Q34    [MOSFET_N_GSD-NX7002AK,SMLF,IC,A]
    D  RST_RTCRST_N   DRAIN  @S9S_MB_2U_LIB.S9S_MB_2U(SCH_1):RST_RTCRST_N
    G  RST_PFR_OVR_RTC   GATE  @S9S_MB_2U_LIB.S9S_MB_2U(SCH_1):RST_PFR_OVR_RTC
    S  GND            SOURCE  @S9S_MB_2U_LIB.S9S_MB_2U(SCH_1):GND

MOSFET_N_GSD  I86  Q35    [MOSFET_N_GSD-NX7002AK,SMLF,IC,A]
    D  RST_SRTCRST_N  DRAIN  @S9S_MB_2U_LIB.S9S_MB_2U(SCH_1):RST_SRTCRST_N
    G  RST_PFR_OVR_SRTC   GATE  @S9S_MB_2U_LIB.S9S_MB_2U(SCH_1):RST_PFR_OVR_SRTC
    S  GND            SOURCE  @S9S_MB_2U_LIB.S9S_MB_2U(SCH_1):GND

MOSFET_NCH_DUAL  I76  Q37    [MOSFET_NCH_DUAL-2N7002KDW,SMLFA]
    5  VR_P5V_EN_N       G2  @S9S_MB_2U_LIB.S9S_MB_2U(SCH_1):VR_P5V_EN_N
    3  VR_P5V_EN_D_R1     D2  @S9S_MB_2U_LIB.S9S_MB_2U(SCH_1):VR_P5V_EN_D_R1
    4  GND               S2  @S9S_MB_2U_LIB.S9S_MB_2U(SCH_1):GND

MOSFET_NCH_DUAL  I75  Q37    [MOSFET_NCH_DUAL-2N7002KDW,SMLFA]
    6  VR_P5V_EN_N       D1  @S9S_MB_2U_LIB.S9S_MB_2U(SCH_1):VR_P5V_EN_N
    2  VR_P5V_EN         G1  @S9S_MB_2U_LIB.S9S_MB_2U(SCH_1):VR_P5V_EN
    1  GND               S1  @S9S_MB_2U_LIB.S9S_MB_2U(SCH_1):GND

MOSFET_NCH_DUAL  I20  Q39    [MOSFET_NCH_DUAL-2N7002KDW,SMLFA]
    3  P12V_SCM_EN_N     D2  @S9S_MB_2U_LIB.S9S_MB_2U(SCH_1):P12V_SCM_EN_N
    4  GND               S2  @S9S_MB_2U_LIB.S9S_MB_2U(SCH_1):GND
    5  FM_SCM_PRSNT1_R_N     G2  @S9S_MB_2U_LIB.S9S_MB_2U(SCH_1):FM_SCM_PRSNT1_R_N

MOSFET_NCH_DUAL  I181  Q45    [MOSFET_NCH_DUAL-2N7002KDW,SMLFA]
    5  HP_LVC3_OCP_V3_1_PWRGD_N     G2  @S9S_MB_2U_LIB.S9S_MB_2U(SCH_1):HP_LVC3_OCP_V3_1_PWRGD_N
    3  HP_LVC3_OCP_V3_1_PWRGD     D2  @S9S_MB_2U_LIB.S9S_MB_2U(SCH_1):HP_LVC3_OCP_V3_1_PWRGD
    4  GND               S2  @S9S_MB_2U_LIB.S9S_MB_2U(SCH_1):GND

MOSFET_NCH_DUAL  I180  Q45    [MOSFET_NCH_DUAL-2N7002KDW,SMLFA]
    6  HP_LVC3_OCP_V3_1_PWRGD_N     D1  @S9S_MB_2U_LIB.S9S_MB_2U(SCH_1):HP_LVC3_OCP_V3_1_PWRGD_N
    2  HP_LVC3_OCP_V3_1_HSC_PWRGD     G1  @S9S_MB_2U_LIB.S9S_MB_2U(SCH_1):HP_LVC3_OCP_V3_1_HSC_PWRGD
    1  GND               S1  @S9S_MB_2U_LIB.S9S_MB_2U(SCH_1):GND

Q_RES  I18  R1     [Q_RES_0402LF-10,1%,1/16W,CHIP,A]
    1  H_CPU_PRDY_QS_GTL_N      A  @S9S_MB_2U_LIB.S9S_MB_2U(SCH_1):H_CPU_PRDY_QS_GTL_N
    2  H_CPU0_PRDY_QS_GTL_R_N      B  @S9S_MB_2U_LIB.S9S_MB_2U(SCH_1):H_CPU0_PRDY_QS_GTL_R_N

Q_RES  I16  R2     [Q_RES_0402LF-100,1%,1/16W,CHIPA]
    1  H_CPU_PREQ_QS_GTL_N      A  @S9S_MB_2U_LIB.S9S_MB_2U(SCH_1):H_CPU_PREQ_QS_GTL_N
    2  H_CPU0_PREQ_QS_GTL_R_N      B  @S9S_MB_2U_LIB.S9S_MB_2U(SCH_1):H_CPU0_PREQ_QS_GTL_R_N

Q_RES  I21  R3     [Q_RES_0402LF-33.2,1%,1/16W,CHIA]
    1  PECI_CPU_GTL       A  @S9S_MB_2U_LIB.S9S_MB_2U(SCH_1):PECI_CPU_GTL
    2  PECI_CPU0_GTL_R      B  @S9S_MB_2U_LIB.S9S_MB_2U(SCH_1):PECI_CPU0_GTL_R

Q_RES  I29  R4     [Q_RES_0402LF-200,1%,1/16W,CHIPA]
    1  JTAG_MUX_CPU0_GTL_TDI      A  @S9S_MB_2U_LIB.S9S_MB_2U(SCH_1):JTAG_MUX_CPU0_GTL_TDI
    2  JTAG_DBP_CPU0_GTL_R_TDI      B  @S9S_MB_2U_LIB.S9S_MB_2U(SCH_1):JTAG_DBP_CPU0_GTL_R_TDI

Q_RES  I24  R5     [Q_RES_0402LF-100,1%,1/16W,CHIPA]
    1  JTAG_DBP_CPU_GTL_TCK      A  @S9S_MB_2U_LIB.S9S_MB_2U(SCH_1):JTAG_DBP_CPU_GTL_TCK
    2  JTAG_DBP_CPU0_GTL_R_TCK      B  @S9S_MB_2U_LIB.S9S_MB_2U(SCH_1):JTAG_DBP_CPU0_GTL_R_TCK

Q_RES  I25  R6     [Q_RES_0402LF-100,1%,1/16W,CHIPA]
    1  JTAG_DBP_CPU_QS_GTL_TMS      A  @S9S_MB_2U_LIB.S9S_MB_2U(SCH_1):JTAG_DBP_CPU_QS_GTL_TMS
    2  JTAG_DBP_CPU0_QS_GTL_R_TMS      B  @S9S_MB_2U_LIB.S9S_MB_2U(SCH_1):JTAG_DBP_CPU0_QS_GTL_R_TMS

Q_RES  I66  R7     [Q_RES_0402LF-33.2,1%,1/16W,CHIA]
    1  H_CPU0_PMDOWN_PCH_R      A  @S9S_MB_2U_LIB.S9S_MB_2U(SCH_1):H_CPU0_PMDOWN_PCH_R
    2  H_CPU0_PMDOWN_PCH      B  @S9S_MB_2U_LIB.S9S_MB_2U(SCH_1):H_CPU0_PMDOWN_PCH

Q_RES  I59  R8     [Q_RES_0402LF-10K,1%,1/16W,CHIPA]
    1  P3V3_AUX           A  @S9S_MB_2U_LIB.S9S_MB_2U(SCH_1):P3V3_AUX
    2  FM_PS_PWROK_DLY_R_SEL      B  @S9S_MB_2U_LIB.S9S_MB_2U(SCH_1):FM_PS_PWROK_DLY_R_SEL

Q_RES  I57  R9     [Q_RES_0402LF-4.32K,1%,1/16W,CHA]
    1  PWRGD_S0_PWROK_CPU0_LVC1_R      A  @S9S_MB_2U_LIB.S9S_MB_2U(SCH_1):PWRGD_S0_PWROK_CPU0_LVC1_R
    2  GND                B  @S9S_MB_2U_LIB.S9S_MB_2U(SCH_1):GND

Q_RES  I78  R10    [Q_RES_0402LF-33.2,1%,1/16W,CHIA]
    1  H_CPU0_PMSYNC_PCH_R      A  @S9S_MB_2U_LIB.S9S_MB_2U(SCH_1):H_CPU0_PMSYNC_PCH_R
    2  H_CPU0_PMSYNC_PCH      B  @S9S_MB_2U_LIB.S9S_MB_2U(SCH_1):H_CPU0_PMSYNC_PCH

Q_RES  I79  R11    [Q_RES_0402LF-33.2,1%,1/16W,CHIA]
    2  H_CPU0_PMDOWN_CPU1_R      B  @S9S_MB_2U_LIB.S9S_MB_2U(SCH_1):H_CPU0_PMDOWN_CPU1_R
    1  H_CPU0_PMDOWN_CPU1      A  @S9S_MB_2U_LIB.S9S_MB_2U(SCH_1):H_CPU0_PMDOWN_CPU1

Q_RES  I59  R12    [Q_RES_0402LF-0,5%,1/16W,CHIP,CA]
    2  SVID_DIO0_CPU0_R      B  @S9S_MB_2U_LIB.S9S_MB_2U(SCH_1):SVID_DIO0_CPU0_R
    1  SVID_DIO0_CPU0      A  @S9S_MB_2U_LIB.S9S_MB_2U(SCH_1):SVID_DIO0_CPU0

Q_RES  I60  R13    [Q_RES_0402LF-0,5%,1/16W,CHIP,CA]
    2  SVID_CLK0_CPU0_R      B  @S9S_MB_2U_LIB.S9S_MB_2U(SCH_1):SVID_CLK0_CPU0_R
    1  SVID_CLK0_CPU0      A  @S9S_MB_2U_LIB.S9S_MB_2U(SCH_1):SVID_CLK0_CPU0

Q_RES  I61  R14    [Q_RES_0402LF-200,1%,1/16W,CHIPA]
    2  SVID_ALERT0_CPU0_R_N      B  @S9S_MB_2U_LIB.S9S_MB_2U(SCH_1):SVID_ALERT0_CPU0_R_N
    1  SVID_ALERT0_CPU0_N      A  @S9S_MB_2U_LIB.S9S_MB_2U(SCH_1):SVID_ALERT0_CPU0_N

Q_RES  I62  R15    [Q_RES_0402LF-0,5%,1/16W,CHIP,CA]
    2  SVID_DIO1_CPU0_R      B  @S9S_MB_2U_LIB.S9S_MB_2U(SCH_1):SVID_DIO1_CPU0_R
    1  SVID_DIO1_CPU0      A  @S9S_MB_2U_LIB.S9S_MB_2U(SCH_1):SVID_DIO1_CPU0

Q_RES  I63  R16    [Q_RES_0402LF-0,5%,1/16W,CHIP,CA]
    2  SVID_CLK1_CPU0_R      B  @S9S_MB_2U_LIB.S9S_MB_2U(SCH_1):SVID_CLK1_CPU0_R
    1  SVID_CLK1_CPU0      A  @S9S_MB_2U_LIB.S9S_MB_2U(SCH_1):SVID_CLK1_CPU0

Q_RES  I64  R17    [Q_RES_0402LF-200,1%,1/16W,CHIPA]
    2  SVID_ALERT1_CPU0_R_N      B  @S9S_MB_2U_LIB.S9S_MB_2U(SCH_1):SVID_ALERT1_CPU0_R_N
    1  SVID_ALERT1_CPU0_N      A  @S9S_MB_2U_LIB.S9S_MB_2U(SCH_1):SVID_ALERT1_CPU0_N

Q_RES  I35  R18    [Q_RES_0402LF-499,1%,1/16W,CHIPA]
    1  PVNN_TERM_CPU0      A  @S9S_MB_2U_LIB.S9S_MB_2U(SCH_1):PVNN_TERM_CPU0
    2  DBP_CPU_MBP0_GTL_N      B  @S9S_MB_2U_LIB.S9S_MB_2U(SCH_1):DBP_CPU_MBP0_GTL_N

Q_RES  I36  R19    [Q_RES_0402LF-499,1%,1/16W,CHIPA]
    1  PVNN_TERM_CPU0      A  @S9S_MB_2U_LIB.S9S_MB_2U(SCH_1):PVNN_TERM_CPU0
    2  DBP_CPU_MBP1_GTL_N      B  @S9S_MB_2U_LIB.S9S_MB_2U(SCH_1):DBP_CPU_MBP1_GTL_N

Q_RES  I31  R20    [Q_RES_0402LF-0,5%,1/16W,CHIP,CA]
    2  FM_PCH_TRIGGER0_N      B  @S9S_MB_2U_LIB.S9S_MB_2U(SCH_1):FM_PCH_TRIGGER0_N
    1  DBP_CPU_MBP0_GTL_N      A  @S9S_MB_2U_LIB.S9S_MB_2U(SCH_1):DBP_CPU_MBP0_GTL_N

Q_RES  I32  R21    [Q_RES_0402LF-0,5%,1/16W,CHIP,CA]
    2  FM_PCH_TRIGGER1_N      B  @S9S_MB_2U_LIB.S9S_MB_2U(SCH_1):FM_PCH_TRIGGER1_N
    1  DBP_CPU_MBP1_GTL_N      A  @S9S_MB_2U_LIB.S9S_MB_2U(SCH_1):DBP_CPU_MBP1_GTL_N

Q_RES  I19  R22    [Q_RES_0402LF-100,1%,1/16W,CHIPA]
    2  DBP_CPU_MBP0_GTL_N      B  @S9S_MB_2U_LIB.S9S_MB_2U(SCH_1):DBP_CPU_MBP0_GTL_N
    1  DBP_CPU0_MBP0_GTL_R_N      A  @S9S_MB_2U_LIB.S9S_MB_2U(SCH_1):DBP_CPU0_MBP0_GTL_R_N

Q_RES  I20  R23    [Q_RES_0402LF-100,1%,1/16W,CHIPA]
    2  DBP_CPU_MBP1_GTL_N      B  @S9S_MB_2U_LIB.S9S_MB_2U(SCH_1):DBP_CPU_MBP1_GTL_N
    1  DBP_CPU0_MBP1_GTL_R_N      A  @S9S_MB_2U_LIB.S9S_MB_2U(SCH_1):DBP_CPU0_MBP1_GTL_R_N

Q_RES  I25  R24    [Q_RES_0402LF-10,1%,1/16W,CHIP,A]
    2  DBP_CPU_HOOK8_MBP2_GTL_QS_N      B  @S9S_MB_2U_LIB.S9S_MB_2U(SCH_1):DBP_CPU_HOOK8_MBP2_GTL_QS_N
    1  DBP_CPU0_HOOK8_MBP2_GTL_QS_R_N      A  @S9S_MB_2U_LIB.S9S_MB_2U(SCH_1):DBP_CPU0_HOOK8_MBP2_GTL_QS_R_N

Q_RES  I26  R25    [Q_RES_0402LF-10,1%,1/16W,CHIP,A]
    2  DBP_CPU_HOOK9_MBP3_GTL_QS_N      B  @S9S_MB_2U_LIB.S9S_MB_2U(SCH_1):DBP_CPU_HOOK9_MBP3_GTL_QS_N
    1  DBP_CPU0_HOOK9_MBP3_GTL_QS_R_N      A  @S9S_MB_2U_LIB.S9S_MB_2U(SCH_1):DBP_CPU0_HOOK9_MBP3_GTL_QS_R_N

Q_RES  I196  R26    [Q_RES_0402LF-10K,1%,1/16W,CHIPA]
    1  PD_CHA_CPU0_DIMM1_SAA      A  @S9S_MB_2U_LIB.S9S_MB_2U(SCH_1):PD_CHA_CPU0_DIMM1_SAA
    2  GND                B  @S9S_MB_2U_LIB.S9S_MB_2U(SCH_1):GND

Q_RES  I10  R27    [Q_RES_0402LF-15.4K,1%,1/16W,CHA]
    1  PD_CHA_CPU0_DIMM2_SAA      A  @S9S_MB_2U_LIB.S9S_MB_2U(SCH_1):PD_CHA_CPU0_DIMM2_SAA
    2  GND                B  @S9S_MB_2U_LIB.S9S_MB_2U(SCH_1):GND

Q_RES  I10  R28    [Q_RES_0402LF-23.2K,1%,1/16W,CHA]
    1  PD_CHB_CPU0_DIMM1_SAA      A  @S9S_MB_2U_LIB.S9S_MB_2U(SCH_1):PD_CHB_CPU0_DIMM1_SAA
    2  GND                B  @S9S_MB_2U_LIB.S9S_MB_2U(SCH_1):GND

Q_RES  I1   R29    [Q_RES_0402LF-35.7K,1%,1/16W,CHA]
    1  PD_CHB_CPU0_DIMM2_SAA      A  @S9S_MB_2U_LIB.S9S_MB_2U(SCH_1):PD_CHB_CPU0_DIMM2_SAA
    2  GND                B  @S9S_MB_2U_LIB.S9S_MB_2U(SCH_1):GND

Q_RES  I3   R30    [Q_RES_0402LF-54.9K,1%,1/16W,CHA]
    1  PD_CHC_CPU0_DIMM1_SAA      A  @S9S_MB_2U_LIB.S9S_MB_2U(SCH_1):PD_CHC_CPU0_DIMM1_SAA
    2  GND                B  @S9S_MB_2U_LIB.S9S_MB_2U(SCH_1):GND

Q_RES  I45  R31    [Q_RES_0402LF-84.5K,1%,1/16W,CHA]
    1  PD_CHC_CPU0_DIMM2_SAA      A  @S9S_MB_2U_LIB.S9S_MB_2U(SCH_1):PD_CHC_CPU0_DIMM2_SAA
    2  GND                B  @S9S_MB_2U_LIB.S9S_MB_2U(SCH_1):GND

Q_RES  I2   R32    [Q_RES_0402LF-127K,1%,1/16W,CHIA]
    1  PD_CHD_CPU0_DIMM1_SAA      A  @S9S_MB_2U_LIB.S9S_MB_2U(SCH_1):PD_CHD_CPU0_DIMM1_SAA
    2  GND                B  @S9S_MB_2U_LIB.S9S_MB_2U(SCH_1):GND

Q_RES  I2   R33    [Q_RES_0402LF-196K,1%,1/16W,CHIA]
    1  PD_CHD_CPU0_DIMM2_SAA      A  @S9S_MB_2U_LIB.S9S_MB_2U(SCH_1):PD_CHD_CPU0_DIMM2_SAA
    2  GND                B  @S9S_MB_2U_LIB.S9S_MB_2U(SCH_1):GND

Q_RES  I11  R34    [Q_RES_0402LF-10K,1%,1/16W,CHIPA]
    1  PD_CHE_CPU0_DIMM1_SAA      A  @S9S_MB_2U_LIB.S9S_MB_2U(SCH_1):PD_CHE_CPU0_DIMM1_SAA
    2  GND                B  @S9S_MB_2U_LIB.S9S_MB_2U(SCH_1):GND

Q_RES  I2   R35    [Q_RES_0402LF-15.4K,1%,1/16W,CHA]
    1  PD_CHE_CPU0_DIMM2_SAA      A  @S9S_MB_2U_LIB.S9S_MB_2U(SCH_1):PD_CHE_CPU0_DIMM2_SAA
    2  GND                B  @S9S_MB_2U_LIB.S9S_MB_2U(SCH_1):GND

Q_RES  I2   R36    [Q_RES_0402LF-23.2K,1%,1/16W,CHA]
    1  PD_CHF_CPU0_DIMM1_SAA      A  @S9S_MB_2U_LIB.S9S_MB_2U(SCH_1):PD_CHF_CPU0_DIMM1_SAA
    2  GND                B  @S9S_MB_2U_LIB.S9S_MB_2U(SCH_1):GND

Q_RES  I2   R37    [Q_RES_0402LF-35.7K,1%,1/16W,CHA]
    1  PD_CHF_CPU0_DIMM2_SAA      A  @S9S_MB_2U_LIB.S9S_MB_2U(SCH_1):PD_CHF_CPU0_DIMM2_SAA
    2  GND                B  @S9S_MB_2U_LIB.S9S_MB_2U(SCH_1):GND

Q_RES  I10  R38    [Q_RES_0402LF-54.9K,1%,1/16W,CHA]
    1  PD_CHG_CPU0_DIMM1_SAA      A  @S9S_MB_2U_LIB.S9S_MB_2U(SCH_1):PD_CHG_CPU0_DIMM1_SAA
    2  GND                B  @S9S_MB_2U_LIB.S9S_MB_2U(SCH_1):GND

Q_RES  I46  R39    [Q_RES_0402LF-84.5K,1%,1/16W,CHA]
    1  PD_CHG_CPU0_DIMM2_SAA      A  @S9S_MB_2U_LIB.S9S_MB_2U(SCH_1):PD_CHG_CPU0_DIMM2_SAA
    2  GND                B  @S9S_MB_2U_LIB.S9S_MB_2U(SCH_1):GND

Q_RES  I47  R40    [Q_RES_0402LF-127K,1%,1/16W,CHIA]
    1  PD_CHH_CPU0_DIMM1_SAA      A  @S9S_MB_2U_LIB.S9S_MB_2U(SCH_1):PD_CHH_CPU0_DIMM1_SAA
    2  GND                B  @S9S_MB_2U_LIB.S9S_MB_2U(SCH_1):GND

Q_RES  I5   R41    [Q_RES_0402LF-196K,1%,1/16W,CHIA]
    1  PD_CHH_CPU0_DIMM2_SAA      A  @S9S_MB_2U_LIB.S9S_MB_2U(SCH_1):PD_CHH_CPU0_DIMM2_SAA
    2  GND                B  @S9S_MB_2U_LIB.S9S_MB_2U(SCH_1):GND

Q_RES  I11  R42    [Q_RES_0402LF-10K,1%,1/16W,CHIPA]
    1  PD_CHA_CPU1_DIMM1_SAA      A  @S9S_MB_2U_LIB.S9S_MB_2U(SCH_1):PD_CHA_CPU1_DIMM1_SAA
    2  GND                B  @S9S_MB_2U_LIB.S9S_MB_2U(SCH_1):GND

Q_RES  I2   R43    [Q_RES_0402LF-15.4K,1%,1/16W,CHA]
    1  PD_CHA_CPU1_DIMM2_SAA      A  @S9S_MB_2U_LIB.S9S_MB_2U(SCH_1):PD_CHA_CPU1_DIMM2_SAA
    2  GND                B  @S9S_MB_2U_LIB.S9S_MB_2U(SCH_1):GND

Q_RES  I3   R44    [Q_RES_0402LF-23.2K,1%,1/16W,CHA]
    1  PD_CHB_CPU1_DIMM1_SAA      A  @S9S_MB_2U_LIB.S9S_MB_2U(SCH_1):PD_CHB_CPU1_DIMM1_SAA
    2  GND                B  @S9S_MB_2U_LIB.S9S_MB_2U(SCH_1):GND

Q_RES  I46  R45    [Q_RES_0402LF-35.7K,1%,1/16W,CHA]
    1  PD_CHB_CPU1_DIMM2_SAA      A  @S9S_MB_2U_LIB.S9S_MB_2U(SCH_1):PD_CHB_CPU1_DIMM2_SAA
    2  GND                B  @S9S_MB_2U_LIB.S9S_MB_2U(SCH_1):GND

Q_RES  I2   R46    [Q_RES_0402LF-54.9K,1%,1/16W,CHA]
    1  PD_CHC_CPU1_DIMM1_SAA      A  @S9S_MB_2U_LIB.S9S_MB_2U(SCH_1):PD_CHC_CPU1_DIMM1_SAA
    2  GND                B  @S9S_MB_2U_LIB.S9S_MB_2U(SCH_1):GND

Q_RES  I2   R47    [Q_RES_0402LF-84.5K,1%,1/16W,CHA]
    1  PD_CHC_CPU1_DIMM2_SAA      A  @S9S_MB_2U_LIB.S9S_MB_2U(SCH_1):PD_CHC_CPU1_DIMM2_SAA
    2  GND                B  @S9S_MB_2U_LIB.S9S_MB_2U(SCH_1):GND

Q_RES  I2   R48    [Q_RES_0402LF-127K,1%,1/16W,CHIA]
    1  PD_CHD_CPU1_DIMM1_SAA      A  @S9S_MB_2U_LIB.S9S_MB_2U(SCH_1):PD_CHD_CPU1_DIMM1_SAA
    2  GND                B  @S9S_MB_2U_LIB.S9S_MB_2U(SCH_1):GND

Q_RES  I34  R49    [Q_RES_0402LF-499,1%,1/16W,CHIPA]
    1  PVNN_TERM_CPU1      A  @S9S_MB_2U_LIB.S9S_MB_2U(SCH_1):PVNN_TERM_CPU1
    2  DBP_CPU_MBP0_GTL_N      B  @S9S_MB_2U_LIB.S9S_MB_2U(SCH_1):DBP_CPU_MBP0_GTL_N

Q_RES  I35  R50    [Q_RES_0402LF-499,1%,1/16W,CHIPA]
    1  PVNN_TERM_CPU1      A  @S9S_MB_2U_LIB.S9S_MB_2U(SCH_1):PVNN_TERM_CPU1
    2  DBP_CPU_MBP1_GTL_N      B  @S9S_MB_2U_LIB.S9S_MB_2U(SCH_1):DBP_CPU_MBP1_GTL_N

Q_RES  I24  R51    [Q_RES_0402LF-100,1%,1/16W,CHIPA]
    2  DBP_CPU_MBP0_GTL_N      B  @S9S_MB_2U_LIB.S9S_MB_2U(SCH_1):DBP_CPU_MBP0_GTL_N
    1  DBP_CPU1_MBP0_GTL_R_N      A  @S9S_MB_2U_LIB.S9S_MB_2U(SCH_1):DBP_CPU1_MBP0_GTL_R_N

Q_RES  I25  R52    [Q_RES_0402LF-100,1%,1/16W,CHIPA]
    2  DBP_CPU_MBP1_GTL_N      B  @S9S_MB_2U_LIB.S9S_MB_2U(SCH_1):DBP_CPU_MBP1_GTL_N
    1  DBP_CPU1_MBP1_GTL_R_N      A  @S9S_MB_2U_LIB.S9S_MB_2U(SCH_1):DBP_CPU1_MBP1_GTL_R_N

Q_RES  I23  R53    [Q_RES_0402LF-10,1%,1/16W,CHIP,A]
    2  DBP_CPU_HOOK8_MBP2_GTL_QS_N      B  @S9S_MB_2U_LIB.S9S_MB_2U(SCH_1):DBP_CPU_HOOK8_MBP2_GTL_QS_N
    1  DBP_CPU1_HOOK8_MBP2_GTL_QS_R_N      A  @S9S_MB_2U_LIB.S9S_MB_2U(SCH_1):DBP_CPU1_HOOK8_MBP2_GTL_QS_R_N

Q_RES  I22  R54    [Q_RES_0402LF-10,1%,1/16W,CHIP,A]
    2  DBP_CPU_HOOK9_MBP3_GTL_QS_N      B  @S9S_MB_2U_LIB.S9S_MB_2U(SCH_1):DBP_CPU_HOOK9_MBP3_GTL_QS_N
    1  DBP_CPU1_HOOK9_MBP3_GTL_QS_R_N      A  @S9S_MB_2U_LIB.S9S_MB_2U(SCH_1):DBP_CPU1_HOOK9_MBP3_GTL_QS_R_N

Q_RES  I54  R55    [Q_RES_0402LF-0,5%,1/16W,CHIP,CA]
    2  SVID_DIO0_CPU1_R      B  @S9S_MB_2U_LIB.S9S_MB_2U(SCH_1):SVID_DIO0_CPU1_R
    1  SVID_DIO0_CPU1      A  @S9S_MB_2U_LIB.S9S_MB_2U(SCH_1):SVID_DIO0_CPU1

Q_RES  I55  R56    [Q_RES_0402LF-0,5%,1/16W,CHIP,CA]
    2  SVID_CLK0_CPU1_R      B  @S9S_MB_2U_LIB.S9S_MB_2U(SCH_1):SVID_CLK0_CPU1_R
    1  SVID_CLK0_CPU1      A  @S9S_MB_2U_LIB.S9S_MB_2U(SCH_1):SVID_CLK0_CPU1

Q_RES  I56  R57    [Q_RES_0402LF-200,1%,1/16W,CHIPA]
    2  SVID_ALERT0_CPU1_R_N      B  @S9S_MB_2U_LIB.S9S_MB_2U(SCH_1):SVID_ALERT0_CPU1_R_N
    1  SVID_ALERT0_CPU1_N      A  @S9S_MB_2U_LIB.S9S_MB_2U(SCH_1):SVID_ALERT0_CPU1_N

Q_RES  I51  R58    [Q_RES_0402LF-0,5%,1/16W,CHIP,CA]
    2  SVID_DIO1_CPU1_R      B  @S9S_MB_2U_LIB.S9S_MB_2U(SCH_1):SVID_DIO1_CPU1_R
    1  SVID_DIO1_CPU1      A  @S9S_MB_2U_LIB.S9S_MB_2U(SCH_1):SVID_DIO1_CPU1

Q_RES  I52  R59    [Q_RES_0402LF-0,5%,1/16W,CHIP,CA]
    2  SVID_CLK1_CPU1_R      B  @S9S_MB_2U_LIB.S9S_MB_2U(SCH_1):SVID_CLK1_CPU1_R
    1  SVID_CLK1_CPU1      A  @S9S_MB_2U_LIB.S9S_MB_2U(SCH_1):SVID_CLK1_CPU1

Q_RES  I53  R60    [Q_RES_0402LF-200,1%,1/16W,CHIPA]
    2  SVID_ALERT1_CPU1_R_N      B  @S9S_MB_2U_LIB.S9S_MB_2U(SCH_1):SVID_ALERT1_CPU1_R_N
    1  SVID_ALERT1_CPU1_N      A  @S9S_MB_2U_LIB.S9S_MB_2U(SCH_1):SVID_ALERT1_CPU1_N

Q_RES  I16  R61    [Q_RES_0402LF-10,1%,1/16W,CHIP,A]
    1  H_CPU_PRDY_QS_GTL_N      A  @S9S_MB_2U_LIB.S9S_MB_2U(SCH_1):H_CPU_PRDY_QS_GTL_N
    2  H_CPU1_PRDY_QS_GTL_R_N      B  @S9S_MB_2U_LIB.S9S_MB_2U(SCH_1):H_CPU1_PRDY_QS_GTL_R_N

Q_RES  I11  R62    [Q_RES_0402LF-100,1%,1/16W,CHIPA]
    1  H_CPU_PREQ_QS_GTL_N      A  @S9S_MB_2U_LIB.S9S_MB_2U(SCH_1):H_CPU_PREQ_QS_GTL_N
    2  H_CPU1_PREQ_QS_GTL_R_N      B  @S9S_MB_2U_LIB.S9S_MB_2U(SCH_1):H_CPU1_PREQ_QS_GTL_R_N

Q_RES  I10  R63    [Q_RES_0402LF-33.2,1%,1/16W,CHIA]
    1  PECI_CPU_GTL       A  @S9S_MB_2U_LIB.S9S_MB_2U(SCH_1):PECI_CPU_GTL
    2  PECI_CPU1_GTL_R      B  @S9S_MB_2U_LIB.S9S_MB_2U(SCH_1):PECI_CPU1_GTL_R

Q_RES  I9   R64    [Q_RES_0402LF-200,1%,1/16W,CHIPA]
    1  JTAG_MUX_CPU1_GTL_TDI      A  @S9S_MB_2U_LIB.S9S_MB_2U(SCH_1):JTAG_MUX_CPU1_GTL_TDI
    2  JTAG_DBP_CPU1_GTL_R_TDI      B  @S9S_MB_2U_LIB.S9S_MB_2U(SCH_1):JTAG_DBP_CPU1_GTL_R_TDI

Q_RES  I8   R65    [Q_RES_0402LF-100,1%,1/16W,CHIPA]
    1  JTAG_DBP_CPU_GTL_TCK      A  @S9S_MB_2U_LIB.S9S_MB_2U(SCH_1):JTAG_DBP_CPU_GTL_TCK
    2  JTAG_DBP_CPU1_GTL_R_TCK      B  @S9S_MB_2U_LIB.S9S_MB_2U(SCH_1):JTAG_DBP_CPU1_GTL_R_TCK

Q_RES  I7   R66    [Q_RES_0402LF-100,1%,1/16W,CHIPA]
    1  JTAG_DBP_CPU_QS_GTL_TMS      A  @S9S_MB_2U_LIB.S9S_MB_2U(SCH_1):JTAG_DBP_CPU_QS_GTL_TMS
    2  JTAG_DBP_CPU1_QS_GTL_R_TMS      B  @S9S_MB_2U_LIB.S9S_MB_2U(SCH_1):JTAG_DBP_CPU1_QS_GTL_R_TMS

Q_RES  I12  R67    [Q_RES_0402LF-33.2,1%,1/16W,CHIA]
    1  PWRGD_PLT_AUX_CPU0_LVT3_R      A  @S9S_MB_2U_LIB.S9S_MB_2U(SCH_1):PWRGD_PLT_AUX_CPU0_LVT3_R
    2  PWRGD_PLT_AUX_CPU0_LVT3      B  @S9S_MB_2U_LIB.S9S_MB_2U(SCH_1):PWRGD_PLT_AUX_CPU0_LVT3

Q_RES  I13  R68    [Q_RES_0402LF-33.2,1%,1/16W,CHIA]
    1  PWRGD_PLT_AUX_CPU1_LVT3_R      A  @S9S_MB_2U_LIB.S9S_MB_2U(SCH_1):PWRGD_PLT_AUX_CPU1_LVT3_R
    2  PWRGD_PLT_AUX_CPU1_LVT3      B  @S9S_MB_2U_LIB.S9S_MB_2U(SCH_1):PWRGD_PLT_AUX_CPU1_LVT3

Q_RES  I16  R69    [Q_RES_0402LF-10K,1%,1/16W,CHIPA]
    1  PWRGD_PLT_AUX_CPU0_LVT3      A  @S9S_MB_2U_LIB.S9S_MB_2U(SCH_1):PWRGD_PLT_AUX_CPU0_LVT3
    2  GND                B  @S9S_MB_2U_LIB.S9S_MB_2U(SCH_1):GND

Q_RES  I17  R70    [Q_RES_0402LF-10K,1%,1/16W,CHIPA]
    1  PWRGD_PLT_AUX_CPU1_LVT3      A  @S9S_MB_2U_LIB.S9S_MB_2U(SCH_1):PWRGD_PLT_AUX_CPU1_LVT3
    2  GND                B  @S9S_MB_2U_LIB.S9S_MB_2U(SCH_1):GND

Q_RES  I60  R71    [Q_RES_0402LF-10K,1%,1/16W,CHIPA]
    1  P3V3_AUX           A  @S9S_MB_2U_LIB.S9S_MB_2U(SCH_1):P3V3_AUX
    2  FM_ME_BT_DONE      B  @S9S_MB_2U_LIB.S9S_MB_2U(SCH_1):FM_ME_BT_DONE

Q_RES  I2   R72    [Q_RES_0402LF-196K,1%,1/16W,CHIA]
    1  PD_CHH_CPU1_DIMM2_SAA      A  @S9S_MB_2U_LIB.S9S_MB_2U(SCH_1):PD_CHH_CPU1_DIMM2_SAA
    2  GND                B  @S9S_MB_2U_LIB.S9S_MB_2U(SCH_1):GND

Q_RES  I3   R73    [Q_RES_0402LF-127K,1%,1/16W,CHIA]
    1  PD_CHH_CPU1_DIMM1_SAA      A  @S9S_MB_2U_LIB.S9S_MB_2U(SCH_1):PD_CHH_CPU1_DIMM1_SAA
    2  GND                B  @S9S_MB_2U_LIB.S9S_MB_2U(SCH_1):GND

Q_RES  I5   R74    [Q_RES_0402LF-84.5K,1%,1/16W,CHA]
    1  PD_CHG_CPU1_DIMM2_SAA      A  @S9S_MB_2U_LIB.S9S_MB_2U(SCH_1):PD_CHG_CPU1_DIMM2_SAA
    2  GND                B  @S9S_MB_2U_LIB.S9S_MB_2U(SCH_1):GND

Q_RES  I47  R75    [Q_RES_0402LF-54.9K,1%,1/16W,CHA]
    1  PD_CHG_CPU1_DIMM1_SAA      A  @S9S_MB_2U_LIB.S9S_MB_2U(SCH_1):PD_CHG_CPU1_DIMM1_SAA
    2  GND                B  @S9S_MB_2U_LIB.S9S_MB_2U(SCH_1):GND

Q_RES  I46  R76    [Q_RES_0402LF-35.7K,1%,1/16W,CHA]
    1  PD_CHF_CPU1_DIMM2_SAA      A  @S9S_MB_2U_LIB.S9S_MB_2U(SCH_1):PD_CHF_CPU1_DIMM2_SAA
    2  GND                B  @S9S_MB_2U_LIB.S9S_MB_2U(SCH_1):GND

Q_RES  I10  R77    [Q_RES_0402LF-23.2K,1%,1/16W,CHA]
    1  PD_CHF_CPU1_DIMM1_SAA      A  @S9S_MB_2U_LIB.S9S_MB_2U(SCH_1):PD_CHF_CPU1_DIMM1_SAA
    2  GND                B  @S9S_MB_2U_LIB.S9S_MB_2U(SCH_1):GND

Q_RES  I2   R78    [Q_RES_0402LF-15.4K,1%,1/16W,CHA]
    1  PD_CHE_CPU1_DIMM2_SAA      A  @S9S_MB_2U_LIB.S9S_MB_2U(SCH_1):PD_CHE_CPU1_DIMM2_SAA
    2  GND                B  @S9S_MB_2U_LIB.S9S_MB_2U(SCH_1):GND

Q_RES  I2   R79    [Q_RES_0402LF-10K,1%,1/16W,CHIPA]
    1  PD_CHE_CPU1_DIMM1_SAA      A  @S9S_MB_2U_LIB.S9S_MB_2U(SCH_1):PD_CHE_CPU1_DIMM1_SAA
    2  GND                B  @S9S_MB_2U_LIB.S9S_MB_2U(SCH_1):GND

Q_RES  I2   R80    [Q_RES_0402LF-196K,1%,1/16W,CHIA]
    1  PD_CHD_CPU1_DIMM2_SAA      A  @S9S_MB_2U_LIB.S9S_MB_2U(SCH_1):PD_CHD_CPU1_DIMM2_SAA
    2  GND                B  @S9S_MB_2U_LIB.S9S_MB_2U(SCH_1):GND

Q_RES  I310  R85    [Q_RES_0402LF-10K,5%,1/16W,EMPTA]
    1  P3V3_AUX           A  @S9S_MB_2U_LIB.S9S_MB_2U(SCH_1):P3V3_AUX
    2  FM_SYS_THROTTLE_R_N      B  @S9S_MB_2U_LIB.S9S_MB_2U(SCH_1):FM_SYS_THROTTLE_R_N

Q_RES  I240  R86    [Q_RES_0402LF-10K,5%,1/16W,EMPTA]
    1  P3V3_AUX           A  @S9S_MB_2U_LIB.S9S_MB_2U(SCH_1):P3V3_AUX
    2  FM_SYS_THROTTLE_R_N      B  @S9S_MB_2U_LIB.S9S_MB_2U(SCH_1):FM_SYS_THROTTLE_R_N

Q_RES  I79  R87    [Q_RES_0402LF-1K,5%,1/16W,EMPTYA]
    1  P3V3_AUX           A  @S9S_MB_2U_LIB.S9S_MB_2U(SCH_1):P3V3_AUX
    2  FM_SPD_REMOTE_EN      B  @S9S_MB_2U_LIB.S9S_MB_2U(SCH_1):FM_SPD_REMOTE_EN

Q_RES  I135  R90    [Q_RES_0402LF-240,1%,1/16W,EMPTA]
    1  PVNN_TERM_CPU1      A  @S9S_MB_2U_LIB.S9S_MB_2U(SCH_1):PVNN_TERM_CPU1
    2  PU_CPU1_UPI0_AC_COUPLING      B  @S9S_MB_2U_LIB.S9S_MB_2U(SCH_1):PU_CPU1_UPI0_AC_COUPLING

Q_RES  I136  R91    [Q_RES_0402LF-240,1%,1/16W,EMPTA]
    1  PVNN_TERM_CPU1      A  @S9S_MB_2U_LIB.S9S_MB_2U(SCH_1):PVNN_TERM_CPU1
    2  PU_CPU1_UPI1_AC_COUPLING      B  @S9S_MB_2U_LIB.S9S_MB_2U(SCH_1):PU_CPU1_UPI1_AC_COUPLING

Q_RES  I140  R92    [Q_RES_0402LF-240,1%,1/16W,EMPTA]
    1  PVNN_TERM_CPU1      A  @S9S_MB_2U_LIB.S9S_MB_2U(SCH_1):PVNN_TERM_CPU1
    2  PU_CPU1_UPI2_AC_COUPLING      B  @S9S_MB_2U_LIB.S9S_MB_2U(SCH_1):PU_CPU1_UPI2_AC_COUPLING

Q_RES  I141  R93    [Q_RES_0402LF-240,1%,1/16W,EMPTA]
    1  PVNN_TERM_CPU1      A  @S9S_MB_2U_LIB.S9S_MB_2U(SCH_1):PVNN_TERM_CPU1
    2  PU_CPU1_UPI3_AC_COUPLING      B  @S9S_MB_2U_LIB.S9S_MB_2U(SCH_1):PU_CPU1_UPI3_AC_COUPLING

Q_RES  I25  R94    [Q_RES_0402LF-240,1%,1/16W,EMPTA]
    1  PVNN_TERM_CPU0      A  @S9S_MB_2U_LIB.S9S_MB_2U(SCH_1):PVNN_TERM_CPU0
    2  PU_CPU0_UPI0_AC_COUPLING      B  @S9S_MB_2U_LIB.S9S_MB_2U(SCH_1):PU_CPU0_UPI0_AC_COUPLING

Q_RES  I23  R95    [Q_RES_0402LF-240,1%,1/16W,EMPTA]
    1  PVNN_TERM_CPU0      A  @S9S_MB_2U_LIB.S9S_MB_2U(SCH_1):PVNN_TERM_CPU0
    2  PU_CPU0_UPI1_AC_COUPLING      B  @S9S_MB_2U_LIB.S9S_MB_2U(SCH_1):PU_CPU0_UPI1_AC_COUPLING

Q_RES  I22  R96    [Q_RES_0402LF-240,1%,1/16W,EMPTA]
    1  PVNN_TERM_CPU0      A  @S9S_MB_2U_LIB.S9S_MB_2U(SCH_1):PVNN_TERM_CPU0
    2  PU_CPU0_UPI2_AC_COUPLING      B  @S9S_MB_2U_LIB.S9S_MB_2U(SCH_1):PU_CPU0_UPI2_AC_COUPLING

Q_RES  I114  R97    [Q_RES_0402LF-240,1%,1/16W,EMPTA]
    1  PVNN_TERM_CPU0      A  @S9S_MB_2U_LIB.S9S_MB_2U(SCH_1):PVNN_TERM_CPU0
    2  PU_CPU0_UPI3_AC_COUPLING      B  @S9S_MB_2U_LIB.S9S_MB_2U(SCH_1):PU_CPU0_UPI3_AC_COUPLING

Q_RES  I84  R100   [Q_RES_0402LF-33,5%,1/16W,CHIP,A]
    2  H_CPU0_MON_FAIL_PLD_LVC1_N      B  @S9S_MB_2U_LIB.S9S_MB_2U(SCH_1):H_CPU0_MON_FAIL_PLD_LVC1_N
    1  H_CPU0_MON_FAIL_LVC1_R_N      A  @S9S_MB_2U_LIB.S9S_MB_2U(SCH_1):H_CPU0_MON_FAIL_LVC1_R_N

Q_RES  I108  R104   [Q_RES_0402LF-33,5%,1/16W,CHIP,A]
    2  H_CPU1_MON_FAIL_PLD_LVC1_N      B  @S9S_MB_2U_LIB.S9S_MB_2U(SCH_1):H_CPU1_MON_FAIL_PLD_LVC1_N
    1  H_CPU1_MON_FAIL_LVC1_R_N      A  @S9S_MB_2U_LIB.S9S_MB_2U(SCH_1):H_CPU1_MON_FAIL_LVC1_R_N

Q_RES  I304  R106   [Q_RES_0402LF-2K,1%,1/16W,CHIP,A]
    1  GND                A  @S9S_MB_2U_LIB.S9S_MB_2U(SCH_1):GND
    2  FM_PLD_CLKS_DEV_EN      B  @S9S_MB_2U_LIB.S9S_MB_2U(SCH_1):FM_PLD_CLKS_DEV_EN

Q_RES  I43  R107   [Q_RES_0402LF-0,5%,1/16W,CHIP,CA]
    2  SMB_HOST_DB2000_3V3AUX_SCL      B  @S9S_MB_2U_LIB.S9S_MB_2U(SCH_1):SMB_HOST_DB2000_3V3AUX_SCL
    1  SMB_HOST_3V3AUX_SCL_R      A  @S9S_MB_2U_LIB.S9S_MB_2U(SCH_1):SMB_HOST_3V3AUX_SCL_R

Q_RES  I42  R108   [Q_RES_0402LF-33.2,1%,1/16W,CHIA]
    2  SMB_HOST_DB2000_3V3AUX_SDA      B  @S9S_MB_2U_LIB.S9S_MB_2U(SCH_1):SMB_HOST_DB2000_3V3AUX_SDA
    1  SMB_HOST_3V3AUX_SDA_R      A  @S9S_MB_2U_LIB.S9S_MB_2U(SCH_1):SMB_HOST_3V3AUX_SDA_R

Q_RES  I44  R109   [Q_RES_0402LF-33.2,1%,1/16W,CHIA]
    1  FM_PLD_CLK_25M_R_EN      A  @S9S_MB_2U_LIB.S9S_MB_2U(SCH_1):FM_PLD_CLK_25M_R_EN
    2  FM_PLD_CLK_25M_EN      B  @S9S_MB_2U_LIB.S9S_MB_2U(SCH_1):FM_PLD_CLK_25M_EN

Q_RES  I17  R110   [Q_RES_0402LF-33.2,1%,1/16W,CHIA]
    1  FM_PLD_CLKS_DEV_R_EN      A  @S9S_MB_2U_LIB.S9S_MB_2U(SCH_1):FM_PLD_CLKS_DEV_R_EN
    2  FM_PLD_CLKS_DEV_EN      B  @S9S_MB_2U_LIB.S9S_MB_2U(SCH_1):FM_PLD_CLKS_DEV_EN

Q_RES  I24  R111   [Q_RES_0402LF-10K,1%,1/16W,CHIPA]
    1  P3V3_AUX           A  @S9S_MB_2U_LIB.S9S_MB_2U(SCH_1):P3V3_AUX
    2  FM_PLD_CLKS_OE_R_N      B  @S9S_MB_2U_LIB.S9S_MB_2U(SCH_1):FM_PLD_CLKS_OE_R_N

Q_RES  I413  R112   [Q_RES_0402LF-10K,1%,1/16W,EMPTA]
    1  P3V3               A  @S9S_MB_2U_LIB.S9S_MB_2U(SCH_1):P3V3
    2  HP_LVC3_OCP_V3_1_PRSNT2_N      B  @S9S_MB_2U_LIB.S9S_MB_2U(SCH_1):HP_LVC3_OCP_V3_1_PRSNT2_N

Q_RES  I27  R113   [Q_RES_0402LF-33.2,1%,1/16W,CHIA]
    1  FM_PLD_CLKS_OE_R_N      A  @S9S_MB_2U_LIB.S9S_MB_2U(SCH_1):FM_PLD_CLKS_OE_R_N
    2  FM_DB2000_OE_N      B  @S9S_MB_2U_LIB.S9S_MB_2U(SCH_1):FM_DB2000_OE_N

Q_RES  I74  R120   [Q_RES_0603LF-10M,1%,1/10W,CHIPA]
    1  XTAL_PCH_RTC2_R      A  @S9S_MB_2U_LIB.S9S_MB_2U(SCH_1):XTAL_PCH_RTC2_R
    2  XTAL_PCH_RTC1      B  @S9S_MB_2U_LIB.S9S_MB_2U(SCH_1):XTAL_PCH_RTC1

Q_RES  I17  R122   [Q_RES_0402LF-0,5%,1/16W,CHIP,CA]
    1  PWRGD_DRAMPWRGD_CPU1_AB_R_LVC1      A  @S9S_MB_2U_LIB.S9S_MB_2U(SCH_1):PWRGD_DRAMPWRGD_CPU1_AB_R_LVC1
    2  PWRGD_DRAMPWRGD_CPU1_AB_LVC1_R      B  @S9S_MB_2U_LIB.S9S_MB_2U(SCH_1):PWRGD_DRAMPWRGD_CPU1_AB_LVC1_R

Q_RES  I15  R124   [Q_RES_0402LF-0,5%,1/16W,CHIP,CA]
    1  PWRGD_DRAMPWRGD_CPU1_CD_R_LVC1      A  @S9S_MB_2U_LIB.S9S_MB_2U(SCH_1):PWRGD_DRAMPWRGD_CPU1_CD_R_LVC1
    2  PWRGD_DRAMPWRGD_CPU1_CD_LVC1_R      B  @S9S_MB_2U_LIB.S9S_MB_2U(SCH_1):PWRGD_DRAMPWRGD_CPU1_CD_LVC1_R

Q_RES  I13  R126   [Q_RES_0402LF-0,5%,1/16W,CHIP,CA]
    1  PWRGD_DRAMPWRGD_CPU1_EF_R_LVC1      A  @S9S_MB_2U_LIB.S9S_MB_2U(SCH_1):PWRGD_DRAMPWRGD_CPU1_EF_R_LVC1
    2  PWRGD_DRAMPWRGD_CPU1_EF_LVC1_R      B  @S9S_MB_2U_LIB.S9S_MB_2U(SCH_1):PWRGD_DRAMPWRGD_CPU1_EF_LVC1_R

Q_RES  I7   R128   [Q_RES_0402LF-0,5%,1/16W,CHIP,CA]
    1  PWRGD_DRAMPWRGD_CPU1_GH_R_LVC1      A  @S9S_MB_2U_LIB.S9S_MB_2U(SCH_1):PWRGD_DRAMPWRGD_CPU1_GH_R_LVC1
    2  PWRGD_DRAMPWRGD_CPU1_GH_LVC1_R      B  @S9S_MB_2U_LIB.S9S_MB_2U(SCH_1):PWRGD_DRAMPWRGD_CPU1_GH_LVC1_R

Q_RES  I5   R130   [Q_RES_0402LF-0,5%,1/16W,CHIP,CA]
    1  PWRGD_CPU1_LVC1_R      A  @S9S_MB_2U_LIB.S9S_MB_2U(SCH_1):PWRGD_CPU1_LVC1_R
    2  PWRGD_CPU1_BUF_R      B  @S9S_MB_2U_LIB.S9S_MB_2U(SCH_1):PWRGD_CPU1_BUF_R

Q_RES  I3   R132   [Q_RES_0402LF-0,5%,1/16W,CHIP,CA]
    1  RST_CPU1_LVC1_R_N      A  @S9S_MB_2U_LIB.S9S_MB_2U(SCH_1):RST_CPU1_LVC1_R_N
    2  RST_CPU1_BUF_R_N      B  @S9S_MB_2U_LIB.S9S_MB_2U(SCH_1):RST_CPU1_BUF_R_N

Q_RES  I62  R135   [Q_RES_0402LF-100,1%,1/16W,EMPTA]
    1  PWRGD_DRAMPWRGD_CPU1_AB_LVC1_R      A  @S9S_MB_2U_LIB.S9S_MB_2U(SCH_1):PWRGD_DRAMPWRGD_CPU1_AB_LVC1_R
    2  PVCCD_HV_CPU1      B  @S9S_MB_2U_LIB.S9S_MB_2U(SCH_1):PVCCD_HV_CPU1

Q_RES  I60  R137   [Q_RES_0402LF-100,1%,1/16W,EMPTA]
    1  PWRGD_DRAMPWRGD_CPU1_CD_LVC1_R      A  @S9S_MB_2U_LIB.S9S_MB_2U(SCH_1):PWRGD_DRAMPWRGD_CPU1_CD_LVC1_R
    2  PVCCD_HV_CPU1      B  @S9S_MB_2U_LIB.S9S_MB_2U(SCH_1):PVCCD_HV_CPU1

Q_RES  I249  R139   [Q_RES_0402LF-10K,1%,1/16W,CHIPA]
    2  P3V3_AUX           B  @S9S_MB_2U_LIB.S9S_MB_2U(SCH_1):P3V3_AUX
    1  FM_BMC_PWRBTN_N      A  @S9S_MB_2U_LIB.S9S_MB_2U(SCH_1):FM_BMC_PWRBTN_N

Q_RES  I99  R142   [Q_RES_0402LF-0,5%,1/16W,CHIP,CA]
    1  PVNN_TERM_CPU0      A  @S9S_MB_2U_LIB.S9S_MB_2U(SCH_1):PVNN_TERM_CPU0
    2  PVCCIO_PECI_BMC      B  @S9S_MB_2U_LIB.S9S_MB_2U(SCH_1):PVCCIO_PECI_BMC

Q_RES  I16  R143   [Q_RES_0402LF-0,5%,1/16W,EMPTY,A]
    1  PECI_PCH           A  @S9S_MB_2U_LIB.S9S_MB_2U(SCH_1):PECI_PCH
    2  PECI_CPU_GTL       B  @S9S_MB_2U_LIB.S9S_MB_2U(SCH_1):PECI_CPU_GTL

Q_RES  I2   R144   [Q_RES_0402LF-10,1%,1/16W,CHIP,A]
    2  PECI_CPU_GTL       B  @S9S_MB_2U_LIB.S9S_MB_2U(SCH_1):PECI_CPU_GTL
    1  PECI_BMC           A  @S9S_MB_2U_LIB.S9S_MB_2U(SCH_1):PECI_BMC

Q_RES  I6   R146   [Q_RES_0402LF-4.75K,1%,1/16W,EMA]
    1  PVNN_TERM_CPU0      A  @S9S_MB_2U_LIB.S9S_MB_2U(SCH_1):PVNN_TERM_CPU0
    2  PECI_CPU_GTL       B  @S9S_MB_2U_LIB.S9S_MB_2U(SCH_1):PECI_CPU_GTL

Q_RES  I4   R148   [Q_RES_0402LF-10K,1%,1/16W,CHIPA]
    1  PECI_CPU_GTL       A  @S9S_MB_2U_LIB.S9S_MB_2U(SCH_1):PECI_CPU_GTL
    2  GND                B  @S9S_MB_2U_LIB.S9S_MB_2U(SCH_1):GND

Q_RES  I58  R151   [Q_RES_0402LF-100,1%,1/16W,EMPTA]
    1  PWRGD_DRAMPWRGD_CPU1_EF_LVC1_R      A  @S9S_MB_2U_LIB.S9S_MB_2U(SCH_1):PWRGD_DRAMPWRGD_CPU1_EF_LVC1_R
    2  PVCCD_HV_CPU1      B  @S9S_MB_2U_LIB.S9S_MB_2U(SCH_1):PVCCD_HV_CPU1

Q_RES  I56  R153   [Q_RES_0402LF-100,1%,1/16W,EMPTA]
    1  PWRGD_DRAMPWRGD_CPU1_GH_LVC1_R      A  @S9S_MB_2U_LIB.S9S_MB_2U(SCH_1):PWRGD_DRAMPWRGD_CPU1_GH_LVC1_R
    2  PVCCD_HV_CPU1      B  @S9S_MB_2U_LIB.S9S_MB_2U(SCH_1):PVCCD_HV_CPU1

Q_RES  I26  R155   [Q_RES_0402LF-100,1%,1/16W,EMPTA]
    1  PWRGD_CPU1_BUF_R      A  @S9S_MB_2U_LIB.S9S_MB_2U(SCH_1):PWRGD_CPU1_BUF_R
    2  PVNN_TERM_CPU1      B  @S9S_MB_2U_LIB.S9S_MB_2U(SCH_1):PVNN_TERM_CPU1

Q_RES  I25  R156   [Q_RES_0402LF-33,5%,1/16W,CHIP,A]
    2  PWRGD_CPU1_LVC1      B  @S9S_MB_2U_LIB.S9S_MB_2U(SCH_1):PWRGD_CPU1_LVC1
    1  PWRGD_CPU1_BUF_R      A  @S9S_MB_2U_LIB.S9S_MB_2U(SCH_1):PWRGD_CPU1_BUF_R

Q_RES  I24  R157   [Q_RES_0402LF-100,1%,1/16W,EMPTA]
    1  RST_CPU1_BUF_R_N      A  @S9S_MB_2U_LIB.S9S_MB_2U(SCH_1):RST_CPU1_BUF_R_N
    2  PVNN_TERM_CPU1      B  @S9S_MB_2U_LIB.S9S_MB_2U(SCH_1):PVNN_TERM_CPU1

Q_RES  I23  R158   [Q_RES_0402LF-33,5%,1/16W,CHIP,A]
    2  RST_CPU1_LVC1_N      B  @S9S_MB_2U_LIB.S9S_MB_2U(SCH_1):RST_CPU1_LVC1_N
    1  RST_CPU1_BUF_R_N      A  @S9S_MB_2U_LIB.S9S_MB_2U(SCH_1):RST_CPU1_BUF_R_N

Q_RES  I17  R160   [Q_RES_0402LF-0,5%,1/16W,CHIP,CA]
    1  PWRGD_DRAMPWRGD_CPU0_AB_R_LVC1      A  @S9S_MB_2U_LIB.S9S_MB_2U(SCH_1):PWRGD_DRAMPWRGD_CPU0_AB_R_LVC1
    2  PWRGD_DRAMPWRGD_CPU0_AB_LVC1_R      B  @S9S_MB_2U_LIB.S9S_MB_2U(SCH_1):PWRGD_DRAMPWRGD_CPU0_AB_LVC1_R

Q_RES  I19  R162   [Q_RES_0402LF-0,5%,1/16W,CHIP,CA]
    1  PWRGD_DRAMPWRGD_CPU0_CD_R_LVC1      A  @S9S_MB_2U_LIB.S9S_MB_2U(SCH_1):PWRGD_DRAMPWRGD_CPU0_CD_R_LVC1
    2  PWRGD_DRAMPWRGD_CPU0_CD_LVC1_R      B  @S9S_MB_2U_LIB.S9S_MB_2U(SCH_1):PWRGD_DRAMPWRGD_CPU0_CD_LVC1_R

Q_RES  I26  R164   [Q_RES_0402LF-0,5%,1/16W,CHIP,CA]
    1  PWRGD_DRAMPWRGD_CPU0_EF_R_LVC1      A  @S9S_MB_2U_LIB.S9S_MB_2U(SCH_1):PWRGD_DRAMPWRGD_CPU0_EF_R_LVC1
    2  PWRGD_DRAMPWRGD_CPU0_EF_LVC1_R      B  @S9S_MB_2U_LIB.S9S_MB_2U(SCH_1):PWRGD_DRAMPWRGD_CPU0_EF_LVC1_R

Q_RES  I33  R166   [Q_RES_0402LF-0,5%,1/16W,CHIP,CA]
    1  PWRGD_DRAMPWRGD_CPU0_GH_R_LVC1      A  @S9S_MB_2U_LIB.S9S_MB_2U(SCH_1):PWRGD_DRAMPWRGD_CPU0_GH_R_LVC1
    2  PWRGD_DRAMPWRGD_CPU0_GH_LVC1_R      B  @S9S_MB_2U_LIB.S9S_MB_2U(SCH_1):PWRGD_DRAMPWRGD_CPU0_GH_LVC1_R

Q_RES  I43  R168   [Q_RES_0402LF-0,5%,1/16W,CHIP,CA]
    1  PWRGD_CPU0_LVC1_R      A  @S9S_MB_2U_LIB.S9S_MB_2U(SCH_1):PWRGD_CPU0_LVC1_R
    2  PWRGD_CPU0_BUF_R      B  @S9S_MB_2U_LIB.S9S_MB_2U(SCH_1):PWRGD_CPU0_BUF_R

Q_RES  I52  R171   [Q_RES_0402LF-0,5%,1/16W,CHIP,CA]
    1  RST_CPU0_LVC1_R_N      A  @S9S_MB_2U_LIB.S9S_MB_2U(SCH_1):RST_CPU0_LVC1_R_N
    2  RST_CPU0_BUF_R_N      B  @S9S_MB_2U_LIB.S9S_MB_2U(SCH_1):RST_CPU0_BUF_R_N

Q_RES  I74  R175   [Q_RES_0402LF-100,1%,1/16W,EMPTA]
    1  PWRGD_DRAMPWRGD_CPU0_AB_LVC1_R      A  @S9S_MB_2U_LIB.S9S_MB_2U(SCH_1):PWRGD_DRAMPWRGD_CPU0_AB_LVC1_R
    2  PVCCD_HV_CPU0      B  @S9S_MB_2U_LIB.S9S_MB_2U(SCH_1):PVCCD_HV_CPU0

Q_RES  I72  R177   [Q_RES_0402LF-100,1%,1/16W,EMPTA]
    1  PWRGD_DRAMPWRGD_CPU0_CD_LVC1_R      A  @S9S_MB_2U_LIB.S9S_MB_2U(SCH_1):PWRGD_DRAMPWRGD_CPU0_CD_LVC1_R
    2  PVCCD_HV_CPU0      B  @S9S_MB_2U_LIB.S9S_MB_2U(SCH_1):PVCCD_HV_CPU0

Q_RES  I70  R179   [Q_RES_0402LF-100,1%,1/16W,EMPTA]
    1  PWRGD_DRAMPWRGD_CPU0_EF_LVC1_R      A  @S9S_MB_2U_LIB.S9S_MB_2U(SCH_1):PWRGD_DRAMPWRGD_CPU0_EF_LVC1_R
    2  PVCCD_HV_CPU0      B  @S9S_MB_2U_LIB.S9S_MB_2U(SCH_1):PVCCD_HV_CPU0

Q_RES  I68  R181   [Q_RES_0402LF-100,1%,1/16W,EMPTA]
    1  PWRGD_DRAMPWRGD_CPU0_GH_LVC1_R      A  @S9S_MB_2U_LIB.S9S_MB_2U(SCH_1):PWRGD_DRAMPWRGD_CPU0_GH_LVC1_R
    2  PVCCD_HV_CPU0      B  @S9S_MB_2U_LIB.S9S_MB_2U(SCH_1):PVCCD_HV_CPU0

Q_RES  I62  R183   [Q_RES_0402LF-100,1%,1/16W,EMPTA]
    1  PWRGD_CPU0_BUF_R      A  @S9S_MB_2U_LIB.S9S_MB_2U(SCH_1):PWRGD_CPU0_BUF_R
    2  PVNN_TERM_CPU0      B  @S9S_MB_2U_LIB.S9S_MB_2U(SCH_1):PVNN_TERM_CPU0

Q_RES  I56  R184   [Q_RES_0402LF-33,5%,1/16W,CHIP,A]
    2  PWRGD_CPU0_LVC1      B  @S9S_MB_2U_LIB.S9S_MB_2U(SCH_1):PWRGD_CPU0_LVC1
    1  PWRGD_CPU0_BUF_R      A  @S9S_MB_2U_LIB.S9S_MB_2U(SCH_1):PWRGD_CPU0_BUF_R

Q_RES  I60  R185   [Q_RES_0402LF-100,1%,1/16W,EMPTA]
    1  RST_CPU0_BUF_R_N      A  @S9S_MB_2U_LIB.S9S_MB_2U(SCH_1):RST_CPU0_BUF_R_N
    2  PVNN_TERM_CPU0      B  @S9S_MB_2U_LIB.S9S_MB_2U(SCH_1):PVNN_TERM_CPU0

Q_RES  I61  R186   [Q_RES_0402LF-33,5%,1/16W,CHIP,A]
    2  RST_CPU0_LVC1_N      B  @S9S_MB_2U_LIB.S9S_MB_2U(SCH_1):RST_CPU0_LVC1_N
    1  RST_CPU0_BUF_R_N      A  @S9S_MB_2U_LIB.S9S_MB_2U(SCH_1):RST_CPU0_BUF_R_N

Q_RES  I8   R188   [Q_RES_0402LF-0,5%,1/16W,CHIP,CA]
    1  H_CPU_NMI_LVC1_R_N      A  @S9S_MB_2U_LIB.S9S_MB_2U(SCH_1):H_CPU_NMI_LVC1_R_N
    2  H_CPU_NMI_LVC1_N      B  @S9S_MB_2U_LIB.S9S_MB_2U(SCH_1):H_CPU_NMI_LVC1_N

Q_RES  I49  R195   [Q_RES_0402LF-49.9     ,1%  ,1/A]
    1  H_CPU_NMI_LVC1_N      A  @S9S_MB_2U_LIB.S9S_MB_2U(SCH_1):H_CPU_NMI_LVC1_N
    2  H_CPU0_NMI_LVC1_N      B  @S9S_MB_2U_LIB.S9S_MB_2U(SCH_1):H_CPU0_NMI_LVC1_N

Q_RES  I57  R196   [Q_RES_0402LF-49.9     ,1%  ,1/A]
    1  H_CPU_NMI_LVC1_N      A  @S9S_MB_2U_LIB.S9S_MB_2U(SCH_1):H_CPU_NMI_LVC1_N
    2  H_CPU1_NMI_LVC1_N      B  @S9S_MB_2U_LIB.S9S_MB_2U(SCH_1):H_CPU1_NMI_LVC1_N

Q_RES  I53  R197   [Q_RES_0402LF-10K,1%,1/16W,EMPTA]
    1  PVNN_TERM_CPU0      A  @S9S_MB_2U_LIB.S9S_MB_2U(SCH_1):PVNN_TERM_CPU0
    2  H_CPU0_NMI_LVC1_N      B  @S9S_MB_2U_LIB.S9S_MB_2U(SCH_1):H_CPU0_NMI_LVC1_N

Q_RES  I54  R198   [Q_RES_0402LF-10K,1%,1/16W,EMPTA]
    1  PVNN_TERM_CPU1      A  @S9S_MB_2U_LIB.S9S_MB_2U(SCH_1):PVNN_TERM_CPU1
    2  H_CPU1_NMI_LVC1_N      B  @S9S_MB_2U_LIB.S9S_MB_2U(SCH_1):H_CPU1_NMI_LVC1_N

Q_RES  I111  R199   [Q_RES_0402LF-100,1%,1/16W,EMPTA]
    1  PVNN_TERM_CPU0      A  @S9S_MB_2U_LIB.S9S_MB_2U(SCH_1):PVNN_TERM_CPU0
    2  H_CPU0_MEMHOT_OUT_LVC1_R_N      B  @S9S_MB_2U_LIB.S9S_MB_2U(SCH_1):H_CPU0_MEMHOT_OUT_LVC1_R_N

Q_RES  I102  R200   [Q_RES_0402LF-100,1%,1/16W,EMPTA]
    1  PVNN_TERM_CPU0      A  @S9S_MB_2U_LIB.S9S_MB_2U(SCH_1):PVNN_TERM_CPU0
    2  H_CPU0_MEMTRIP_LVC1_R_N      B  @S9S_MB_2U_LIB.S9S_MB_2U(SCH_1):H_CPU0_MEMTRIP_LVC1_R_N

Q_RES  I108  R201   [Q_RES_0402LF-100,1%,1/16W,EMPTA]
    1  PVNN_TERM_CPU1      A  @S9S_MB_2U_LIB.S9S_MB_2U(SCH_1):PVNN_TERM_CPU1
    2  H_CPU1_MEMHOT_OUT_LVC1_R_N      B  @S9S_MB_2U_LIB.S9S_MB_2U(SCH_1):H_CPU1_MEMHOT_OUT_LVC1_R_N

Q_RES  I110  R202   [Q_RES_0402LF-100,1%,1/16W,EMPTA]
    1  PVNN_TERM_CPU1      A  @S9S_MB_2U_LIB.S9S_MB_2U(SCH_1):PVNN_TERM_CPU1
    2  H_CPU1_MEMTRIP_LVC1_R_N      B  @S9S_MB_2U_LIB.S9S_MB_2U(SCH_1):H_CPU1_MEMTRIP_LVC1_R_N

Q_RES  I98  R203   [Q_RES_0402LF-33,5%,1/16W,CHIP,A]
    1  H_CPU0_MEMHOT_OUT_LVC1_R_N      A  @S9S_MB_2U_LIB.S9S_MB_2U(SCH_1):H_CPU0_MEMHOT_OUT_LVC1_R_N
    2  H_CPU0_MEMHOT_OUT_LVC1_N      B  @S9S_MB_2U_LIB.S9S_MB_2U(SCH_1):H_CPU0_MEMHOT_OUT_LVC1_N

Q_RES  I100  R204   [Q_RES_0402LF-33,5%,1/16W,CHIP,A]
    1  H_CPU1_MEMHOT_OUT_LVC1_R_N      A  @S9S_MB_2U_LIB.S9S_MB_2U(SCH_1):H_CPU1_MEMHOT_OUT_LVC1_R_N
    2  H_CPU1_MEMHOT_OUT_LVC1_N      B  @S9S_MB_2U_LIB.S9S_MB_2U(SCH_1):H_CPU1_MEMHOT_OUT_LVC1_N

Q_RES  I101  R205   [Q_RES_0402LF-33,5%,1/16W,CHIP,A]
    1  H_CPU0_MEMTRIP_LVC1_R_N      A  @S9S_MB_2U_LIB.S9S_MB_2U(SCH_1):H_CPU0_MEMTRIP_LVC1_R_N
    2  H_CPU0_MEMTRIP_LVC1_N      B  @S9S_MB_2U_LIB.S9S_MB_2U(SCH_1):H_CPU0_MEMTRIP_LVC1_N

Q_RES  I99  R206   [Q_RES_0402LF-33,5%,1/16W,CHIP,A]
    1  H_CPU1_MEMTRIP_LVC1_R_N      A  @S9S_MB_2U_LIB.S9S_MB_2U(SCH_1):H_CPU1_MEMTRIP_LVC1_R_N
    2  H_CPU1_MEMTRIP_LVC1_N      B  @S9S_MB_2U_LIB.S9S_MB_2U(SCH_1):H_CPU1_MEMTRIP_LVC1_N

Q_RES  I26  R208   [Q_RES_0402LF-0,5%,1/16W,CHIP,CA]
    1  H_CPU0_MEMHOT_IN_LVC1_R_N      A  @S9S_MB_2U_LIB.S9S_MB_2U(SCH_1):H_CPU0_MEMHOT_IN_LVC1_R_N
    2  H_CPU0_MEMHOT_IN_LVC1_N      B  @S9S_MB_2U_LIB.S9S_MB_2U(SCH_1):H_CPU0_MEMHOT_IN_LVC1_N

Q_RES  I66  R210   [Q_RES_0402LF-0,5%,1/16W,CHIP,CA]
    1  H_CPU1_MEMHOT_IN_LVC1_R_N      A  @S9S_MB_2U_LIB.S9S_MB_2U(SCH_1):H_CPU1_MEMHOT_IN_LVC1_R_N
    2  H_CPU1_MEMHOT_IN_LVC1_N      B  @S9S_MB_2U_LIB.S9S_MB_2U(SCH_1):H_CPU1_MEMHOT_IN_LVC1_N

Q_RES  I54  R219   [Q_RES_0402LF-100,1%,1/16W,EMPTA]
    1  PVNN_TERM_CPU0      A  @S9S_MB_2U_LIB.S9S_MB_2U(SCH_1):PVNN_TERM_CPU0
    2  H_CPU0_MEMHOT_IN_LVC1_N      B  @S9S_MB_2U_LIB.S9S_MB_2U(SCH_1):H_CPU0_MEMHOT_IN_LVC1_N

Q_RES  I63  R220   [Q_RES_0402LF-100,1%,1/16W,EMPTA]
    1  PVNN_TERM_CPU1      A  @S9S_MB_2U_LIB.S9S_MB_2U(SCH_1):PVNN_TERM_CPU1
    2  H_CPU1_MEMHOT_IN_LVC1_N      B  @S9S_MB_2U_LIB.S9S_MB_2U(SCH_1):H_CPU1_MEMHOT_IN_LVC1_N

Q_RES  I69  R237   [Q_RES_0402LF-0,5%,1/16W,CHIP,CA]
    1  H_CPU0_THERMTRIP_LVC1_R_N      A  @S9S_MB_2U_LIB.S9S_MB_2U(SCH_1):H_CPU0_THERMTRIP_LVC1_R_N
    2  H_CPU0_THERMTRIP_LVC1_N      B  @S9S_MB_2U_LIB.S9S_MB_2U(SCH_1):H_CPU0_THERMTRIP_LVC1_N

Q_RES  I80  R238   [Q_RES_0402LF-0,5%,1/16W,CHIP,CA]
    1  H_CPU1_THERMTRIP_LVC1_R_N      A  @S9S_MB_2U_LIB.S9S_MB_2U(SCH_1):H_CPU1_THERMTRIP_LVC1_R_N
    2  H_CPU1_THERMTRIP_LVC1_N      B  @S9S_MB_2U_LIB.S9S_MB_2U(SCH_1):H_CPU1_THERMTRIP_LVC1_N

Q_RES  I129  R239   [Q_RES_0402LF-0,5%,1/16W,CHIP,CA]
    1  H_CPU0_PROCHOT_LVC1_R_N      A  @S9S_MB_2U_LIB.S9S_MB_2U(SCH_1):H_CPU0_PROCHOT_LVC1_R_N
    2  H_CPU0_PROCHOT_LVC1_N      B  @S9S_MB_2U_LIB.S9S_MB_2U(SCH_1):H_CPU0_PROCHOT_LVC1_N

Q_RES  I151  R240   [Q_RES_0402LF-0,5%,1/16W,CHIP,CA]
    1  H_CPU1_PROCHOT_LVC1_R_N      A  @S9S_MB_2U_LIB.S9S_MB_2U(SCH_1):H_CPU1_PROCHOT_LVC1_R_N
    2  H_CPU1_PROCHOT_LVC1_N      B  @S9S_MB_2U_LIB.S9S_MB_2U(SCH_1):H_CPU1_PROCHOT_LVC1_N

Q_RES  I167  R241   [Q_RES_0402LF-1K,1%,1/16W,EMPTYA]
    1  P3V3               A  @S9S_MB_2U_LIB.S9S_MB_2U(SCH_1):P3V3
    2  H_CPU0_THERMTRIP_LVC1_N      B  @S9S_MB_2U_LIB.S9S_MB_2U(SCH_1):H_CPU0_THERMTRIP_LVC1_N

Q_RES  I169  R242   [Q_RES_0402LF-1K,1%,1/16W,EMPTYA]
    1  P3V3               A  @S9S_MB_2U_LIB.S9S_MB_2U(SCH_1):P3V3
    2  H_CPU1_THERMTRIP_LVC1_N      B  @S9S_MB_2U_LIB.S9S_MB_2U(SCH_1):H_CPU1_THERMTRIP_LVC1_N

Q_RES  I171  R243   [Q_RES_0402LF-100,1%,1/16W,EMPTA]
    1  PVNN_TERM_CPU0      A  @S9S_MB_2U_LIB.S9S_MB_2U(SCH_1):PVNN_TERM_CPU0
    2  H_CPU0_PROCHOT_LVC1_N      B  @S9S_MB_2U_LIB.S9S_MB_2U(SCH_1):H_CPU0_PROCHOT_LVC1_N

Q_RES  I173  R244   [Q_RES_0402LF-100,1%,1/16W,EMPTA]
    1  PVNN_TERM_CPU1      A  @S9S_MB_2U_LIB.S9S_MB_2U(SCH_1):PVNN_TERM_CPU1
    2  H_CPU1_PROCHOT_LVC1_N      B  @S9S_MB_2U_LIB.S9S_MB_2U(SCH_1):H_CPU1_PROCHOT_LVC1_N

Q_RES  I27  R249   [Q_RES_0402LF-240,1%,1/16W,EMPTA]
    1  PVNN_TERM_CPU0      A  @S9S_MB_2U_LIB.S9S_MB_2U(SCH_1):PVNN_TERM_CPU0
    2  FM_S3M_CPU0_LVC1_GPIO_0      B  @S9S_MB_2U_LIB.S9S_MB_2U(SCH_1):FM_S3M_CPU0_LVC1_GPIO_0

Q_RES  I29  R250   [Q_RES_0402LF-240,1%,1/16W,EMPTA]
    1  PVNN_TERM_CPU0      A  @S9S_MB_2U_LIB.S9S_MB_2U(SCH_1):PVNN_TERM_CPU0
    2  FM_S3M_CPU0_LVC1_GPIO_1      B  @S9S_MB_2U_LIB.S9S_MB_2U(SCH_1):FM_S3M_CPU0_LVC1_GPIO_1

Q_RES  I28  R251   [Q_RES_0402LF-240,1%,1/16W,EMPTA]
    1  PVNN_TERM_CPU0      A  @S9S_MB_2U_LIB.S9S_MB_2U(SCH_1):PVNN_TERM_CPU0
    2  FM_S3M_CPU0_LVC1_GPIO_4      B  @S9S_MB_2U_LIB.S9S_MB_2U(SCH_1):FM_S3M_CPU0_LVC1_GPIO_4

Q_RES  I30  R252   [Q_RES_0402LF-240,1%,1/16W,CHIPA]
    1  PVNN_TERM_CPU0      A  @S9S_MB_2U_LIB.S9S_MB_2U(SCH_1):PVNN_TERM_CPU0
    2  PUD_PCH_BOOT_MODE_CPU0      B  @S9S_MB_2U_LIB.S9S_MB_2U(SCH_1):PUD_PCH_BOOT_MODE_CPU0

Q_RES  I31  R253   [Q_RES_0402LF-240,1%,1/16W,CHIPA]
    1  PVNN_TERM_CPU0      A  @S9S_MB_2U_LIB.S9S_MB_2U(SCH_1):PVNN_TERM_CPU0
    2  FM_S3M_CPU0_LVC1_GPIO_2      B  @S9S_MB_2U_LIB.S9S_MB_2U(SCH_1):FM_S3M_CPU0_LVC1_GPIO_2

Q_RES  I32  R254   [Q_RES_0402LF-240,1%,1/16W,CHIPA]
    1  PVNN_TERM_CPU0      A  @S9S_MB_2U_LIB.S9S_MB_2U(SCH_1):PVNN_TERM_CPU0
    2  FM_S3M_CPU0_LVC1_GPIO_3      B  @S9S_MB_2U_LIB.S9S_MB_2U(SCH_1):FM_S3M_CPU0_LVC1_GPIO_3

Q_RES  I42  R255   [Q_RES_0402LF-240,1%,1/16W,EMPTA]
    1  PVNN_TERM_CPU1      A  @S9S_MB_2U_LIB.S9S_MB_2U(SCH_1):PVNN_TERM_CPU1
    2  FM_S3M_CPU1_LVC1_GPIO_0      B  @S9S_MB_2U_LIB.S9S_MB_2U(SCH_1):FM_S3M_CPU1_LVC1_GPIO_0

Q_RES  I48  R256   [Q_RES_0402LF-240,1%,1/16W,EMPTA]
    1  PVNN_TERM_CPU1      A  @S9S_MB_2U_LIB.S9S_MB_2U(SCH_1):PVNN_TERM_CPU1
    2  FM_S3M_CPU1_LVC1_GPIO_1      B  @S9S_MB_2U_LIB.S9S_MB_2U(SCH_1):FM_S3M_CPU1_LVC1_GPIO_1

Q_RES  I43  R257   [Q_RES_0402LF-240,1%,1/16W,EMPTA]
    1  PVNN_TERM_CPU1      A  @S9S_MB_2U_LIB.S9S_MB_2U(SCH_1):PVNN_TERM_CPU1
    2  FM_S3M_CPU1_LVC1_GPIO_4      B  @S9S_MB_2U_LIB.S9S_MB_2U(SCH_1):FM_S3M_CPU1_LVC1_GPIO_4

Q_RES  I44  R258   [Q_RES_0402LF-240,1%,1/16W,CHIPA]
    1  PVNN_TERM_CPU1      A  @S9S_MB_2U_LIB.S9S_MB_2U(SCH_1):PVNN_TERM_CPU1
    2  PUD_PCH_BOOT_MODE_CPU1      B  @S9S_MB_2U_LIB.S9S_MB_2U(SCH_1):PUD_PCH_BOOT_MODE_CPU1

Q_RES  I45  R259   [Q_RES_0402LF-240,1%,1/16W,CHIPA]
    1  PVNN_TERM_CPU1      A  @S9S_MB_2U_LIB.S9S_MB_2U(SCH_1):PVNN_TERM_CPU1
    2  FM_S3M_CPU1_LVC1_GPIO_2      B  @S9S_MB_2U_LIB.S9S_MB_2U(SCH_1):FM_S3M_CPU1_LVC1_GPIO_2

Q_RES  I46  R260   [Q_RES_0402LF-240,1%,1/16W,CHIPA]
    1  PVNN_TERM_CPU1      A  @S9S_MB_2U_LIB.S9S_MB_2U(SCH_1):PVNN_TERM_CPU1
    2  FM_S3M_CPU1_LVC1_GPIO_3      B  @S9S_MB_2U_LIB.S9S_MB_2U(SCH_1):FM_S3M_CPU1_LVC1_GPIO_3

Q_RES  I101  R261   [Q_RES_0402LF-240,1%,1/16W,EMPTA]
    1  PVNN_TERM_CPU1      A  @S9S_MB_2U_LIB.S9S_MB_2U(SCH_1):PVNN_TERM_CPU1
    2  PU_CPU1_TXT_AGENT      B  @S9S_MB_2U_LIB.S9S_MB_2U(SCH_1):PU_CPU1_TXT_AGENT

Q_RES  I100  R262   [Q_RES_0402LF-240,1%,1/16W,EMPTA]
    1  PVNN_TERM_CPU1      A  @S9S_MB_2U_LIB.S9S_MB_2U(SCH_1):PVNN_TERM_CPU1
    2  PU_CPU1_SAFE_MODE_BOOT      B  @S9S_MB_2U_LIB.S9S_MB_2U(SCH_1):PU_CPU1_SAFE_MODE_BOOT

Q_RES  I125  R263   [Q_RES_0402LF-240,1%,1/16W,EMPTA]
    1  PVNN_TERM_CPU1      A  @S9S_MB_2U_LIB.S9S_MB_2U(SCH_1):PVNN_TERM_CPU1
    2  PU_CPU1_FRMAGENT      B  @S9S_MB_2U_LIB.S9S_MB_2U(SCH_1):PU_CPU1_FRMAGENT

Q_RES  I98  R264   [Q_RES_0402LF-240,1%,1/16W,EMPTA]
    1  PVNN_TERM_CPU1      A  @S9S_MB_2U_LIB.S9S_MB_2U(SCH_1):PVNN_TERM_CPU1
    2  H_CPU1_BMCINIT_LVC1      B  @S9S_MB_2U_LIB.S9S_MB_2U(SCH_1):H_CPU1_BMCINIT_LVC1

Q_RES  I97  R265   [Q_RES_0402LF-240,1%,1/16W,CHIPA]
    1  PVNN_TERM_CPU1      A  @S9S_MB_2U_LIB.S9S_MB_2U(SCH_1):PVNN_TERM_CPU1
    2  PU_CPU1_SOCKET_ID0      B  @S9S_MB_2U_LIB.S9S_MB_2U(SCH_1):PU_CPU1_SOCKET_ID0

Q_RES  I96  R266   [Q_RES_0402LF-240,1%,1/16W,EMPTA]
    1  PVNN_TERM_CPU1      A  @S9S_MB_2U_LIB.S9S_MB_2U(SCH_1):PVNN_TERM_CPU1
    2  PU_CPU1_SOCKET_ID1      B  @S9S_MB_2U_LIB.S9S_MB_2U(SCH_1):PU_CPU1_SOCKET_ID1

Q_RES  I95  R267   [Q_RES_0402LF-240,1%,1/16W,EMPTA]
    1  PVNN_TERM_CPU1      A  @S9S_MB_2U_LIB.S9S_MB_2U(SCH_1):PVNN_TERM_CPU1
    2  PU_CPU1_SOCKET_ID2      B  @S9S_MB_2U_LIB.S9S_MB_2U(SCH_1):PU_CPU1_SOCKET_ID2

Q_RES  I94  R268   [Q_RES_0402LF-240,1%,1/16W,EMPTA]
    1  PVNN_TERM_CPU1      A  @S9S_MB_2U_LIB.S9S_MB_2U(SCH_1):PVNN_TERM_CPU1
    2  PU_CPU1_LEGACY_SKT      B  @S9S_MB_2U_LIB.S9S_MB_2U(SCH_1):PU_CPU1_LEGACY_SKT

Q_RES  I91  R269   [Q_RES_0402LF-33.2,1%,1/16W,CHIA]
    2  FM_ADR_MODE1_R      B  @S9S_MB_2U_LIB.S9S_MB_2U(SCH_1):FM_ADR_MODE1_R
    1  FM_ADR_MODE1       A  @S9S_MB_2U_LIB.S9S_MB_2U(SCH_1):FM_ADR_MODE1

Q_RES  I93  R270   [Q_RES_0402LF-10K,1%,1/16W,CHIPA]
    1  P3V3_AUX           A  @S9S_MB_2U_LIB.S9S_MB_2U(SCH_1):P3V3_AUX
    2  FM_CPU1_PKGID0      B  @S9S_MB_2U_LIB.S9S_MB_2U(SCH_1):FM_CPU1_PKGID0

Q_RES  I92  R271   [Q_RES_0402LF-10K,1%,1/16W,CHIPA]
    1  P3V3_AUX           A  @S9S_MB_2U_LIB.S9S_MB_2U(SCH_1):P3V3_AUX
    2  FM_CPU1_PKGID1      B  @S9S_MB_2U_LIB.S9S_MB_2U(SCH_1):FM_CPU1_PKGID1

Q_RES  I90  R272   [Q_RES_0402LF-10K,1%,1/16W,CHIPA]
    1  P3V3_AUX           A  @S9S_MB_2U_LIB.S9S_MB_2U(SCH_1):P3V3_AUX
    2  FM_CPU1_PKGID2      B  @S9S_MB_2U_LIB.S9S_MB_2U(SCH_1):FM_CPU1_PKGID2

Q_RES  I89  R273   [Q_RES_0402LF-10K,1%,1/16W,CHIPA]
    1  P3V3_AUX           A  @S9S_MB_2U_LIB.S9S_MB_2U(SCH_1):P3V3_AUX
    2  FM_CPU1_PROC_ID0      B  @S9S_MB_2U_LIB.S9S_MB_2U(SCH_1):FM_CPU1_PROC_ID0

Q_RES  I88  R274   [Q_RES_0402LF-10K,1%,1/16W,CHIPA]
    1  P3V3_AUX           A  @S9S_MB_2U_LIB.S9S_MB_2U(SCH_1):P3V3_AUX
    2  FM_CPU1_PROC_ID1      B  @S9S_MB_2U_LIB.S9S_MB_2U(SCH_1):FM_CPU1_PROC_ID1

Q_RES  I68  R275   [Q_RES_0402LF-240,1%,1/16W,CHIPA]
    1  PVNN_TERM_CPU0      A  @S9S_MB_2U_LIB.S9S_MB_2U(SCH_1):PVNN_TERM_CPU0
    2  PU_CPU0_TXT_AGENT      B  @S9S_MB_2U_LIB.S9S_MB_2U(SCH_1):PU_CPU0_TXT_AGENT

Q_RES  I66  R276   [Q_RES_0402LF-240,1%,1/16W,EMPTA]
    1  PVNN_TERM_CPU0      A  @S9S_MB_2U_LIB.S9S_MB_2U(SCH_1):PVNN_TERM_CPU0
    2  PU_CPU0_SAFE_MODE_BOOT      B  @S9S_MB_2U_LIB.S9S_MB_2U(SCH_1):PU_CPU0_SAFE_MODE_BOOT

Q_RES  I62  R277   [Q_RES_0402LF-240,1%,1/16W,CHIPA]
    1  PVNN_TERM_CPU0      A  @S9S_MB_2U_LIB.S9S_MB_2U(SCH_1):PVNN_TERM_CPU0
    2  PU_CPU0_FRMAGENT      B  @S9S_MB_2U_LIB.S9S_MB_2U(SCH_1):PU_CPU0_FRMAGENT

Q_RES  I61  R278   [Q_RES_0402LF-240,1%,1/16W,EMPTA]
    1  PVNN_TERM_CPU0      A  @S9S_MB_2U_LIB.S9S_MB_2U(SCH_1):PVNN_TERM_CPU0
    2  H_CPU0_BMCINIT_LVC1      B  @S9S_MB_2U_LIB.S9S_MB_2U(SCH_1):H_CPU0_BMCINIT_LVC1

Q_RES  I54  R279   [Q_RES_0402LF-240,1%,1/16W,EMPTA]
    1  PVNN_TERM_CPU0      A  @S9S_MB_2U_LIB.S9S_MB_2U(SCH_1):PVNN_TERM_CPU0
    2  PU_CPU0_SOCKET_ID0      B  @S9S_MB_2U_LIB.S9S_MB_2U(SCH_1):PU_CPU0_SOCKET_ID0

Q_RES  I57  R280   [Q_RES_0402LF-240,1%,1/16W,EMPTA]
    1  PVNN_TERM_CPU0      A  @S9S_MB_2U_LIB.S9S_MB_2U(SCH_1):PVNN_TERM_CPU0
    2  PU_CPU0_SOCKET_ID1      B  @S9S_MB_2U_LIB.S9S_MB_2U(SCH_1):PU_CPU0_SOCKET_ID1

Q_RES  I58  R281   [Q_RES_0402LF-240,1%,1/16W,EMPTA]
    1  PVNN_TERM_CPU0      A  @S9S_MB_2U_LIB.S9S_MB_2U(SCH_1):PVNN_TERM_CPU0
    2  PU_CPU0_SOCKET_ID2      B  @S9S_MB_2U_LIB.S9S_MB_2U(SCH_1):PU_CPU0_SOCKET_ID2

Q_RES  I53  R282   [Q_RES_0402LF-240,1%,1/16W,CHIPA]
    1  PVNN_TERM_CPU0      A  @S9S_MB_2U_LIB.S9S_MB_2U(SCH_1):PVNN_TERM_CPU0
    2  PU_CPU0_LEGACY_SKT      B  @S9S_MB_2U_LIB.S9S_MB_2U(SCH_1):PU_CPU0_LEGACY_SKT

Q_RES  I147  R283   [Q_RES_0402LF-10K,1%,1/16W,CHIPA]
    1  P3V3_AUX           A  @S9S_MB_2U_LIB.S9S_MB_2U(SCH_1):P3V3_AUX
    2  FM_CPU0_PKGID0      B  @S9S_MB_2U_LIB.S9S_MB_2U(SCH_1):FM_CPU0_PKGID0

Q_RES  I148  R284   [Q_RES_0402LF-10K,1%,1/16W,CHIPA]
    1  P3V3_AUX           A  @S9S_MB_2U_LIB.S9S_MB_2U(SCH_1):P3V3_AUX
    2  FM_CPU0_PKGID1      B  @S9S_MB_2U_LIB.S9S_MB_2U(SCH_1):FM_CPU0_PKGID1

Q_RES  I150  R285   [Q_RES_0402LF-10K,1%,1/16W,CHIPA]
    1  P3V3_AUX           A  @S9S_MB_2U_LIB.S9S_MB_2U(SCH_1):P3V3_AUX
    2  FM_CPU0_PKGID2      B  @S9S_MB_2U_LIB.S9S_MB_2U(SCH_1):FM_CPU0_PKGID2

Q_RES  I151  R286   [Q_RES_0402LF-10K,1%,1/16W,CHIPA]
    1  P3V3_AUX           A  @S9S_MB_2U_LIB.S9S_MB_2U(SCH_1):P3V3_AUX
    2  FM_CPU0_PROC_ID0      B  @S9S_MB_2U_LIB.S9S_MB_2U(SCH_1):FM_CPU0_PROC_ID0

Q_RES  I152  R287   [Q_RES_0402LF-10K,1%,1/16W,CHIPA]
    1  P3V3_AUX           A  @S9S_MB_2U_LIB.S9S_MB_2U(SCH_1):P3V3_AUX
    2  FM_CPU0_PROC_ID1      B  @S9S_MB_2U_LIB.S9S_MB_2U(SCH_1):FM_CPU0_PROC_ID1

Q_RES  I119  R288   [Q_RES_0402LF-240,1%,1/16W,CHIPA]
    2  PD_CPU1_TXT_PLTEN      B  @S9S_MB_2U_LIB.S9S_MB_2U(SCH_1):PD_CPU1_TXT_PLTEN
    1  GND                A  @S9S_MB_2U_LIB.S9S_MB_2U(SCH_1):GND

Q_RES  I118  R289   [Q_RES_0402LF-240,1%,1/16W,CHIPA]
    2  PD_CPU1_BIST_ENABLE      B  @S9S_MB_2U_LIB.S9S_MB_2U(SCH_1):PD_CPU1_BIST_ENABLE
    1  GND                A  @S9S_MB_2U_LIB.S9S_MB_2U(SCH_1):GND

Q_RES  I135  R290   [Q_RES_0402LF-240,1%,1/16W,CHIPA]
    2  PD_CPU1_DMIMODE_OVERRIDE      B  @S9S_MB_2U_LIB.S9S_MB_2U(SCH_1):PD_CPU1_DMIMODE_OVERRIDE
    1  GND                A  @S9S_MB_2U_LIB.S9S_MB_2U(SCH_1):GND

Q_RES  I116  R291   [Q_RES_0402LF-240,1%,1/16W,EMPTA]
    2  PD_CPU1_ENH_MCECC_DIS      B  @S9S_MB_2U_LIB.S9S_MB_2U(SCH_1):PD_CPU1_ENH_MCECC_DIS
    1  GND                A  @S9S_MB_2U_LIB.S9S_MB_2U(SCH_1):GND

Q_RES  I69  R292   [Q_RES_0402LF-240,1%,1/16W,CHIPA]
    2  PD_CPU0_TXT_PLTEN      B  @S9S_MB_2U_LIB.S9S_MB_2U(SCH_1):PD_CPU0_TXT_PLTEN
    1  GND                A  @S9S_MB_2U_LIB.S9S_MB_2U(SCH_1):GND

Q_RES  I70  R293   [Q_RES_0402LF-240,1%,1/16W,CHIPA]
    2  PD_CPU0_BIST_ENABLE      B  @S9S_MB_2U_LIB.S9S_MB_2U(SCH_1):PD_CPU0_BIST_ENABLE
    1  GND                A  @S9S_MB_2U_LIB.S9S_MB_2U(SCH_1):GND

Q_RES  I71  R294   [Q_RES_0402LF-240,1%,1/16W,EMPTA]
    2  PD_CPU0_DMIMODE_OVERRIDE      B  @S9S_MB_2U_LIB.S9S_MB_2U(SCH_1):PD_CPU0_DMIMODE_OVERRIDE
    1  GND                A  @S9S_MB_2U_LIB.S9S_MB_2U(SCH_1):GND

Q_RES  I72  R295   [Q_RES_0402LF-240,1%,1/16W,EMPTA]
    2  PD_CPU0_ENH_MCECC_DIS      B  @S9S_MB_2U_LIB.S9S_MB_2U(SCH_1):PD_CPU0_ENH_MCECC_DIS
    1  GND                A  @S9S_MB_2U_LIB.S9S_MB_2U(SCH_1):GND

Q_RES  I65  R296   [Q_RES_0402LF-301,1%,1/16W,CHIPA]
    1  PVNN_TERM_CPU0      A  @S9S_MB_2U_LIB.S9S_MB_2U(SCH_1):PVNN_TERM_CPU0
    2  H_CPU_CATERR_LVC1_R_N      B  @S9S_MB_2U_LIB.S9S_MB_2U(SCH_1):H_CPU_CATERR_LVC1_R_N

Q_RES  I23  R297   [Q_RES_0402LF-0,5%,1/16W,CHIP,CA]
    2  H_CPU_CATERR_LVC1_R_N      B  @S9S_MB_2U_LIB.S9S_MB_2U(SCH_1):H_CPU_CATERR_LVC1_R_N
    1  H_CPU0_CATERR_LVC1_R_N      A  @S9S_MB_2U_LIB.S9S_MB_2U(SCH_1):H_CPU0_CATERR_LVC1_R_N

Q_RES  I67  R298   [Q_RES_0402LF-301,1%,1/16W,CHIPA]
    1  PVNN_TERM_CPU1      A  @S9S_MB_2U_LIB.S9S_MB_2U(SCH_1):PVNN_TERM_CPU1
    2  H_CPU_CATERR_LVC1_R_N      B  @S9S_MB_2U_LIB.S9S_MB_2U(SCH_1):H_CPU_CATERR_LVC1_R_N

Q_RES  I63  R299   [Q_RES_0402LF-0,5%,1/16W,CHIP,CA]
    2  H_CPU_CATERR_LVC1_R_N      B  @S9S_MB_2U_LIB.S9S_MB_2U(SCH_1):H_CPU_CATERR_LVC1_R_N
    1  H_CPU1_CATERR_LVC1_R_N      A  @S9S_MB_2U_LIB.S9S_MB_2U(SCH_1):H_CPU1_CATERR_LVC1_R_N

Q_RES  I73  R301   [Q_RES_0402LF-301,1%,1/16W,CHIPA]
    1  PVNN_TERM_CPU0      A  @S9S_MB_2U_LIB.S9S_MB_2U(SCH_1):PVNN_TERM_CPU0
    2  H_CPU_RMCA_LVC1_R_N      B  @S9S_MB_2U_LIB.S9S_MB_2U(SCH_1):H_CPU_RMCA_LVC1_R_N

Q_RES  I75  R302   [Q_RES_0402LF-33.2,1%,1/16W,CHIA]
    2  H_CPU_RMCA_LVC1_R_N      B  @S9S_MB_2U_LIB.S9S_MB_2U(SCH_1):H_CPU_RMCA_LVC1_R_N
    1  H_CPU0_RMCA_LVC1_R_N      A  @S9S_MB_2U_LIB.S9S_MB_2U(SCH_1):H_CPU0_RMCA_LVC1_R_N

Q_RES  I76  R303   [Q_RES_0402LF-301,1%,1/16W,CHIPA]
    1  PVNN_TERM_CPU1      A  @S9S_MB_2U_LIB.S9S_MB_2U(SCH_1):PVNN_TERM_CPU1
    2  H_CPU_RMCA_LVC1_R_N      B  @S9S_MB_2U_LIB.S9S_MB_2U(SCH_1):H_CPU_RMCA_LVC1_R_N

Q_RES  I72  R304   [Q_RES_0402LF-33.2,1%,1/16W,CHIA]
    2  H_CPU_RMCA_LVC1_R_N      B  @S9S_MB_2U_LIB.S9S_MB_2U(SCH_1):H_CPU_RMCA_LVC1_R_N
    1  H_CPU1_RMCA_LVC1_R_N      A  @S9S_MB_2U_LIB.S9S_MB_2U(SCH_1):H_CPU1_RMCA_LVC1_R_N

Q_RES  I92  R315   [Q_RES_0402LF-33,5%,1/16W,CHIP,A]
    2  PWRGD_CPUPWRGD_LVC1_R      B  @S9S_MB_2U_LIB.S9S_MB_2U(SCH_1):PWRGD_CPUPWRGD_LVC1_R
    1  PWRGD_CPUPWRGD_GTL      A  @S9S_MB_2U_LIB.S9S_MB_2U(SCH_1):PWRGD_CPUPWRGD_GTL

Q_RES  I59  R316   [Q_RES_0402LF-4.32K,1%,1/16W,CHA]
    1  PWRGD_S0_PWROK_CPU1_LVC1_R      A  @S9S_MB_2U_LIB.S9S_MB_2U(SCH_1):PWRGD_S0_PWROK_CPU1_LVC1_R
    2  GND                B  @S9S_MB_2U_LIB.S9S_MB_2U(SCH_1):GND

Q_RES  I81  R318   [Q_RES_0402LF-10K,1%,1/16W,CHIPA]
    2  GND                B  @S9S_MB_2U_LIB.S9S_MB_2U(SCH_1):GND
    1  FM_SPD_REMOTE_EN      A  @S9S_MB_2U_LIB.S9S_MB_2U(SCH_1):FM_SPD_REMOTE_EN

Q_RES  I19  R319   [Q_RES_0402LF-10K,1%,1/16W,CHIPA]
    2  PU_S3M_CPU0_CPLD_STATUS      B  @S9S_MB_2U_LIB.S9S_MB_2U(SCH_1):PU_S3M_CPU0_CPLD_STATUS
    1  P3V3_AUX           A  @S9S_MB_2U_LIB.S9S_MB_2U(SCH_1):P3V3_AUX

Q_RES  I20  R320   [Q_RES_0402LF-10K,1%,1/16W,CHIPA]
    2  PU_S3M_CPU0_CPLD_CONFD      B  @S9S_MB_2U_LIB.S9S_MB_2U(SCH_1):PU_S3M_CPU0_CPLD_CONFD
    1  P3V3_AUX           A  @S9S_MB_2U_LIB.S9S_MB_2U(SCH_1):P3V3_AUX

Q_RES  I21  R321   [Q_RES_0402LF-10K,1%,1/16W,CHIPA]
    1  P3V3_AUX           A  @S9S_MB_2U_LIB.S9S_MB_2U(SCH_1):P3V3_AUX
    2  FM_S3M_CPU0_CPLD_CONFIG_N      B  @S9S_MB_2U_LIB.S9S_MB_2U(SCH_1):FM_S3M_CPU0_CPLD_CONFIG_N

Q_RES  I90  R322   [Q_RES_0402LF-33.2,1%,1/16W,CHIA]
    1  H_CPU0_PMSYNC_CPU1_R      A  @S9S_MB_2U_LIB.S9S_MB_2U(SCH_1):H_CPU0_PMSYNC_CPU1_R
    2  H_CPU0_PMSYNC_CPU1      B  @S9S_MB_2U_LIB.S9S_MB_2U(SCH_1):H_CPU0_PMSYNC_CPU1

Q_RES  I4   R323   [Q_RES_1206LF-0,,1/2W,EMPTY,CS0A]
    2  PVNN_TERM_CPU0      B  @S9S_MB_2U_LIB.S9S_MB_2U(SCH_1):PVNN_TERM_CPU0
    1  PVCCINFAON_CPU0      A  @S9S_MB_2U_LIB.S9S_MB_2U(SCH_1):PVCCINFAON_CPU0

Q_RES  I3   R324   [Q_RES_1206LF-0,,1/2W,CHIP,CS00A]
    2  PVNN_TERM_CPU0      B  @S9S_MB_2U_LIB.S9S_MB_2U(SCH_1):PVNN_TERM_CPU0
    1  PVNN_MAIN_CPU0      A  @S9S_MB_2U_LIB.S9S_MB_2U(SCH_1):PVNN_MAIN_CPU0

Q_RES  I28  R325   [Q_RES_0402LF-10K,1%,1/16W,CHIPA]
    2  PU_S3M_CPU1_CPLD_STATUS      B  @S9S_MB_2U_LIB.S9S_MB_2U(SCH_1):PU_S3M_CPU1_CPLD_STATUS
    1  P3V3_AUX           A  @S9S_MB_2U_LIB.S9S_MB_2U(SCH_1):P3V3_AUX

Q_RES  I29  R326   [Q_RES_0402LF-10K,1%,1/16W,CHIPA]
    2  PU_S3M_CPU1_CPLD_CONFD      B  @S9S_MB_2U_LIB.S9S_MB_2U(SCH_1):PU_S3M_CPU1_CPLD_CONFD
    1  P3V3_AUX           A  @S9S_MB_2U_LIB.S9S_MB_2U(SCH_1):P3V3_AUX

Q_RES  I30  R327   [Q_RES_0402LF-10K,1%,1/16W,CHIPA]
    1  P3V3_AUX           A  @S9S_MB_2U_LIB.S9S_MB_2U(SCH_1):P3V3_AUX
    2  FM_S3M_CPU1_CPLD_CONFIG_N      B  @S9S_MB_2U_LIB.S9S_MB_2U(SCH_1):FM_S3M_CPU1_CPLD_CONFIG_N

Q_RES  I93  R328   [Q_RES_0402LF-100,1%,1/16W,CHIPA]
    1  SVID_DIO0_CPU0_R      A  @S9S_MB_2U_LIB.S9S_MB_2U(SCH_1):SVID_DIO0_CPU0_R
    2  PVNN_TERM_CPU0      B  @S9S_MB_2U_LIB.S9S_MB_2U(SCH_1):PVNN_TERM_CPU0

Q_RES  I8   R329   [Q_RES_1206LF-0,,1/2W,EMPTY,CS0A]
    2  PVNN_TERM_CPU1      B  @S9S_MB_2U_LIB.S9S_MB_2U(SCH_1):PVNN_TERM_CPU1
    1  PVCCINFAON_CPU1      A  @S9S_MB_2U_LIB.S9S_MB_2U(SCH_1):PVCCINFAON_CPU1

Q_RES  I9   R330   [Q_RES_1206LF-0,,1/2W,CHIP,CS00A]
    2  PVNN_TERM_CPU1      B  @S9S_MB_2U_LIB.S9S_MB_2U(SCH_1):PVNN_TERM_CPU1
    1  PVNN_MAIN_CPU1      A  @S9S_MB_2U_LIB.S9S_MB_2U(SCH_1):PVNN_MAIN_CPU1

Q_RES  I20  R331   [Q_RES_0402LF-1K,1%,1/16W,EMPTYA]
    2  PD_PIROM_CPU0_ADDR2      B  @S9S_MB_2U_LIB.S9S_MB_2U(SCH_1):PD_PIROM_CPU0_ADDR2
    1  P3V3_AUX           A  @S9S_MB_2U_LIB.S9S_MB_2U(SCH_1):P3V3_AUX

Q_RES  I21  R332   [Q_RES_0402LF-10K,1%,1/16W,CHIPA]
    1  PD_PIROM_CPU0_ADDR2      A  @S9S_MB_2U_LIB.S9S_MB_2U(SCH_1):PD_PIROM_CPU0_ADDR2
    2  GND                B  @S9S_MB_2U_LIB.S9S_MB_2U(SCH_1):GND

Q_RES  I6   R333   [Q_RES_0402LF-1K,1%,1/16W,EMPTYA]
    2  PD_PIROM_CPU0_ADDR1      B  @S9S_MB_2U_LIB.S9S_MB_2U(SCH_1):PD_PIROM_CPU0_ADDR1
    1  P3V3_AUX           A  @S9S_MB_2U_LIB.S9S_MB_2U(SCH_1):P3V3_AUX

Q_RES  I1   R334   [Q_RES_0402LF-10K,1%,1/16W,CHIPA]
    1  PD_PIROM_CPU0_ADDR1      A  @S9S_MB_2U_LIB.S9S_MB_2U(SCH_1):PD_PIROM_CPU0_ADDR1
    2  GND                B  @S9S_MB_2U_LIB.S9S_MB_2U(SCH_1):GND

Q_RES  I5   R335   [Q_RES_0402LF-1K,1%,1/16W,EMPTYA]
    2  PD_PIROM_CPU0_ADDR0      B  @S9S_MB_2U_LIB.S9S_MB_2U(SCH_1):PD_PIROM_CPU0_ADDR0
    1  P3V3_AUX           A  @S9S_MB_2U_LIB.S9S_MB_2U(SCH_1):P3V3_AUX

Q_RES  I37  R336   [Q_RES_0402LF-0,5%,1/16W,CHIP,CA]
    2  H_CPU_ERR0_LVC1_R_N      B  @S9S_MB_2U_LIB.S9S_MB_2U(SCH_1):H_CPU_ERR0_LVC1_R_N
    1  H_CPU0_ERR0_LVC1_R_N      A  @S9S_MB_2U_LIB.S9S_MB_2U(SCH_1):H_CPU0_ERR0_LVC1_R_N

Q_RES  I33  R337   [Q_RES_0402LF-0,5%,1/16W,CHIP,CA]
    2  H_CPU_ERR0_LVC1_R_N      B  @S9S_MB_2U_LIB.S9S_MB_2U(SCH_1):H_CPU_ERR0_LVC1_R_N
    1  H_CPU1_ERR0_LVC1_R_N      A  @S9S_MB_2U_LIB.S9S_MB_2U(SCH_1):H_CPU1_ERR0_LVC1_R_N

Q_RES  I91  R338   [Q_RES_0402LF-33,5%,1/16W,CHIP,A]
    1  H_CPU_ERR0_LVC1_R_N      A  @S9S_MB_2U_LIB.S9S_MB_2U(SCH_1):H_CPU_ERR0_LVC1_R_N
    2  H_CPU_ERR0_LVC1_N      B  @S9S_MB_2U_LIB.S9S_MB_2U(SCH_1):H_CPU_ERR0_LVC1_N

Q_RES  I94  R339   [Q_RES_0402LF-33,5%,1/16W,CHIP,A]
    2  H_CPU_ERR0_PCH_R_N      B  @S9S_MB_2U_LIB.S9S_MB_2U(SCH_1):H_CPU_ERR0_PCH_R_N
    1  H_CPU_ERR0_LVC1_R_N      A  @S9S_MB_2U_LIB.S9S_MB_2U(SCH_1):H_CPU_ERR0_LVC1_R_N

Q_RES  I43  R340   [Q_RES_0402LF-0,5%,1/16W,CHIP,CA]
    2  H_CPU_ERR1_LVC1_R_N      B  @S9S_MB_2U_LIB.S9S_MB_2U(SCH_1):H_CPU_ERR1_LVC1_R_N
    1  H_CPU0_ERR1_LVC1_R_N      A  @S9S_MB_2U_LIB.S9S_MB_2U(SCH_1):H_CPU0_ERR1_LVC1_R_N

Q_RES  I44  R341   [Q_RES_0402LF-0,5%,1/16W,CHIP,CA]
    2  H_CPU_ERR1_LVC1_R_N      B  @S9S_MB_2U_LIB.S9S_MB_2U(SCH_1):H_CPU_ERR1_LVC1_R_N
    1  H_CPU1_ERR1_LVC1_R_N      A  @S9S_MB_2U_LIB.S9S_MB_2U(SCH_1):H_CPU1_ERR1_LVC1_R_N

Q_RES  I96  R342   [Q_RES_0402LF-33,5%,1/16W,CHIP,A]
    1  H_CPU_ERR1_LVC1_R_N      A  @S9S_MB_2U_LIB.S9S_MB_2U(SCH_1):H_CPU_ERR1_LVC1_R_N
    2  H_CPU_ERR1_LVC1_N      B  @S9S_MB_2U_LIB.S9S_MB_2U(SCH_1):H_CPU_ERR1_LVC1_N

Q_RES  I95  R343   [Q_RES_0402LF-33,5%,1/16W,CHIP,A]
    2  H_CPU_ERR1_PCH_R_N      B  @S9S_MB_2U_LIB.S9S_MB_2U(SCH_1):H_CPU_ERR1_PCH_R_N
    1  H_CPU_ERR1_LVC1_R_N      A  @S9S_MB_2U_LIB.S9S_MB_2U(SCH_1):H_CPU_ERR1_LVC1_R_N

Q_RES  I45  R344   [Q_RES_0402LF-0,5%,1/16W,CHIP,CA]
    2  H_CPU_ERR2_LVC1_R_N      B  @S9S_MB_2U_LIB.S9S_MB_2U(SCH_1):H_CPU_ERR2_LVC1_R_N
    1  H_CPU0_ERR2_LVC1_R_N      A  @S9S_MB_2U_LIB.S9S_MB_2U(SCH_1):H_CPU0_ERR2_LVC1_R_N

Q_RES  I46  R345   [Q_RES_0402LF-0,5%,1/16W,CHIP,CA]
    2  H_CPU_ERR2_LVC1_R_N      B  @S9S_MB_2U_LIB.S9S_MB_2U(SCH_1):H_CPU_ERR2_LVC1_R_N
    1  H_CPU1_ERR2_LVC1_R_N      A  @S9S_MB_2U_LIB.S9S_MB_2U(SCH_1):H_CPU1_ERR2_LVC1_R_N

Q_RES  I100  R346   [Q_RES_0402LF-33,5%,1/16W,CHIP,A]
    1  H_CPU_ERR2_LVC1_R_N      A  @S9S_MB_2U_LIB.S9S_MB_2U(SCH_1):H_CPU_ERR2_LVC1_R_N
    2  H_CPU_ERR2_LVC1_N      B  @S9S_MB_2U_LIB.S9S_MB_2U(SCH_1):H_CPU_ERR2_LVC1_N

Q_RES  I99  R347   [Q_RES_0402LF-33,5%,1/16W,CHIP,A]
    2  H_CPU_ERR2_PCH_R_N      B  @S9S_MB_2U_LIB.S9S_MB_2U(SCH_1):H_CPU_ERR2_PCH_R_N
    1  H_CPU_ERR2_LVC1_R_N      A  @S9S_MB_2U_LIB.S9S_MB_2U(SCH_1):H_CPU_ERR2_LVC1_R_N

Q_RES  I247  R365   [Q_RES_0402LF-0,5%,1/16W,CHIP,CA]
    1  FM_CPU_RMCA_CATERR_LVT3_R_N      A  @S9S_MB_2U_LIB.S9S_MB_2U(SCH_1):FM_CPU_RMCA_CATERR_LVT3_R_N
    2  CPU_RMCA_CATERR_LVT3_N      B  @S9S_MB_2U_LIB.S9S_MB_2U(SCH_1):CPU_RMCA_CATERR_LVT3_N

Q_RES  I246  R366   [Q_RES_0402LF-332,1%,1/16W,CHIPA]
    2  LED_CPU_RMCA_CATERR_R      B  @S9S_MB_2U_LIB.S9S_MB_2U(SCH_1):LED_CPU_RMCA_CATERR_R
    1  LED_CPU_RMCA_CATERR      A  @S9S_MB_2U_LIB.S9S_MB_2U(SCH_1):LED_CPU_RMCA_CATERR

Q_RES  I11  R367   [Q_RES_0402LF-1K,5%,1/16W,CHIP,A]
    2  PU_NO_REBOOT_STRAP      B  @S9S_MB_2U_LIB.S9S_MB_2U(SCH_1):PU_NO_REBOOT_STRAP
    1  P3V3_AUX           A  @S9S_MB_2U_LIB.S9S_MB_2U(SCH_1):P3V3_AUX

Q_RES  I16  R369   [Q_RES_0402LF-1K,5%,1/16W,CHIP,A]
    1  P3V3_AUX           A  @S9S_MB_2U_LIB.S9S_MB_2U(SCH_1):P3V3_AUX
    2  FM_ADR_ACK         B  @S9S_MB_2U_LIB.S9S_MB_2U(SCH_1):FM_ADR_ACK

Q_RES  I45  R371   [Q_RES_0402LF-1K,5%,1/16W,EMPTYA]
    1  P3V3_AUX           A  @S9S_MB_2U_LIB.S9S_MB_2U(SCH_1):P3V3_AUX
    2  FM_PCH_BOOT_BIOS_STRAP      B  @S9S_MB_2U_LIB.S9S_MB_2U(SCH_1):FM_PCH_BOOT_BIOS_STRAP

Q_RES  I46  R372   [Q_RES_0402LF-10K,1%,1/16W,CHIPA]
    2  GND                B  @S9S_MB_2U_LIB.S9S_MB_2U(SCH_1):GND
    1  FM_PCH_BOOT_BIOS_STRAP      A  @S9S_MB_2U_LIB.S9S_MB_2U(SCH_1):FM_PCH_BOOT_BIOS_STRAP

Q_RES  I60  R374   [Q_RES_0402LF-1K,5%,1/16W,EMPTYA]
    1  P3V3_AUX           A  @S9S_MB_2U_LIB.S9S_MB_2U(SCH_1):P3V3_AUX
    2  FM_SPI_3V3_1V8_VOLTAGE      B  @S9S_MB_2U_LIB.S9S_MB_2U(SCH_1):FM_SPI_3V3_1V8_VOLTAGE

Q_RES  I61  R375   [Q_RES_0402LF-10K,1%,1/16W,CHIPA]
    2  GND                B  @S9S_MB_2U_LIB.S9S_MB_2U(SCH_1):GND
    1  FM_SPI_3V3_1V8_VOLTAGE      A  @S9S_MB_2U_LIB.S9S_MB_2U(SCH_1):FM_SPI_3V3_1V8_VOLTAGE

Q_RES  I77  R378   [Q_RES_0402LF-1K,5%,1/16W,EMPTYA]
    1  P3V3_AUX           A  @S9S_MB_2U_LIB.S9S_MB_2U(SCH_1):P3V3_AUX
    2  FM_ADR_MODE1       B  @S9S_MB_2U_LIB.S9S_MB_2U(SCH_1):FM_ADR_MODE1

Q_RES  I76  R379   [Q_RES_0402LF-1K,5%,1/16W,CHIP,A]
    2  GND                B  @S9S_MB_2U_LIB.S9S_MB_2U(SCH_1):GND
    1  FM_ADR_MODE1       A  @S9S_MB_2U_LIB.S9S_MB_2U(SCH_1):FM_ADR_MODE1

Q_RES  I78  R380   [Q_RES_0402LF-1K,5%,1/16W,EMPTYA]
    1  P3V3_AUX           A  @S9S_MB_2U_LIB.S9S_MB_2U(SCH_1):P3V3_AUX
    2  FM_FLASH_SECURITY_STRAP      B  @S9S_MB_2U_LIB.S9S_MB_2U(SCH_1):FM_FLASH_SECURITY_STRAP

Q_RES  I81  R381   [Q_RES_0402LF-10K,1%,1/16W,CHIPA]
    2  GND                B  @S9S_MB_2U_LIB.S9S_MB_2U(SCH_1):GND
    1  FM_FLASH_SECURITY_STRAP      A  @S9S_MB_2U_LIB.S9S_MB_2U(SCH_1):FM_FLASH_SECURITY_STRAP

Q_RES  I32  R382   [Q_RES_0402LF-1K,5%,1/16W,EMPTYA]
    1  P1V05_PCH_AUX      A  @S9S_MB_2U_LIB.S9S_MB_2U(SCH_1):P1V05_PCH_AUX
    2  FM_XTAL_INPUT_FREQUENCY_0_MGPIO      B  @S9S_MB_2U_LIB.S9S_MB_2U(SCH_1):FM_XTAL_INPUT_FREQUENCY_0_MGPIO_TEST4

Q_RES  I108  R388   [Q_RES_0402LF-10K,1%,1/16W,CHIPA]
    2  RISER2_TYPE_ID      B  @S9S_MB_2U_LIB.S9S_MB_2U(SCH_1):RISER2_TYPE_ID
    1  P3V3_AUX           A  @S9S_MB_2U_LIB.S9S_MB_2U(SCH_1):P3V3_AUX

Q_RES  I108  R391   [Q_RES_0402LF-10K,1%,1/16W,CHIPA]
    2  RISER3_TYPE_ID      B  @S9S_MB_2U_LIB.S9S_MB_2U(SCH_1):RISER3_TYPE_ID
    1  P3V3_AUX           A  @S9S_MB_2U_LIB.S9S_MB_2U(SCH_1):P3V3_AUX

Q_RES  I335  R392   [Q_RES_0402LF-10K,5%,1/16W,CHIPA]
    2  PCIE_RISER3_PRSNT2_N      B  @S9S_MB_2U_LIB.S9S_MB_2U(SCH_1):PCIE_RISER3_PRSNT2_N
    1  P3V3_AUX           A  @S9S_MB_2U_LIB.S9S_MB_2U(SCH_1):P3V3_AUX

Q_RES  I71  R394   [Q_RES_0402LF-4.7K,5%,1/16W,CHIA]
    2  P3V3_AUX           B  @S9S_MB_2U_LIB.S9S_MB_2U(SCH_1):P3V3_AUX
    1  FM_PCIE_EDSFF2A_PRSNT_1_N      A  @S9S_MB_2U_LIB.S9S_MB_2U(SCH_1):FM_PCIE_EDSFF2A_PRSNT_1_N

Q_RES  I77  R395   [Q_RES_0402LF-10K,1%,1/16W,CHIPA]
    1  PU_EDSFF2A_PERST1_CLKREQ_N      A  @S9S_MB_2U_LIB.S9S_MB_2U(SCH_1):PU_EDSFF2A_PERST1_CLKREQ_N
    2  P3V3_AUX           B  @S9S_MB_2U_LIB.S9S_MB_2U(SCH_1):P3V3_AUX

Q_RES  I78  R396   [Q_RES_0402LF-10K,1%,1/16W,CHIPA]
    1  PD_EDSFF2A_PWRDIS      A  @S9S_MB_2U_LIB.S9S_MB_2U(SCH_1):PD_EDSFF2A_PWRDIS
    2  GND                B  @S9S_MB_2U_LIB.S9S_MB_2U(SCH_1):GND

Q_RES  I71  R398   [Q_RES_0402LF-4.7K,5%,1/16W,CHIA]
    2  P3V3_AUX           B  @S9S_MB_2U_LIB.S9S_MB_2U(SCH_1):P3V3_AUX
    1  FM_PCIE_EDSFF2B_PRSNT_1_N      A  @S9S_MB_2U_LIB.S9S_MB_2U(SCH_1):FM_PCIE_EDSFF2B_PRSNT_1_N

Q_RES  I77  R399   [Q_RES_0402LF-10K,1%,1/16W,CHIPA]
    1  PU_EDSFF2B_PERST1_CLKREQ_N      A  @S9S_MB_2U_LIB.S9S_MB_2U(SCH_1):PU_EDSFF2B_PERST1_CLKREQ_N
    2  P3V3_AUX           B  @S9S_MB_2U_LIB.S9S_MB_2U(SCH_1):P3V3_AUX

Q_RES  I78  R400   [Q_RES_0402LF-10K,1%,1/16W,CHIPA]
    1  PD_EDSFF2B_PWRDIS      A  @S9S_MB_2U_LIB.S9S_MB_2U(SCH_1):PD_EDSFF2B_PWRDIS
    2  GND                B  @S9S_MB_2U_LIB.S9S_MB_2U(SCH_1):GND

Q_RES  I69  R401   [Q_RES_0402LF-10K,1%,1/16W,EMPTA]
    1  P1V8_PCH_AUX       A  @S9S_MB_2U_LIB.S9S_MB_2U(SCH_1):P1V8_PCH_AUX
    2  IRQ_TPM_SPI_N      B  @S9S_MB_2U_LIB.S9S_MB_2U(SCH_1):IRQ_TPM_SPI_N

Q_RES  I204  R402   [Q_RES_0402LF-4.7K,5%,1/16W,CHIA]
    2  P3V3_AUX           B  @S9S_MB_2U_LIB.S9S_MB_2U(SCH_1):P3V3_AUX
    1  FM_PCIE_EDSFF3_PRSNT_1_N      A  @S9S_MB_2U_LIB.S9S_MB_2U(SCH_1):FM_PCIE_EDSFF3_PRSNT_1_N

Q_RES  I206  R404   [Q_RES_0402LF-10K,1%,1/16W,CHIPA]
    1  NC                 A  NC
    2  GND                B  @S9S_MB_2U_LIB.S9S_MB_2U(SCH_1):GND

Q_RES  I147  R409   [Q_RES_0402LF-4.7K,1%,1/16W,EMPA]
    1  P3V3_OCP_SFF       A  @S9S_MB_2U_LIB.S9S_MB_2U(SCH_1):P3V3_OCP_SFF
    2  OCP_SFF_ID0        B  @S9S_MB_2U_LIB.S9S_MB_2U(SCH_1):OCP_SFF_ID0

Q_RES  I148  R410   [Q_RES_0402LF-4.7K,1%,1/16W,CHIA]
    1  OCP_SFF_ID0        A  @S9S_MB_2U_LIB.S9S_MB_2U(SCH_1):OCP_SFF_ID0
    2  GND                B  @S9S_MB_2U_LIB.S9S_MB_2U(SCH_1):GND

Q_RES  I362  R413   [Q_RES_0402LF-100K,1%,1/16W,CHIA]
    1  GND                A  @S9S_MB_2U_LIB.S9S_MB_2U(SCH_1):GND
    2  FM_OCP_SFF_PWR_GOOD      B  @S9S_MB_2U_LIB.S9S_MB_2U(SCH_1):FM_OCP_SFF_PWR_GOOD

Q_RES  I144  R414   [Q_RES_0402LF-4.7K,1%,1/16W,EMPA]
    1  P3V3_OCP_SFF       A  @S9S_MB_2U_LIB.S9S_MB_2U(SCH_1):P3V3_OCP_SFF
    2  OCP_SFF_ID1        B  @S9S_MB_2U_LIB.S9S_MB_2U(SCH_1):OCP_SFF_ID1

Q_RES  I145  R415   [Q_RES_0402LF-4.7K,1%,1/16W,CHIA]
    1  OCP_SFF_ID1        A  @S9S_MB_2U_LIB.S9S_MB_2U(SCH_1):OCP_SFF_ID1
    2  GND                B  @S9S_MB_2U_LIB.S9S_MB_2U(SCH_1):GND

Q_RES  I253  R416   [Q_RES_0402LF-0,5%,1/16W,CHIP,CA]
    1  OCP_SFF_ISO_BIF0_EN      A  @S9S_MB_2U_LIB.S9S_MB_2U(SCH_1):OCP_SFF_ISO_BIF0_EN
    2  OCP_SFF_BIF0_R_N      B  @S9S_MB_2U_LIB.S9S_MB_2U(SCH_1):OCP_SFF_BIF0_R_N

Q_RES  I255  R417   [Q_RES_0402LF-0,5%,1/16W,CHIP,CA]
    1  OCP_SFF_ISO_BIF1_EN      A  @S9S_MB_2U_LIB.S9S_MB_2U(SCH_1):OCP_SFF_ISO_BIF1_EN
    2  OCP_SFF_BIF1_R_N      B  @S9S_MB_2U_LIB.S9S_MB_2U(SCH_1):OCP_SFF_BIF1_R_N

Q_RES  I258  R418   [Q_RES_0402LF-0,5%,1/16W,CHIP,CA]
    1  OCP_SFF_ISO_BIF2_EN      A  @S9S_MB_2U_LIB.S9S_MB_2U(SCH_1):OCP_SFF_ISO_BIF2_EN
    2  OCP_SFF_BIF2_R_N      B  @S9S_MB_2U_LIB.S9S_MB_2U(SCH_1):OCP_SFF_BIF2_R_N

Q_RES  I6   R419   [Q_RES_0402LF-33.2,1%,1/16W,CHIA]
    2  RST_PERST0_OCP_SFF_N      B  @S9S_MB_2U_LIB.S9S_MB_2U(SCH_1):RST_PERST0_OCP_SFF_N
    1  RST_OCP_V3_1_BUF_N      A  @S9S_MB_2U_LIB.S9S_MB_2U(SCH_1):RST_OCP_V3_1_BUF_N

Q_RES  I10  R420   [Q_RES_0402LF-1K,1%,1/16W,EMPTYA]
    1  SGPIO_OCP_SFF_LD_N      A  @S9S_MB_2U_LIB.S9S_MB_2U(SCH_1):SGPIO_OCP_SFF_LD_N
    2  P3V3_OCP_SFF       B  @S9S_MB_2U_LIB.S9S_MB_2U(SCH_1):P3V3_OCP_SFF

Q_RES  I11  R421   [Q_RES_0402LF-4.7K,5%,1/16W,CHIA]
    1  SGPIO_OCP_SFF_DATAIN_N      A  @S9S_MB_2U_LIB.S9S_MB_2U(SCH_1):SGPIO_OCP_SFF_DATAIN_N
    2  P3V3_OCP_SFF       B  @S9S_MB_2U_LIB.S9S_MB_2U(SCH_1):P3V3_OCP_SFF

Q_RES  I12  R422   [Q_RES_0402LF-1K,1%,1/16W,EMPTYA]
    1  SGPIO_OCP_SFF_DATAOUT_N      A  @S9S_MB_2U_LIB.S9S_MB_2U(SCH_1):SGPIO_OCP_SFF_DATAOUT_N
    2  GND                B  @S9S_MB_2U_LIB.S9S_MB_2U(SCH_1):GND

Q_RES  I13  R423   [Q_RES_0402LF-0,5%,1/16W,EMPTY,A]
    1  SGPIO_OCP_SFF_CLK_N      A  @S9S_MB_2U_LIB.S9S_MB_2U(SCH_1):SGPIO_OCP_SFF_CLK_N
    2  GND                B  @S9S_MB_2U_LIB.S9S_MB_2U(SCH_1):GND

Q_RES  I173  R424   [Q_RES_0402LF-33.2,1%,1/16W,CHIA]
    2  SMB_OCP_SFF_3V3AUX_SCL      B  @S9S_MB_2U_LIB.S9S_MB_2U(SCH_1):SMB_OCP_SFF_3V3AUX_SCL
    1  SMB_OCP_SFF_3V3AUX_R_SCL      A  @S9S_MB_2U_LIB.S9S_MB_2U(SCH_1):SMB_OCP_SFF_3V3AUX_R_SCL

Q_RES  I174  R425   [Q_RES_0402LF-33.2,1%,1/16W,CHIA]
    2  SMB_OCP_SFF_3V3AUX_SDA      B  @S9S_MB_2U_LIB.S9S_MB_2U(SCH_1):SMB_OCP_SFF_3V3AUX_SDA
    1  SMB_OCP_SFF_3V3AUX_R_SDA      A  @S9S_MB_2U_LIB.S9S_MB_2U(SCH_1):SMB_OCP_SFF_3V3AUX_R_SDA

Q_RES  I344  R429   [Q_RES_0402LF-0,5%,1/16W,CHIP,CA]
    2  OCP_SFF_MAIN_PWR_EN      B  @S9S_MB_2U_LIB.S9S_MB_2U(SCH_1):OCP_SFF_MAIN_PWR_EN
    1  HP_LVC3_OCP_V3_1_HSC_PWRGD      A  @S9S_MB_2U_LIB.S9S_MB_2U(SCH_1):HP_LVC3_OCP_V3_1_HSC_PWRGD

Q_RES  I8   R435   [Q_RES_0402LF-33.2,1%,1/16W,CHIA]
    2  RST_PERST1_OCP_SFF_N      B  @S9S_MB_2U_LIB.S9S_MB_2U(SCH_1):RST_PERST1_OCP_SFF_N
    1  RST_OCP_V3_1_BUF_N      A  @S9S_MB_2U_LIB.S9S_MB_2U(SCH_1):RST_OCP_V3_1_BUF_N

Q_RES  I36  R442   [Q_RES_0603LF-1,1%,1/10W,CHIP,CA]
    1  P3V3_AUX_CLK_GEN_VDDXTAL_CK440      A  @S9S_MB_2U_LIB.S9S_MB_2U(SCH_1):P3V3_AUX_CLK_GEN_VDDXTAL_CK440
    2  P3V3_AUX_CLK_GEN_VDDA25M_CK440      B  @S9S_MB_2U_LIB.S9S_MB_2U(SCH_1):P3V3_AUX_CLK_GEN_VDDA25M_CK440

Q_RES  I350  R444   [Q_RES_0402LF-0,5%,1/16W,CHIP,CA]
    2  USB2_3_DN          B  @S9S_MB_2U_LIB.S9S_MB_2U(SCH_1):USB2_3_DN
    1  OCP_SFF_USB2_3_DN      A  @S9S_MB_2U_LIB.S9S_MB_2U(SCH_1):OCP_SFF_USB2_3_DN

Q_RES  I349  R445   [Q_RES_0402LF-0,5%,1/16W,CHIP,CA]
    2  USB2_3_DP          B  @S9S_MB_2U_LIB.S9S_MB_2U(SCH_1):USB2_3_DP
    1  OCP_SFF_USB2_3_DP      A  @S9S_MB_2U_LIB.S9S_MB_2U(SCH_1):OCP_SFF_USB2_3_DP

Q_RES  I55  R447   [Q_RES_0603LF-1,1%,1/10W,CHIP,CA]
    2  P3V3_AUX_CLK_GEN_VDDPT_CK440      B  @S9S_MB_2U_LIB.S9S_MB_2U(SCH_1):P3V3_AUX_CLK_GEN_VDDPT_CK440
    1  P3V3_AUX_CLK_GEN_VDDMXCK_CK440      A  @S9S_MB_2U_LIB.S9S_MB_2U(SCH_1):P3V3_AUX_CLK_GEN_VDDMXCK_CK440

Q_RES  I13  R448   [Q_RES_0402LF-0,5%,1/16W,EMPTY,A]
    2  SMB_S3M_CPU1_3V3AUX_SCL      B  @S9S_MB_2U_LIB.S9S_MB_2U(SCH_1):SMB_S3M_CPU1_3V3AUX_SCL
    1  SMB_S3M_CPU0_3V3AUX_SCL      A  @S9S_MB_2U_LIB.S9S_MB_2U(SCH_1):SMB_S3M_CPU0_3V3AUX_SCL

Q_RES  I77  R453   [Q_RES_0402LF-10K,1%,1/16W,CHIPA]
    2  PU_LAN_WAKE_N      B  @S9S_MB_2U_LIB.S9S_MB_2U(SCH_1):PU_LAN_WAKE_N
    1  P3V3_AUX           A  @S9S_MB_2U_LIB.S9S_MB_2U(SCH_1):P3V3_AUX

Q_RES  I314  R454   [Q_RES_0402LF-10K,1%,1/16W,EMPTA]
    2  PU_RST_SMB_OCP_SFF_N      B  @S9S_MB_2U_LIB.S9S_MB_2U(SCH_1):PU_RST_SMB_OCP_SFF_N
    1  P3V3_OCP_SFF       A  @S9S_MB_2U_LIB.S9S_MB_2U(SCH_1):P3V3_OCP_SFF

Q_RES  I66  R456   [Q_RES_0402LF-10K,1%,1/16W,CHIPA]
    2  PU_PCH_PMCALERT_N      B  @S9S_MB_2U_LIB.S9S_MB_2U(SCH_1):PU_PCH_PMCALERT_N
    1  P3V3_AUX           A  @S9S_MB_2U_LIB.S9S_MB_2U(SCH_1):P3V3_AUX

Q_RES  I15  R459   [Q_RES_0402LF-33.2,1%,1/16W,CHIA]
    2  SMB_TMP75_1_3V3AUX_SDA_R      B  @S9S_MB_2U_LIB.S9S_MB_2U(SCH_1):SMB_TMP75_1_3V3AUX_SDA_R
    1  SMB_SENSOR_3V3AUX_SDA      A  @S9S_MB_2U_LIB.S9S_MB_2U(SCH_1):SMB_SENSOR_3V3AUX_SDA

Q_RES  I14  R460   [Q_RES_0402LF-33.2,1%,1/16W,CHIA]
    2  SMB_TMP75_1_3V3AUX_SCL_R      B  @S9S_MB_2U_LIB.S9S_MB_2U(SCH_1):SMB_TMP75_1_3V3AUX_SCL_R
    1  SMB_SENSOR_3V3AUX_SCL      A  @S9S_MB_2U_LIB.S9S_MB_2U(SCH_1):SMB_SENSOR_3V3AUX_SCL

Q_RES  I10  R461   [Q_RES_0402LF-100K,5%,1/16W,CHIA]
    2  PU_USB_INT_P5V_EN_N      B  @S9S_MB_2U_LIB.S9S_MB_2U(SCH_1):PU_USB_INT_P5V_EN_N
    1  P5V                A  @S9S_MB_2U_LIB.S9S_MB_2U(SCH_1):P5V

Q_RES  I25  R462   [Q_RES_0402LF-20K,1%,1/16W,CHIPA]
    1  PD_USB_INT_ILIM      A  @S9S_MB_2U_LIB.S9S_MB_2U(SCH_1):PD_USB_INT_ILIM
    2  GND                B  @S9S_MB_2U_LIB.S9S_MB_2U(SCH_1):GND

Q_RES  I29  R463   [Q_RES_0402LF-10K,1%,1/16W,CHIPA]
    2  USB_OC2_INT_N      B  @S9S_MB_2U_LIB.S9S_MB_2U(SCH_1):USB_OC2_INT_N
    1  P3V3_AUX           A  @S9S_MB_2U_LIB.S9S_MB_2U(SCH_1):P3V3_AUX

Q_RES  I27  R464   [Q_RES_0402LF-0,5%,1/16W,CHIP,CA]
    2  USB3_9_TX_DN_FB      B  @S9S_MB_2U_LIB.S9S_MB_2U(SCH_1):USB3_9_TX_DN_FB
    1  USB3_9_TX_DN_C      A  @S9S_MB_2U_LIB.S9S_MB_2U(SCH_1):USB3_9_TX_DN_C

Q_RES  I21  R465   [Q_RES_0402LF-0,5%,1/16W,CHIP,CA]
    2  USB3_9_TX_DP_FB      B  @S9S_MB_2U_LIB.S9S_MB_2U(SCH_1):USB3_9_TX_DP_FB
    1  USB3_9_TX_DP_C      A  @S9S_MB_2U_LIB.S9S_MB_2U(SCH_1):USB3_9_TX_DP_C

Q_RES  I20  R466   [Q_RES_0402LF-0,5%,1/16W,CHIP,CA]
    2  USB3_9_RX_DN_FB      B  @S9S_MB_2U_LIB.S9S_MB_2U(SCH_1):USB3_9_RX_DN_FB
    1  USB3_9_RX_DN       A  @S9S_MB_2U_LIB.S9S_MB_2U(SCH_1):USB3_9_RX_DN

Q_RES  I19  R468   [Q_RES_0402LF-0,5%,1/16W,CHIP,CA]
    2  USB3_9_RX_DP_FB      B  @S9S_MB_2U_LIB.S9S_MB_2U(SCH_1):USB3_9_RX_DP_FB
    1  USB3_9_RX_DP       A  @S9S_MB_2U_LIB.S9S_MB_2U(SCH_1):USB3_9_RX_DP

Q_RES  I5   R469   [Q_RES_0402LF-0,5%,1/16W,CHIP,CA]
    2  USB2_1_F_DP        B  @S9S_MB_2U_LIB.S9S_MB_2U(SCH_1):USB2_1_F_DP
    1  USB2_1_DP          A  @S9S_MB_2U_LIB.S9S_MB_2U(SCH_1):USB2_1_DP

Q_RES  I3   R470   [Q_RES_0402LF-0,5%,1/16W,CHIP,CA]
    2  USB2_1_F_DN        B  @S9S_MB_2U_LIB.S9S_MB_2U(SCH_1):USB2_1_F_DN
    1  USB2_1_DN          A  @S9S_MB_2U_LIB.S9S_MB_2U(SCH_1):USB2_1_DN

Q_RES  I30  R471   [Q_RES_0402LF-0,5%,1/16W,CHIP,CA]
    2  USB_OC2_INT_R_N      B  @S9S_MB_2U_LIB.S9S_MB_2U(SCH_1):USB_OC2_INT_R_N
    1  USB_OC2_INT_N      A  @S9S_MB_2U_LIB.S9S_MB_2U(SCH_1):USB_OC2_INT_N

Q_RES  I204  R473   [Q_RES_0402LF-0,5%,1/16W,CHIP,CA]
    1  IRQ_PSU_ALERT_N      A  @S9S_MB_2U_LIB.S9S_MB_2U(SCH_1):IRQ_PSU_ALERT_N
    2  FM_OV_ADR_TRIGGER_N      B  @S9S_MB_2U_LIB.S9S_MB_2U(SCH_1):FM_OV_ADR_TRIGGER_N

Q_RES  I213  R474   [Q_RES_0402LF-33,5%,1/16W,CHIP,A]
    2  FM_PCHHOT_R_N      B  @S9S_MB_2U_LIB.S9S_MB_2U(SCH_1):FM_PCHHOT_R_N
    1  FM_PCHHOT_N        A  @S9S_MB_2U_LIB.S9S_MB_2U(SCH_1):FM_PCHHOT_N

Q_RES  I39  R475   [Q_RES_0402LF-33.2,1%,1/16W,CHIA]
    1  SMB_SENSOR_3V3AUX_SCL      A  @S9S_MB_2U_LIB.S9S_MB_2U(SCH_1):SMB_SENSOR_3V3AUX_SCL
    2  SMB_FRU_3V3AUX_SCL_R      B  @S9S_MB_2U_LIB.S9S_MB_2U(SCH_1):SMB_FRU_3V3AUX_SCL_R

Q_RES  I69  R477   [Q_RES_0402LF-60.4,1%,1/16W,CHIA]
    1  PD_PCH_XCLK_BIASREF      A  @S9S_MB_2U_LIB.S9S_MB_2U(SCH_1):PD_PCH_XCLK_BIASREF
    2  GND                B  @S9S_MB_2U_LIB.S9S_MB_2U(SCH_1):GND

Q_RES  I176  R478   [Q_RES_0402LF-4.7K,1%,1/16W,CHIA]
    2  PCIE_M2_SSD0_PRSNT_N      B  @S9S_MB_2U_LIB.S9S_MB_2U(SCH_1):PCIE_M2_SSD0_PRSNT_N
    1  P3V3_AUX           A  @S9S_MB_2U_LIB.S9S_MB_2U(SCH_1):P3V3_AUX

Q_RES  I59  R480   [Q_RES_0402LF-0,5%,1/16W,CHIP,CA]
    1  JTAG_DBP_TMS       A  @S9S_MB_2U_LIB.S9S_MB_2U(SCH_1):JTAG_DBP_TMS
    2  JTAG_DBP_FB_TMS      B  @S9S_MB_2U_LIB.S9S_MB_2U(SCH_1):JTAG_DBP_FB_TMS

Q_RES  I58  R481   [Q_RES_0402LF-0,5%,1/16W,CHIP,CA]
    1  JTAG_DBP_TDI       A  @S9S_MB_2U_LIB.S9S_MB_2U(SCH_1):JTAG_DBP_TDI
    2  JTAG_DBP_FB_TDI      B  @S9S_MB_2U_LIB.S9S_MB_2U(SCH_1):JTAG_DBP_FB_TDI

Q_RES  I57  R482   [Q_RES_0402LF-0,5%,1/16W,CHIP,CA]
    2  JTAG_DBP_PREQ_R_N      B  @S9S_MB_2U_LIB.S9S_MB_2U(SCH_1):JTAG_DBP_PREQ_R_N
    1  JTAG_DBP_PREQ_N      A  @S9S_MB_2U_LIB.S9S_MB_2U(SCH_1):JTAG_DBP_PREQ_N

Q_RES  I37  R483   [Q_RES_0402LF-0,5%,1/16W,CHIP,CA]
    1  JTAG_BMC_DBP_TDO_R      A  @S9S_MB_2U_LIB.S9S_MB_2U(SCH_1):JTAG_BMC_DBP_TDO_R
    2  JTAG_BMC_DBP_TDO      B  @S9S_MB_2U_LIB.S9S_MB_2U(SCH_1):JTAG_BMC_DBP_TDO

Q_RES  I170  R484   [Q_RES_0402LF-4.7K,1%,1/16W,EMPA]
    2  PU_DAS_DSS_N       B  @S9S_MB_2U_LIB.S9S_MB_2U(SCH_1):PU_DAS_DSS_N
    1  P3V3               A  @S9S_MB_2U_LIB.S9S_MB_2U(SCH_1):P3V3

Q_RES  I122  R485   [Q_RES_0402LF-0,5%,1/16W,CHIP,CA]
    1  RST_PCIE_PCH_DEV_PERST_N      A  @S9S_MB_2U_LIB.S9S_MB_2U(SCH_1):RST_PCIE_PCH_DEV_PERST_N
    2  RST_PCIE_PCH_DEV_0_N      B  @S9S_MB_2U_LIB.S9S_MB_2U(SCH_1):RST_PCIE_PCH_DEV_0_N

Q_RES  I162  R486   [Q_RES_0402LF-0,5%,1/16W,CHIP,CA]
    2  M2_SSD0_CLKREQ_EN_N_BUF      B  @S9S_MB_2U_LIB.S9S_MB_2U(SCH_1):M2_SSD0_CLKREQ_EN_N_BUF
    1  M2_SSD0_CLKREQ_EN_N      A  @S9S_MB_2U_LIB.S9S_MB_2U(SCH_1):M2_SSD0_CLKREQ_EN_N

Q_RES  I173  R487   [Q_RES_0402LF-1K,1%,1/16W,EMPTYA]
    1  P3V3_AUX           A  @S9S_MB_2U_LIB.S9S_MB_2U(SCH_1):P3V3_AUX
    2  M2_SSD0_CLKREQ_EN_N_BUF      B  @S9S_MB_2U_LIB.S9S_MB_2U(SCH_1):M2_SSD0_CLKREQ_EN_N_BUF

Q_RES  I164  R491   [Q_RES_0402LF-4.7K,1%,1/16W,EMPA]
    1  M2_SSD0_CLKREQ_EN_N      A  @S9S_MB_2U_LIB.S9S_MB_2U(SCH_1):M2_SSD0_CLKREQ_EN_N
    2  GND                B  @S9S_MB_2U_LIB.S9S_MB_2U(SCH_1):GND

Q_RES  I4   R494   [Q_RES_0402LF-4.75K,1%,1/16W,CHA]
    1  P3V3_AUX           A  @S9S_MB_2U_LIB.S9S_MB_2U(SCH_1):P3V3_AUX
    2  IRQ_LVC3_WAKE_N      B  @S9S_MB_2U_LIB.S9S_MB_2U(SCH_1):IRQ_LVC3_WAKE_N

Q_RES  I118  R495   [Q_RES_0402LF-100,1%,1/16W,CHIPA]
    1  PCH_PCIEUP_RCOMPP      A  @S9S_MB_2U_LIB.S9S_MB_2U(SCH_1):PCH_PCIEUP_RCOMPP
    2  PCH_PCIEUP_RCOMPN      B  @S9S_MB_2U_LIB.S9S_MB_2U(SCH_1):PCH_PCIEUP_RCOMPN

Q_RES  I10  R496   [Q_RES_0402LF-113,1%,1/16W,CHIPA]
    1  PD_PCH_USB2_COMP      A  @S9S_MB_2U_LIB.S9S_MB_2U(SCH_1):PD_PCH_USB2_COMP
    2  GND                B  @S9S_MB_2U_LIB.S9S_MB_2U(SCH_1):GND

Q_RES  I2   R497   [Q_RES_0402LF-200,1%,1/16W,CHIPA]
    1  PD_RCOMP_1P8_3P3      A  @S9S_MB_2U_LIB.S9S_MB_2U(SCH_1):PD_RCOMP_1P8_3P3
    2  GND                B  @S9S_MB_2U_LIB.S9S_MB_2U(SCH_1):GND

Q_RES  I24  R498   [Q_RES_0402LF-10K,1%,1/16W,CHIPA]
    1  P3V3_AUX           A  @S9S_MB_2U_LIB.S9S_MB_2U(SCH_1):P3V3_AUX
    2  FM_PCH_PRSNT_N      B  @S9S_MB_2U_LIB.S9S_MB_2U(SCH_1):FM_PCH_PRSNT_N

Q_RES  I106  R499   [Q_RES_0402LF-33.2,1%,1/16W,CHIA]
    2  SPI_SYS_CLK        B  @S9S_MB_2U_LIB.S9S_MB_2U(SCH_1):SPI_SYS_CLK
    1  SPI_PCH_CLK        A  @S9S_MB_2U_LIB.S9S_MB_2U(SCH_1):SPI_PCH_CLK

Q_RES  I101  R500   [Q_RES_0402LF-33.2,1%,1/16W,CHIA]
    2  SPI_PCH_PFR_CS1_N      B  @S9S_MB_2U_LIB.S9S_MB_2U(SCH_1):SPI_PCH_PFR_CS1_N
    1  SPI_PCH_CS1_R_N      A  @S9S_MB_2U_LIB.S9S_MB_2U(SCH_1):SPI_PCH_CS1_R_N

Q_RES  I100  R501   [Q_RES_0402LF-33.2,1%,1/16W,CHIA]
    2  SPI_SYS_CS0_N      B  @S9S_MB_2U_LIB.S9S_MB_2U(SCH_1):SPI_SYS_CS0_N
    1  SPI_PCH_CS0_R_N      A  @S9S_MB_2U_LIB.S9S_MB_2U(SCH_1):SPI_PCH_CS0_R_N

Q_RES  I68  R502   [Q_RES_0402LF-20K,5%,1/16W,EMPTA]
    1  P3V3_AUX           A  @S9S_MB_2U_LIB.S9S_MB_2U(SCH_1):P3V3_AUX
    2  FM_PCH_CONSENT_STRAP_N      B  @S9S_MB_2U_LIB.S9S_MB_2U(SCH_1):FM_PCH_CONSENT_STRAP_N

Q_RES  I543  R506   [Q_RES_0402LF-0,5%,1/16W,CHIP,CA]
    1  IRQ_SMI_ACTIVE_BMC_N      A  @S9S_MB_2U_LIB.S9S_MB_2U(SCH_1):IRQ_SMI_ACTIVE_BMC_N
    2  IRQ0_A57           B  @S9S_MB_2U_LIB.S9S_MB_2U(SCH_1):IRQ0_A57

Q_RES  I173  R507   [Q_RES_0402LF-0,5%,1/16W,EMPTY,A]
    1  PVCCA_AUX_PLD      A  @S9S_MB_2U_LIB.S9S_MB_2U(SCH_1):PVCCA_AUX_PLD
    2  P3V3_AUX_DPLD_ADC_VREF      B  @S9S_MB_2U_LIB.S9S_MB_2U(SCH_1):P3V3_AUX_DPLD_ADC_VREF

Q_RES  I172  R508   [Q_RES_0402LF-0,5%,1/16W,EMPTY,A]
    1  P3V3_AUX_DPLD_ADC_VREF      A  @S9S_MB_2U_LIB.S9S_MB_2U(SCH_1):P3V3_AUX_DPLD_ADC_VREF
    2  GND                B  @S9S_MB_2U_LIB.S9S_MB_2U(SCH_1):GND

Q_RES  I197  R509   [Q_RES_0402LF-0,5%,1/16W,CHIP,CA]
    2  GND                B  @S9S_MB_2U_LIB.S9S_MB_2U(SCH_1):GND
    1  FP_DPLD_ANAIN1      A  @S9S_MB_2U_LIB.S9S_MB_2U(SCH_1):FP_DPLD_ANAIN1

Q_RES  I266  R511   [Q_RES_1206LF-0,5%,1/4W,CHIP,CSA]
    2  PVCCIO_PLDIO2      B  @S9S_MB_2U_LIB.S9S_MB_2U(SCH_1):PVCCIO_PLDIO2
    1  PVCCD_HV_CPU0      A  @S9S_MB_2U_LIB.S9S_MB_2U(SCH_1):PVCCD_HV_CPU0

Q_RES  I267  R512   [Q_RES_1206LF-0,5%,1/4W,EMPTY,CA]
    2  PVCCIO_PLDIO2      B  @S9S_MB_2U_LIB.S9S_MB_2U(SCH_1):PVCCIO_PLDIO2
    1  P3V3_AUX           A  @S9S_MB_2U_LIB.S9S_MB_2U(SCH_1):P3V3_AUX

Q_RES  I258  R513   [Q_RES_1206LF-0,5%,1/4W,CHIP,CSA]
    1  PVNN_TERM_CPU0      A  @S9S_MB_2U_LIB.S9S_MB_2U(SCH_1):PVNN_TERM_CPU0
    2  PVCCIO_PLDIO5      B  @S9S_MB_2U_LIB.S9S_MB_2U(SCH_1):PVCCIO_PLDIO5

Q_RES  I259  R514   [Q_RES_1206LF-0,5%,1/4W,EMPTY,CA]
    2  PVCCIO_PLDIO5      B  @S9S_MB_2U_LIB.S9S_MB_2U(SCH_1):PVCCIO_PLDIO5
    1  P3V3_AUX           A  @S9S_MB_2U_LIB.S9S_MB_2U(SCH_1):P3V3_AUX

Q_RES  I7   R515   [Q_RES_0402LF-10K,1%,1/16W,CHIPA]
    1  PD_PIROM_CPU0_ADDR0      A  @S9S_MB_2U_LIB.S9S_MB_2U(SCH_1):PD_PIROM_CPU0_ADDR0
    2  GND                B  @S9S_MB_2U_LIB.S9S_MB_2U(SCH_1):GND

Q_RES  I7   R519   [Q_RES_0603LF-1,1%,1/10W,CHIP,CA]
    1  P3V3_AUX_CLK_GEN_VDD_CK440      A  @S9S_MB_2U_LIB.S9S_MB_2U(SCH_1):P3V3_AUX_CLK_GEN_VDD_CK440
    2  P3V3_AUX_CLK_GEN_VDDA100M_CK440      B  @S9S_MB_2U_LIB.S9S_MB_2U(SCH_1):P3V3_AUX_CLK_GEN_VDDA100M_CK440

Q_RES  I28  R520   [Q_RES_0402LF-0,5%,1/16W,CHIP,CA]
    1  CLK_100M_PE_2_R_DP      A  @S9S_MB_2U_LIB.S9S_MB_2U(SCH_1):CLK_100M_PE_2_R_DP
    2  CLK_100M_PE_2_DP      B  @S9S_MB_2U_LIB.S9S_MB_2U(SCH_1):CLK_100M_PE_2_DP

Q_RES  I123  R521   [Q_RES_0402LF-0,5%,1/16W,CHIP,CA]
    1  CLK_100M_PE_2_R_DN      A  @S9S_MB_2U_LIB.S9S_MB_2U(SCH_1):CLK_100M_PE_2_R_DN
    2  CLK_100M_PE_2_DN      B  @S9S_MB_2U_LIB.S9S_MB_2U(SCH_1):CLK_100M_PE_2_DN

Q_RES  I129  R522   [Q_RES_0402LF-0,5%,1/16W,CHIP,CA]
    1  CLK_100M_PE_3_R_DP      A  @S9S_MB_2U_LIB.S9S_MB_2U(SCH_1):CLK_100M_PE_3_R_DP
    2  CLK_100M_PE_3_DP      B  @S9S_MB_2U_LIB.S9S_MB_2U(SCH_1):CLK_100M_PE_3_DP

Q_RES  I128  R523   [Q_RES_0402LF-0,5%,1/16W,CHIP,CA]
    1  CLK_100M_PE_3_R_DN      A  @S9S_MB_2U_LIB.S9S_MB_2U(SCH_1):CLK_100M_PE_3_R_DN
    2  CLK_100M_PE_3_DN      B  @S9S_MB_2U_LIB.S9S_MB_2U(SCH_1):CLK_100M_PE_3_DN

Q_RES  I136  R524   [Q_RES_0402LF-0,5%,1/16W,CHIP,CA]
    1  CLK_100M_PE_4_R_DP      A  @S9S_MB_2U_LIB.S9S_MB_2U(SCH_1):CLK_100M_PE_4_R_DP
    2  CLK_100M_PE_4_DP      B  @S9S_MB_2U_LIB.S9S_MB_2U(SCH_1):CLK_100M_PE_4_DP

Q_RES  I135  R525   [Q_RES_0402LF-0,5%,1/16W,CHIP,CA]
    1  CLK_100M_PE_4_R_DN      A  @S9S_MB_2U_LIB.S9S_MB_2U(SCH_1):CLK_100M_PE_4_R_DN
    2  CLK_100M_PE_4_DN      B  @S9S_MB_2U_LIB.S9S_MB_2U(SCH_1):CLK_100M_PE_4_DN

Q_RES  I137  R526   [Q_RES_0402LF-0,5%,1/16W,CHIP,CA]
    1  CLK_100M_PE_5_R_DP      A  @S9S_MB_2U_LIB.S9S_MB_2U(SCH_1):CLK_100M_PE_5_R_DP
    2  CLK_100M_PE_5_DP      B  @S9S_MB_2U_LIB.S9S_MB_2U(SCH_1):CLK_100M_PE_5_DP

Q_RES  I138  R527   [Q_RES_0402LF-0,5%,1/16W,CHIP,CA]
    1  CLK_100M_PE_5_R_DN      A  @S9S_MB_2U_LIB.S9S_MB_2U(SCH_1):CLK_100M_PE_5_R_DN
    2  CLK_100M_PE_5_DN      B  @S9S_MB_2U_LIB.S9S_MB_2U(SCH_1):CLK_100M_PE_5_DN

Q_RES  I239  R528   [Q_RES_0402LF-0,5%,1/16W,CHIP,CA]
    1  CLK_100M_E1S_0_R_DP      A  @S9S_MB_2U_LIB.S9S_MB_2U(SCH_1):CLK_100M_E1S_0_R_DP
    2  CLK_100M_E1S_0_DP      B  @S9S_MB_2U_LIB.S9S_MB_2U(SCH_1):CLK_100M_E1S_0_DP

Q_RES  I242  R529   [Q_RES_0402LF-0,5%,1/16W,CHIP,CA]
    1  CLK_100M_E1S_0_R_DN      A  @S9S_MB_2U_LIB.S9S_MB_2U(SCH_1):CLK_100M_E1S_0_R_DN
    2  CLK_100M_E1S_0_DN      B  @S9S_MB_2U_LIB.S9S_MB_2U(SCH_1):CLK_100M_E1S_0_DN

Q_RES  I241  R530   [Q_RES_0402LF-0,5%,1/16W,CHIP,CA]
    1  CLK_100M_E1S_1_R_DP      A  @S9S_MB_2U_LIB.S9S_MB_2U(SCH_1):CLK_100M_E1S_1_R_DP
    2  CLK_100M_E1S_1_DP      B  @S9S_MB_2U_LIB.S9S_MB_2U(SCH_1):CLK_100M_E1S_1_DP

Q_RES  I240  R531   [Q_RES_0402LF-0,5%,1/16W,CHIP,CA]
    1  CLK_100M_E1S_1_R_DN      A  @S9S_MB_2U_LIB.S9S_MB_2U(SCH_1):CLK_100M_E1S_1_R_DN
    2  CLK_100M_E1S_1_DN      B  @S9S_MB_2U_LIB.S9S_MB_2U(SCH_1):CLK_100M_E1S_1_DN

Q_RES  I243  R532   [Q_RES_0402LF-0,5%,1/16W,CHIP,CA]
    1  CLK_100M_E1S_2_R_DP      A  @S9S_MB_2U_LIB.S9S_MB_2U(SCH_1):CLK_100M_E1S_2_R_DP
    2  CLK_100M_E1S_2_DP      B  @S9S_MB_2U_LIB.S9S_MB_2U(SCH_1):CLK_100M_E1S_2_DP

Q_RES  I244  R533   [Q_RES_0402LF-0,5%,1/16W,CHIP,CA]
    1  CLK_100M_E1S_2_R_DN      A  @S9S_MB_2U_LIB.S9S_MB_2U(SCH_1):CLK_100M_E1S_2_R_DN
    2  CLK_100M_E1S_2_DN      B  @S9S_MB_2U_LIB.S9S_MB_2U(SCH_1):CLK_100M_E1S_2_DN

Q_RES  I246  R534   [Q_RES_0402LF-0,5%,1/16W,CHIP,CA]
    1  CLK_100M_E1S_3_R_DP      A  @S9S_MB_2U_LIB.S9S_MB_2U(SCH_1):CLK_100M_E1S_3_R_DP
    2  CLK_100M_E1S_3_DP      B  @S9S_MB_2U_LIB.S9S_MB_2U(SCH_1):CLK_100M_E1S_3_DP

Q_RES  I247  R535   [Q_RES_0402LF-0,5%,1/16W,CHIP,CA]
    1  CLK_100M_E1S_3_R_DN      A  @S9S_MB_2U_LIB.S9S_MB_2U(SCH_1):CLK_100M_E1S_3_R_DN
    2  CLK_100M_E1S_3_DN      B  @S9S_MB_2U_LIB.S9S_MB_2U(SCH_1):CLK_100M_E1S_3_DN

Q_RES  I7   R536   [Q_RES_0402LF-10K,1%,1/16W,EMPTA]
    2  PCA9546_PCIE0_ADDR2      B  @S9S_MB_2U_LIB.S9S_MB_2U(SCH_1):PCA9546_PCIE0_ADDR2
    1  P3V3_AUX           A  @S9S_MB_2U_LIB.S9S_MB_2U(SCH_1):P3V3_AUX

Q_RES  I2   R537   [Q_RES_0402LF-1K,1%,1/16W,CHIP,A]
    1  PCA9546_PCIE0_ADDR2      A  @S9S_MB_2U_LIB.S9S_MB_2U(SCH_1):PCA9546_PCIE0_ADDR2
    2  GND                B  @S9S_MB_2U_LIB.S9S_MB_2U(SCH_1):GND

Q_RES  I9   R538   [Q_RES_0402LF-10K,1%,1/16W,EMPTA]
    2  PCA9546_PCIE0_ADDR1      B  @S9S_MB_2U_LIB.S9S_MB_2U(SCH_1):PCA9546_PCIE0_ADDR1
    1  P3V3_AUX           A  @S9S_MB_2U_LIB.S9S_MB_2U(SCH_1):P3V3_AUX

Q_RES  I4   R539   [Q_RES_0402LF-1K,1%,1/16W,CHIP,A]
    1  PCA9546_PCIE0_ADDR1      A  @S9S_MB_2U_LIB.S9S_MB_2U(SCH_1):PCA9546_PCIE0_ADDR1
    2  GND                B  @S9S_MB_2U_LIB.S9S_MB_2U(SCH_1):GND

Q_RES  I10  R540   [Q_RES_0402LF-10K,1%,1/16W,EMPTA]
    2  PCA9546_PCIE0_ADDR0      B  @S9S_MB_2U_LIB.S9S_MB_2U(SCH_1):PCA9546_PCIE0_ADDR0
    1  P3V3_AUX           A  @S9S_MB_2U_LIB.S9S_MB_2U(SCH_1):P3V3_AUX

Q_RES  I15  R541   [Q_RES_0402LF-0,5%,1/16W,CHIP,CA]
    2  PVCCIN_CPU0_PIN_ALERT      B  @S9S_MB_2U_LIB.S9S_MB_2U(SCH_1):PVCCIN_CPU0_PIN_ALERT
    1  IRQ_PSYS_CRIT_N      A  @S9S_MB_2U_LIB.S9S_MB_2U(SCH_1):IRQ_PSYS_CRIT_N

Q_RES  I94  R548   [Q_RES_0402LF-49.9     ,1%  ,1/A]
    1  SVID_ALERT0_CPU0_R_N      A  @S9S_MB_2U_LIB.S9S_MB_2U(SCH_1):SVID_ALERT0_CPU0_R_N
    2  PVNN_TERM_CPU0      B  @S9S_MB_2U_LIB.S9S_MB_2U(SCH_1):PVNN_TERM_CPU0

Q_RES  I225  R553   [Q_RES_0402LF-0,5%,1/16W,CHIP,CA]
    1  CLK_100M_CK440_PCH_EXTCLK_R_DP      A  @S9S_MB_2U_LIB.S9S_MB_2U(SCH_1):CLK_100M_CK440_PCH_EXTCLK_R_DP
    2  CLK_100M_CK440_PCH_EXTCLK_DP      B  @S9S_MB_2U_LIB.S9S_MB_2U(SCH_1):CLK_100M_CK440_PCH_EXTCLK_DP

Q_RES  I226  R554   [Q_RES_0402LF-0,5%,1/16W,CHIP,CA]
    1  CLK_100M_CK440_PCH_EXTCLK_R_DN      A  @S9S_MB_2U_LIB.S9S_MB_2U(SCH_1):CLK_100M_CK440_PCH_EXTCLK_R_DN
    2  CLK_100M_CK440_PCH_EXTCLK_DN      B  @S9S_MB_2U_LIB.S9S_MB_2U(SCH_1):CLK_100M_CK440_PCH_EXTCLK_DN

Q_RES  I98  R555   [Q_RES_0402LF-100,1%,1/16W,CHIPA]
    1  SVID_DIO1_CPU0_R      A  @S9S_MB_2U_LIB.S9S_MB_2U(SCH_1):SVID_DIO1_CPU0_R
    2  PVNN_TERM_CPU0      B  @S9S_MB_2U_LIB.S9S_MB_2U(SCH_1):PVNN_TERM_CPU0

Q_RES  I100  R556   [Q_RES_0402LF-49.9     ,1%  ,1/A]
    1  SVID_ALERT1_CPU0_R_N      A  @S9S_MB_2U_LIB.S9S_MB_2U(SCH_1):SVID_ALERT1_CPU0_R_N
    2  PVNN_TERM_CPU0      B  @S9S_MB_2U_LIB.S9S_MB_2U(SCH_1):PVNN_TERM_CPU0

Q_RES  I74  R557   [Q_RES_0402LF-100,1%,1/16W,CHIPA]
    1  SVID_DIO0_CPU1_R      A  @S9S_MB_2U_LIB.S9S_MB_2U(SCH_1):SVID_DIO0_CPU1_R
    2  PVNN_TERM_CPU0      B  @S9S_MB_2U_LIB.S9S_MB_2U(SCH_1):PVNN_TERM_CPU0

Q_RES  I73  R558   [Q_RES_0402LF-49.9     ,1%  ,1/A]
    1  SVID_ALERT0_CPU1_R_N      A  @S9S_MB_2U_LIB.S9S_MB_2U(SCH_1):SVID_ALERT0_CPU1_R_N
    2  PVNN_TERM_CPU0      B  @S9S_MB_2U_LIB.S9S_MB_2U(SCH_1):PVNN_TERM_CPU0

Q_RES  I69  R559   [Q_RES_0402LF-100,1%,1/16W,CHIPA]
    1  SVID_DIO1_CPU1_R      A  @S9S_MB_2U_LIB.S9S_MB_2U(SCH_1):SVID_DIO1_CPU1_R
    2  PVNN_TERM_CPU0      B  @S9S_MB_2U_LIB.S9S_MB_2U(SCH_1):PVNN_TERM_CPU0

Q_RES  I70  R560   [Q_RES_0402LF-49.9     ,1%  ,1/A]
    1  SVID_ALERT1_CPU1_R_N      A  @S9S_MB_2U_LIB.S9S_MB_2U(SCH_1):SVID_ALERT1_CPU1_R_N
    2  PVNN_TERM_CPU0      B  @S9S_MB_2U_LIB.S9S_MB_2U(SCH_1):PVNN_TERM_CPU0

Q_RES  I21  R561   [Q_RES_0402LF-100,1%,1/16W,EMPTA]
    2  SVID_DIO0_CPU0_R      B  @S9S_MB_2U_LIB.S9S_MB_2U(SCH_1):SVID_DIO0_CPU0_R
    1  PVNN_TERM_CPU0      A  @S9S_MB_2U_LIB.S9S_MB_2U(SCH_1):PVNN_TERM_CPU0

Q_RES  I280  R562   [Q_RES_0402LF-4.75K,1%,1/16W,EMA]
    1  P3V3_AUX           A  @S9S_MB_2U_LIB.S9S_MB_2U(SCH_1):P3V3_AUX
    2  CLK_CK440_SMB_ADDR1      B  @S9S_MB_2U_LIB.S9S_MB_2U(SCH_1):CLK_CK440_SMB_ADDR1

Q_RES  I169  R563   [Q_RES_0402LF-0,5%,1/16W,CHIP,CA]
    1  CLK_100M_OCP_SFF_0_R_DP      A  @S9S_MB_2U_LIB.S9S_MB_2U(SCH_1):CLK_100M_OCP_SFF_0_R_DP
    2  CLK_100M_OCP_SFF_0_DP      B  @S9S_MB_2U_LIB.S9S_MB_2U(SCH_1):CLK_100M_OCP_SFF_0_DP

Q_RES  I170  R564   [Q_RES_0402LF-0,5%,1/16W,CHIP,CA]
    1  CLK_100M_OCP_SFF_0_R_DN      A  @S9S_MB_2U_LIB.S9S_MB_2U(SCH_1):CLK_100M_OCP_SFF_0_R_DN
    2  CLK_100M_OCP_SFF_0_DN      B  @S9S_MB_2U_LIB.S9S_MB_2U(SCH_1):CLK_100M_OCP_SFF_0_DN

Q_RES  I167  R565   [Q_RES_0402LF-0,5%,1/16W,CHIP,CA]
    1  CLK_100M_OCP_SFF_1_R_DP      A  @S9S_MB_2U_LIB.S9S_MB_2U(SCH_1):CLK_100M_OCP_SFF_1_R_DP
    2  CLK_100M_OCP_SFF_1_DP      B  @S9S_MB_2U_LIB.S9S_MB_2U(SCH_1):CLK_100M_OCP_SFF_1_DP

Q_RES  I168  R566   [Q_RES_0402LF-0,5%,1/16W,CHIP,CA]
    1  CLK_100M_OCP_SFF_1_R_DN      A  @S9S_MB_2U_LIB.S9S_MB_2U(SCH_1):CLK_100M_OCP_SFF_1_R_DN
    2  CLK_100M_OCP_SFF_1_DN      B  @S9S_MB_2U_LIB.S9S_MB_2U(SCH_1):CLK_100M_OCP_SFF_1_DN

Q_RES  I179  R567   [Q_RES_0402LF-4.7K,1%,1/16W,EMPA]
    2  PD_DB2000_SMB_SA1      B  @S9S_MB_2U_LIB.S9S_MB_2U(SCH_1):PD_DB2000_SMB_SA1
    1  P3V3               A  @S9S_MB_2U_LIB.S9S_MB_2U(SCH_1):P3V3

Q_RES  I178  R568   [Q_RES_0402LF-4.7K,1%,1/16W,CHIA]
    1  PD_DB2000_SMB_SA1      A  @S9S_MB_2U_LIB.S9S_MB_2U(SCH_1):PD_DB2000_SMB_SA1
    2  GND                B  @S9S_MB_2U_LIB.S9S_MB_2U(SCH_1):GND

Q_RES  I185  R569   [Q_RES_0402LF-4.7K,1%,1/16W,EMPA]
    2  PD_DB2000_SMB_SA0      B  @S9S_MB_2U_LIB.S9S_MB_2U(SCH_1):PD_DB2000_SMB_SA0
    1  P3V3               A  @S9S_MB_2U_LIB.S9S_MB_2U(SCH_1):P3V3

Q_RES  I187  R570   [Q_RES_0402LF-4.7K,1%,1/16W,CHIA]
    1  PD_DB2000_SMB_SA0      A  @S9S_MB_2U_LIB.S9S_MB_2U(SCH_1):PD_DB2000_SMB_SA0
    2  GND                B  @S9S_MB_2U_LIB.S9S_MB_2U(SCH_1):GND

Q_RES  I163  R571   [Q_RES_0603LF-2.2,1%,1/10W,CHIPA]
    2  P3V3_DB2000_VDDR      B  @S9S_MB_2U_LIB.S9S_MB_2U(SCH_1):P3V3_DB2000_VDDR
    1  P3V3_DB2000_FB_VDD      A  @S9S_MB_2U_LIB.S9S_MB_2U(SCH_1):P3V3_DB2000_FB_VDD

Q_RES  I162  R572   [Q_RES_0603LF-2.2,1%,1/10W,CHIPA]
    2  P3V3_DB2000_VDDA      B  @S9S_MB_2U_LIB.S9S_MB_2U(SCH_1):P3V3_DB2000_VDDA
    1  P3V3_DB2000_FB_VDD      A  @S9S_MB_2U_LIB.S9S_MB_2U(SCH_1):P3V3_DB2000_FB_VDD

Q_RES  I194  R573   [Q_RES_0402LF-4.7K,1%,1/16W,EMPA]
    1  P3V3               A  @S9S_MB_2U_LIB.S9S_MB_2U(SCH_1):P3V3
    2  FM_DB2000_VSBEN      B  @S9S_MB_2U_LIB.S9S_MB_2U(SCH_1):FM_DB2000_VSBEN

Q_RES  I197  R574   [Q_RES_0402LF-4.7K,1%,1/16W,CHIA]
    2  GND                B  @S9S_MB_2U_LIB.S9S_MB_2U(SCH_1):GND
    1  FM_DB2000_VSBEN      A  @S9S_MB_2U_LIB.S9S_MB_2U(SCH_1):FM_DB2000_VSBEN

Q_RES  I199  R575   [Q_RES_0402LF-49.9     ,1%  ,1/A]
    1  FM_PLD_CLKS_DEV_EN      A  @S9S_MB_2U_LIB.S9S_MB_2U(SCH_1):FM_PLD_CLKS_DEV_EN
    2  FM_DB2000_DEV_EN      B  @S9S_MB_2U_LIB.S9S_MB_2U(SCH_1):FM_DB2000_DEV_EN

Q_RES  I156  R576   [Q_RES_0402LF-49.9     ,1%  ,1/A]
    1  FM_DB2000_OE_N      A  @S9S_MB_2U_LIB.S9S_MB_2U(SCH_1):FM_DB2000_OE_N
    2  FM_DB2000_1_OE_N      B  @S9S_MB_2U_LIB.S9S_MB_2U(SCH_1):FM_DB2000_1_OE_N

Q_RES  I36  R577   [Q_RES_0402LF-33,5%,1/16W,CHIP,A]
    2  SMB_HOST_3V3AUX_SCL_R      B  @S9S_MB_2U_LIB.S9S_MB_2U(SCH_1):SMB_HOST_3V3AUX_SCL_R
    1  SMB_HOST_3V3AUX_SCL      A  @S9S_MB_2U_LIB.S9S_MB_2U(SCH_1):SMB_HOST_3V3AUX_SCL

Q_RES  I37  R578   [Q_RES_0402LF-33,5%,1/16W,CHIP,A]
    2  SMB_HOST_3V3AUX_SDA_R      B  @S9S_MB_2U_LIB.S9S_MB_2U(SCH_1):SMB_HOST_3V3AUX_SDA_R
    1  SMB_HOST_3V3AUX_SDA      A  @S9S_MB_2U_LIB.S9S_MB_2U(SCH_1):SMB_HOST_3V3AUX_SDA

Q_RES  I38  R579   [Q_RES_0402LF-33,5%,1/16W,CHIP,A]
    2  SMB_HOST_BMC_3V3AUX_SCL      B  @S9S_MB_2U_LIB.S9S_MB_2U(SCH_1):SMB_HOST_BMC_3V3AUX_SCL
    1  SMB_HOST_3V3AUX_SCL      A  @S9S_MB_2U_LIB.S9S_MB_2U(SCH_1):SMB_HOST_3V3AUX_SCL

Q_RES  I39  R580   [Q_RES_0402LF-33,5%,1/16W,CHIP,A]
    2  SMB_HOST_BMC_3V3AUX_SDA      B  @S9S_MB_2U_LIB.S9S_MB_2U(SCH_1):SMB_HOST_BMC_3V3AUX_SDA
    1  SMB_HOST_3V3AUX_SDA      A  @S9S_MB_2U_LIB.S9S_MB_2U(SCH_1):SMB_HOST_3V3AUX_SDA

Q_RES  I44  R581   [Q_RES_0402LF-33,5%,1/16W,CHIP,A]
    1  SMB_SML0_3V3AUX_SCL      A  @S9S_MB_2U_LIB.S9S_MB_2U(SCH_1):SMB_SML0_3V3AUX_SCL
    2  SMB_SML0_3V3AUX_PCH_SCL      B  @S9S_MB_2U_LIB.S9S_MB_2U(SCH_1):SMB_SML0_3V3AUX_PCH_SCL

Q_RES  I45  R582   [Q_RES_0402LF-33,5%,1/16W,CHIP,A]
    1  SMB_SML0_3V3AUX_SDA      A  @S9S_MB_2U_LIB.S9S_MB_2U(SCH_1):SMB_SML0_3V3AUX_SDA
    2  SMB_SML0_3V3AUX_PCH_SDA      B  @S9S_MB_2U_LIB.S9S_MB_2U(SCH_1):SMB_SML0_3V3AUX_PCH_SDA

Q_RES  I109  R585   [Q_RES_0402LF-33,5%,1/16W,CHIP,A]
    2  SMB_SML1_PMBUS_3V3AUX_PLD_SCL      B  @S9S_MB_2U_LIB.S9S_MB_2U(SCH_1):SMB_SML1_PMBUS_3V3AUX_PLD_SCL
    1  SMB_SML1_PMBUS_3V3AUX_PCH_SCL      A  @S9S_MB_2U_LIB.S9S_MB_2U(SCH_1):SMB_SML1_PMBUS_3V3AUX_PCH_SCL

Q_RES  I106  R586   [Q_RES_0402LF-33,5%,1/16W,CHIP,A]
    2  SMB_SML1_PMBUS_3V3AUX_PLD_SDA      B  @S9S_MB_2U_LIB.S9S_MB_2U(SCH_1):SMB_SML1_PMBUS_3V3AUX_PLD_SDA
    1  SMB_SML1_PMBUS_3V3AUX_PCH_SDA      A  @S9S_MB_2U_LIB.S9S_MB_2U(SCH_1):SMB_SML1_PMBUS_3V3AUX_PCH_SDA

Q_RES  I6   R587   [Q_RES_0402LF-1K,1%,1/16W,CHIP,A]
    1  PCA9546_PCIE0_ADDR0      A  @S9S_MB_2U_LIB.S9S_MB_2U(SCH_1):PCA9546_PCIE0_ADDR0
    2  GND                B  @S9S_MB_2U_LIB.S9S_MB_2U(SCH_1):GND

Q_RES  I154  R588   [Q_RES_0402LF-33.2,1%,1/16W,CHIA]
    1  SMB_PCIE0_3V3AUX_SDA_R      A  @S9S_MB_2U_LIB.S9S_MB_2U(SCH_1):SMB_PCIE0_3V3AUX_SDA_R
    2  SMB_PCIE0_3V3AUX_SDA      B  @S9S_MB_2U_LIB.S9S_MB_2U(SCH_1):SMB_PCIE0_3V3AUX_SDA

Q_RES  I153  R589   [Q_RES_0402LF-33.2,1%,1/16W,CHIA]
    1  SMB_PCIE0_3V3AUX_SCL_R      A  @S9S_MB_2U_LIB.S9S_MB_2U(SCH_1):SMB_PCIE0_3V3AUX_SCL_R
    2  SMB_PCIE0_3V3AUX_SCL      B  @S9S_MB_2U_LIB.S9S_MB_2U(SCH_1):SMB_PCIE0_3V3AUX_SCL

Q_RES  I173  R592   [Q_RES_0402LF-2.2K ,5%,1/16W,CHA]
    1  SMB_FAN_3V3AUX_SCL      A  @S9S_MB_2U_LIB.S9S_MB_2U(SCH_1):SMB_FAN_3V3AUX_SCL
    2  P3V3_AUX           B  @S9S_MB_2U_LIB.S9S_MB_2U(SCH_1):P3V3_AUX

Q_RES  I58  R593   [Q_RES_0402LF-0,5%,1/16W,CHIP,CA]
    2  I3C_SPD_DDRABCD_CPU0_BMC_SCL      B  @S9S_MB_2U_LIB.S9S_MB_2U(SCH_1):I3C_SPD_DDRABCD_CPU0_BMC_SCL
    1  I3C_SPD_DDRABCD_CPU0_BMC_R_SCL      A  @S9S_MB_2U_LIB.S9S_MB_2U(SCH_1):I3C_SPD_DDRABCD_CPU0_BMC_R_SCL

Q_RES  I59  R594   [Q_RES_0402LF-0,5%,1/16W,CHIP,CA]
    2  I3C_SPD_DDRABCD_CPU0_BMC_SDA      B  @S9S_MB_2U_LIB.S9S_MB_2U(SCH_1):I3C_SPD_DDRABCD_CPU0_BMC_SDA
    1  I3C_SPD_DDRABCD_CPU0_BMC_R_SDA      A  @S9S_MB_2U_LIB.S9S_MB_2U(SCH_1):I3C_SPD_DDRABCD_CPU0_BMC_R_SDA

Q_RES  I60  R595   [Q_RES_0402LF-0,5%,1/16W,CHIP,CA]
    2  I3C_SPD_DDREFGH_CPU0_BMC_SCL      B  @S9S_MB_2U_LIB.S9S_MB_2U(SCH_1):I3C_SPD_DDREFGH_CPU0_BMC_SCL
    1  I3C_SPD_DDREFGH_CPU0_BMC_R_SCL      A  @S9S_MB_2U_LIB.S9S_MB_2U(SCH_1):I3C_SPD_DDREFGH_CPU0_BMC_R_SCL

Q_RES  I61  R596   [Q_RES_0402LF-0,5%,1/16W,CHIP,CA]
    2  I3C_SPD_DDREFGH_CPU0_BMC_SDA      B  @S9S_MB_2U_LIB.S9S_MB_2U(SCH_1):I3C_SPD_DDREFGH_CPU0_BMC_SDA
    1  I3C_SPD_DDREFGH_CPU0_BMC_R_SDA      A  @S9S_MB_2U_LIB.S9S_MB_2U(SCH_1):I3C_SPD_DDREFGH_CPU0_BMC_R_SDA

Q_RES  I62  R597   [Q_RES_0402LF-0,5%,1/16W,CHIP,CA]
    2  I3C_SPD_DDRABCD_CPU1_BMC_SCL      B  @S9S_MB_2U_LIB.S9S_MB_2U(SCH_1):I3C_SPD_DDRABCD_CPU1_BMC_SCL
    1  I3C_SPD_DDRABCD_CPU1_BMC_R_SCL      A  @S9S_MB_2U_LIB.S9S_MB_2U(SCH_1):I3C_SPD_DDRABCD_CPU1_BMC_R_SCL

Q_RES  I63  R598   [Q_RES_0402LF-0,5%,1/16W,CHIP,CA]
    2  I3C_SPD_DDRABCD_CPU1_BMC_SDA      B  @S9S_MB_2U_LIB.S9S_MB_2U(SCH_1):I3C_SPD_DDRABCD_CPU1_BMC_SDA
    1  I3C_SPD_DDRABCD_CPU1_BMC_R_SDA      A  @S9S_MB_2U_LIB.S9S_MB_2U(SCH_1):I3C_SPD_DDRABCD_CPU1_BMC_R_SDA

Q_RES  I64  R599   [Q_RES_0402LF-0,5%,1/16W,CHIP,CA]
    2  I3C_SPD_DDREFGH_CPU1_BMC_SCL      B  @S9S_MB_2U_LIB.S9S_MB_2U(SCH_1):I3C_SPD_DDREFGH_CPU1_BMC_SCL
    1  I3C_SPD_DDREFGH_CPU1_BMC_R_SCL      A  @S9S_MB_2U_LIB.S9S_MB_2U(SCH_1):I3C_SPD_DDREFGH_CPU1_BMC_R_SCL

Q_RES  I65  R600   [Q_RES_0402LF-0,5%,1/16W,CHIP,CA]
    2  I3C_SPD_DDREFGH_CPU1_BMC_SDA      B  @S9S_MB_2U_LIB.S9S_MB_2U(SCH_1):I3C_SPD_DDREFGH_CPU1_BMC_SDA
    1  I3C_SPD_DDREFGH_CPU1_BMC_R_SDA      A  @S9S_MB_2U_LIB.S9S_MB_2U(SCH_1):I3C_SPD_DDREFGH_CPU1_BMC_R_SDA

Q_RES  I172  R601   [Q_RES_0402LF-2.2K ,5%,1/16W,CHA]
    1  SMB_FAN_3V3AUX_SDA      A  @S9S_MB_2U_LIB.S9S_MB_2U(SCH_1):SMB_FAN_3V3AUX_SDA
    2  P3V3_AUX           B  @S9S_MB_2U_LIB.S9S_MB_2U(SCH_1):P3V3_AUX

Q_RES  I175  R606   [Q_RES_0402LF-2.2K ,5%,1/16W,CHA]
    1  SMB_CPU_PIROM_3V3AUX_SCL      A  @S9S_MB_2U_LIB.S9S_MB_2U(SCH_1):SMB_CPU_PIROM_3V3AUX_SCL
    2  P3V3_AUX           B  @S9S_MB_2U_LIB.S9S_MB_2U(SCH_1):P3V3_AUX

Q_RES  I21  R607   [Q_RES_0402LF-1K,5%,1/16W,EMPTYA]
    1  P3V3_AUX           A  @S9S_MB_2U_LIB.S9S_MB_2U(SCH_1):P3V3_AUX
    2  FM_ESPI_FLASH_MODE      B  @S9S_MB_2U_LIB.S9S_MB_2U(SCH_1):FM_ESPI_FLASH_MODE

Q_RES  I36  R608   [Q_RES_0402LF-10K,1%,1/16W,CHIPA]
    2  GND                B  @S9S_MB_2U_LIB.S9S_MB_2U(SCH_1):GND
    1  FM_ESPI_FLASH_MODE      A  @S9S_MB_2U_LIB.S9S_MB_2U(SCH_1):FM_ESPI_FLASH_MODE

Q_RES  I39  R609   [Q_RES_0402LF-1K,5%,1/16W,EMPTYA]
    1  P3V3_AUX           A  @S9S_MB_2U_LIB.S9S_MB_2U(SCH_1):P3V3_AUX
    2  FM_ESPI_CS_SWIZZLE      B  @S9S_MB_2U_LIB.S9S_MB_2U(SCH_1):FM_ESPI_CS_SWIZZLE

Q_RES  I40  R610   [Q_RES_0402LF-10K,1%,1/16W,CHIPA]
    2  GND                B  @S9S_MB_2U_LIB.S9S_MB_2U(SCH_1):GND
    1  FM_ESPI_CS_SWIZZLE      A  @S9S_MB_2U_LIB.S9S_MB_2U(SCH_1):FM_ESPI_CS_SWIZZLE

Q_RES  I43  R611   [Q_RES_0402LF-1K,5%,1/16W,CHIP,A]
    1  P3V3_AUX           A  @S9S_MB_2U_LIB.S9S_MB_2U(SCH_1):P3V3_AUX
    2  FM_PCH_EXTERNALCLKMODE      B  @S9S_MB_2U_LIB.S9S_MB_2U(SCH_1):FM_PCH_EXTERNALCLKMODE

Q_RES  I44  R612   [Q_RES_0402LF-10K,1%,1/16W,EMPTA]
    2  GND                B  @S9S_MB_2U_LIB.S9S_MB_2U(SCH_1):GND
    1  FM_PCH_EXTERNALCLKMODE      A  @S9S_MB_2U_LIB.S9S_MB_2U(SCH_1):FM_PCH_EXTERNALCLKMODE

Q_RES  I18  R613   [Q_RES_0402LF-10K,1%,1/16W,CHIPA]
    1  P3V3_AUX           A  @S9S_MB_2U_LIB.S9S_MB_2U(SCH_1):P3V3_AUX
    2  FM_JTAG_ODT_DISABLE      B  @S9S_MB_2U_LIB.S9S_MB_2U(SCH_1):FM_JTAG_ODT_DISABLE

Q_RES  I23  R614   [Q_RES_0402LF-1K,5%,1/16W,EMPTYA]
    2  GND                B  @S9S_MB_2U_LIB.S9S_MB_2U(SCH_1):GND
    1  FM_JTAG_ODT_DISABLE      A  @S9S_MB_2U_LIB.S9S_MB_2U(SCH_1):FM_JTAG_ODT_DISABLE

Q_RES  I51  R615   [Q_RES_0402LF-1K,5%,1/16W,CHIP,A]
    1  P3V3_AUX           A  @S9S_MB_2U_LIB.S9S_MB_2U(SCH_1):P3V3_AUX
    2  FM_PCH_VISA_DEFAULT      B  @S9S_MB_2U_LIB.S9S_MB_2U(SCH_1):FM_PCH_VISA_DEFAULT

Q_RES  I54  R617   [Q_RES_0402LF-1K,5%,1/16W,EMPTYA]
    1  P3V3_AUX           A  @S9S_MB_2U_LIB.S9S_MB_2U(SCH_1):P3V3_AUX
    2  FM_PCH_IO_EXPANDER      B  @S9S_MB_2U_LIB.S9S_MB_2U(SCH_1):FM_PCH_IO_EXPANDER

Q_RES  I53  R618   [Q_RES_0402LF-10K,1%,1/16W,CHIPA]
    2  GND                B  @S9S_MB_2U_LIB.S9S_MB_2U(SCH_1):GND
    1  FM_PCH_IO_EXPANDER      A  @S9S_MB_2U_LIB.S9S_MB_2U(SCH_1):FM_PCH_IO_EXPANDER

Q_RES  I48  R619   [Q_RES_0402LF-10K,1%,1/16W,CHIPA]
    1  P3V3_AUX           A  @S9S_MB_2U_LIB.S9S_MB_2U(SCH_1):P3V3_AUX
    2  FM_LT_KEY_DOWNGRADE_N      B  @S9S_MB_2U_LIB.S9S_MB_2U(SCH_1):FM_LT_KEY_DOWNGRADE_N

Q_RES  I55  R621   [Q_RES_0402LF-1K,5%,1/16W,EMPTYA]
    1  P3V3_AUX           A  @S9S_MB_2U_LIB.S9S_MB_2U(SCH_1):P3V3_AUX
    2  FM_PCH_SKIP_RTC_CLOCK      B  @S9S_MB_2U_LIB.S9S_MB_2U(SCH_1):FM_PCH_SKIP_RTC_CLOCK

Q_RES  I56  R622   [Q_RES_0402LF-1K,5%,1/16W,CHIP,A]
    2  GND                B  @S9S_MB_2U_LIB.S9S_MB_2U(SCH_1):GND
    1  FM_PCH_SKIP_RTC_CLOCK      A  @S9S_MB_2U_LIB.S9S_MB_2U(SCH_1):FM_PCH_SKIP_RTC_CLOCK

Q_RES  I13  R623   [Q_RES_0402LF-1K,5%,1/16W,EMPTYA]
    1  P1V8_PCH_AUX       A  @S9S_MB_2U_LIB.S9S_MB_2U(SCH_1):P1V8_PCH_AUX
    2  FM_PCH_XTALSEL      B  @S9S_MB_2U_LIB.S9S_MB_2U(SCH_1):FM_PCH_XTALSEL

Q_RES  I14  R624   [Q_RES_0402LF-10K,1%,1/16W,CHIPA]
    2  GND                B  @S9S_MB_2U_LIB.S9S_MB_2U(SCH_1):GND
    1  FM_PCH_XTALSEL      A  @S9S_MB_2U_LIB.S9S_MB_2U(SCH_1):FM_PCH_XTALSEL

Q_RES  I24  R625   [Q_RES_0402LF-1K,1%,1/16W,EMPTYA]
    2  PD_PIROM_CPU1_ADDR2      B  @S9S_MB_2U_LIB.S9S_MB_2U(SCH_1):PD_PIROM_CPU1_ADDR2
    1  P3V3_AUX           A  @S9S_MB_2U_LIB.S9S_MB_2U(SCH_1):P3V3_AUX

Q_RES  I26  R626   [Q_RES_0402LF-10K,1%,1/16W,CHIPA]
    1  PD_PIROM_CPU1_ADDR2      A  @S9S_MB_2U_LIB.S9S_MB_2U(SCH_1):PD_PIROM_CPU1_ADDR2
    2  GND                B  @S9S_MB_2U_LIB.S9S_MB_2U(SCH_1):GND

Q_RES  I14  R627   [Q_RES_0402LF-1K,1%,1/16W,EMPTYA]
    2  PD_PIROM_CPU1_ADDR1      B  @S9S_MB_2U_LIB.S9S_MB_2U(SCH_1):PD_PIROM_CPU1_ADDR1
    1  P3V3_AUX           A  @S9S_MB_2U_LIB.S9S_MB_2U(SCH_1):P3V3_AUX

Q_RES  I17  R628   [Q_RES_0402LF-10K,1%,1/16W,CHIPA]
    1  PD_PIROM_CPU1_ADDR1      A  @S9S_MB_2U_LIB.S9S_MB_2U(SCH_1):PD_PIROM_CPU1_ADDR1
    2  GND                B  @S9S_MB_2U_LIB.S9S_MB_2U(SCH_1):GND

Q_RES  I13  R629   [Q_RES_0402LF-1K,1%,1/16W,CHIP,A]
    2  PU_PIROM_CPU1_ADDR0      B  @S9S_MB_2U_LIB.S9S_MB_2U(SCH_1):PU_PIROM_CPU1_ADDR0
    1  P3V3_AUX           A  @S9S_MB_2U_LIB.S9S_MB_2U(SCH_1):P3V3_AUX

Q_RES  I15  R630   [Q_RES_0402LF-10K,1%,1/16W,EMPTA]
    1  PU_PIROM_CPU1_ADDR0      A  @S9S_MB_2U_LIB.S9S_MB_2U(SCH_1):PU_PIROM_CPU1_ADDR0
    2  GND                B  @S9S_MB_2U_LIB.S9S_MB_2U(SCH_1):GND

Q_RES  I226  R631   [Q_RES_0402LF-0,5%,1/16W,EMPTY,A]
    2  IRQ_BMC_PCH_NMI_R1      B  @S9S_MB_2U_LIB.S9S_MB_2U(SCH_1):IRQ_BMC_PCH_NMI_R1
    1  IRQ_BMC_PCH_NMI_R      A  @S9S_MB_2U_LIB.S9S_MB_2U(SCH_1):IRQ_BMC_PCH_NMI_R

Q_RES  I214  R632   [Q_RES_0402LF-0,5%,1/16W,EMPTY,A]
    2  SMB_HOST_BMC_3V3AUX_SDA      B  @S9S_MB_2U_LIB.S9S_MB_2U(SCH_1):SMB_HOST_BMC_3V3AUX_SDA
    1  NC                 A  NC

Q_RES  I215  R633   [Q_RES_0402LF-0,5%,1/16W,EMPTY,A]
    2  SMB_HOST_BMC_3V3AUX_SCL      B  @S9S_MB_2U_LIB.S9S_MB_2U(SCH_1):SMB_HOST_BMC_3V3AUX_SCL
    1  NC                 A  NC

Q_RES  I234  R635   [Q_RES_0402LF-10K,1%,1/16W,CHIPA]
    1  PU_OC3_USB_N       A  @S9S_MB_2U_LIB.S9S_MB_2U(SCH_1):PU_OC3_USB_N
    2  P3V3_AUX           B  @S9S_MB_2U_LIB.S9S_MB_2U(SCH_1):P3V3_AUX

Q_RES  I164  R640   [Q_RES_0402LF-4.7K,5%,1/16W,EMPA]
    2  P3V3_AUX           B  @S9S_MB_2U_LIB.S9S_MB_2U(SCH_1):P3V3_AUX
    1  JTAG_RISER2_TDI      A  @S9S_MB_2U_LIB.S9S_MB_2U(SCH_1):JTAG_RISER2_TDI

Q_RES  I54  R641   [Q_RES_0402LF-10K,1%,1/16W,EMPTA]
    2  PCA9546_PCIE1_ADDR2      B  @S9S_MB_2U_LIB.S9S_MB_2U(SCH_1):PCA9546_PCIE1_ADDR2
    1  P3V3_AUX           A  @S9S_MB_2U_LIB.S9S_MB_2U(SCH_1):P3V3_AUX

Q_RES  I53  R642   [Q_RES_0402LF-1K,1%,1/16W,CHIP,A]
    1  PCA9546_PCIE1_ADDR2      A  @S9S_MB_2U_LIB.S9S_MB_2U(SCH_1):PCA9546_PCIE1_ADDR2
    2  GND                B  @S9S_MB_2U_LIB.S9S_MB_2U(SCH_1):GND

Q_RES  I58  R643   [Q_RES_0402LF-10K,1%,1/16W,EMPTA]
    2  PCA9546_PCIE1_ADDR1      B  @S9S_MB_2U_LIB.S9S_MB_2U(SCH_1):PCA9546_PCIE1_ADDR1
    1  P3V3_AUX           A  @S9S_MB_2U_LIB.S9S_MB_2U(SCH_1):P3V3_AUX

Q_RES  I55  R644   [Q_RES_0402LF-1K,1%,1/16W,CHIP,A]
    1  PCA9546_PCIE1_ADDR1      A  @S9S_MB_2U_LIB.S9S_MB_2U(SCH_1):PCA9546_PCIE1_ADDR1
    2  GND                B  @S9S_MB_2U_LIB.S9S_MB_2U(SCH_1):GND

Q_RES  I57  R645   [Q_RES_0402LF-10K,1%,1/16W,CHIPA]
    2  PCA9546_PCIE1_ADDR0      B  @S9S_MB_2U_LIB.S9S_MB_2U(SCH_1):PCA9546_PCIE1_ADDR0
    1  P3V3_AUX           A  @S9S_MB_2U_LIB.S9S_MB_2U(SCH_1):P3V3_AUX

Q_RES  I56  R646   [Q_RES_0402LF-1K,1%,1/16W,EMPTYA]
    1  PCA9546_PCIE1_ADDR0      A  @S9S_MB_2U_LIB.S9S_MB_2U(SCH_1):PCA9546_PCIE1_ADDR0
    2  GND                B  @S9S_MB_2U_LIB.S9S_MB_2U(SCH_1):GND

Q_RES  I185  R647   [Q_RES_0402LF-33.2,1%,1/16W,CHIA]
    1  SMB_PCIE1_3V3AUX_SDA_R      A  @S9S_MB_2U_LIB.S9S_MB_2U(SCH_1):SMB_PCIE1_3V3AUX_SDA_R
    2  SMB_PCIE1_3V3AUX_SDA      B  @S9S_MB_2U_LIB.S9S_MB_2U(SCH_1):SMB_PCIE1_3V3AUX_SDA

Q_RES  I184  R648   [Q_RES_0402LF-0,5%,1/16W,CHIP,CA]
    1  SMB_PCIE1_3V3AUX_SCL_R      A  @S9S_MB_2U_LIB.S9S_MB_2U(SCH_1):SMB_PCIE1_3V3AUX_SCL_R
    2  SMB_PCIE1_3V3AUX_SCL      B  @S9S_MB_2U_LIB.S9S_MB_2U(SCH_1):SMB_PCIE1_3V3AUX_SCL

Q_RES  I174  R649   [Q_RES_0402LF-2.2K ,5%,1/16W,CHA]
    1  SMB_CPU_PIROM_3V3AUX_SDA      A  @S9S_MB_2U_LIB.S9S_MB_2U(SCH_1):SMB_CPU_PIROM_3V3AUX_SDA
    2  P3V3_AUX           B  @S9S_MB_2U_LIB.S9S_MB_2U(SCH_1):P3V3_AUX

Q_RES  I32  R650   [Q_RES_0402LF-1K,1%,1/16W,CHIP,A]
    2  PU_PIROM_CPU0_SM_WP      B  @S9S_MB_2U_LIB.S9S_MB_2U(SCH_1):PU_PIROM_CPU0_SM_WP
    1  P3V3_AUX           A  @S9S_MB_2U_LIB.S9S_MB_2U(SCH_1):P3V3_AUX

Q_RES  I170  R651   [Q_RES_0402LF-2.2K ,5%,1/16W,CHA]
    2  SMB_RISER2_0_3V3AUX_SCL      B  @S9S_MB_2U_LIB.S9S_MB_2U(SCH_1):SMB_RISER2_0_3V3AUX_SCL
    1  P3V3_AUX           A  @S9S_MB_2U_LIB.S9S_MB_2U(SCH_1):P3V3_AUX

Q_RES  I169  R652   [Q_RES_0402LF-2.2K ,5%,1/16W,CHA]
    2  SMB_RISER2_0_3V3AUX_SDA      B  @S9S_MB_2U_LIB.S9S_MB_2U(SCH_1):SMB_RISER2_0_3V3AUX_SDA
    1  P3V3_AUX           A  @S9S_MB_2U_LIB.S9S_MB_2U(SCH_1):P3V3_AUX

Q_RES  I163  R653   [Q_RES_0402LF-2.2K ,5%,1/16W,CHA]
    2  SMB_RISER2_1_3V3AUX_SCL      B  @S9S_MB_2U_LIB.S9S_MB_2U(SCH_1):SMB_RISER2_1_3V3AUX_SCL
    1  P3V3_AUX           A  @S9S_MB_2U_LIB.S9S_MB_2U(SCH_1):P3V3_AUX

Q_RES  I164  R654   [Q_RES_0402LF-2.2K ,5%,1/16W,CHA]
    2  SMB_RISER2_1_3V3AUX_SDA      B  @S9S_MB_2U_LIB.S9S_MB_2U(SCH_1):SMB_RISER2_1_3V3AUX_SDA
    1  P3V3_AUX           A  @S9S_MB_2U_LIB.S9S_MB_2U(SCH_1):P3V3_AUX

Q_RES  I129  R655   [Q_RES_0402LF-2.2K ,5%,1/16W,CHA]
    1  UNNAMED_222_QRES_I129_A      A  @S9S_MB_2U_LIB.S9S_MB_2U(SCH_1):UNNAMED_222_QRES_I129_A
    2  SMB_RISER3_3V3AUX_SCL      B  @S9S_MB_2U_LIB.S9S_MB_2U(SCH_1):SMB_RISER3_3V3AUX_SCL

Q_RES  I130  R656   [Q_RES_0402LF-2.2K ,5%,1/16W,CHA]
    1  UNNAMED_222_QRES_I129_A      A  @S9S_MB_2U_LIB.S9S_MB_2U(SCH_1):UNNAMED_222_QRES_I129_A
    2  SMB_RISER3_3V3AUX_SDA      B  @S9S_MB_2U_LIB.S9S_MB_2U(SCH_1):SMB_RISER3_3V3AUX_SDA

Q_RES  I131  R657   [Q_RES_0402LF-2.2K ,5%,1/16W,EMA]
    1  UNNAMED_222_QRES_I129_A      A  @S9S_MB_2U_LIB.S9S_MB_2U(SCH_1):UNNAMED_222_QRES_I129_A
    2  SMB_OCP_SFF_3V3AUX_SCL      B  @S9S_MB_2U_LIB.S9S_MB_2U(SCH_1):SMB_OCP_SFF_3V3AUX_SCL

Q_RES  I132  R658   [Q_RES_0402LF-2.2K ,5%,1/16W,EMA]
    1  UNNAMED_222_QRES_I129_A      A  @S9S_MB_2U_LIB.S9S_MB_2U(SCH_1):UNNAMED_222_QRES_I129_A
    2  SMB_OCP_SFF_3V3AUX_SDA      B  @S9S_MB_2U_LIB.S9S_MB_2U(SCH_1):SMB_OCP_SFF_3V3AUX_SDA

Q_RES  I175  R659   [Q_RES_0402LF-0,5%,1/16W,CHIP,CA]
    1  SMB_RISER2_0_3V3AUX_SDA      A  @S9S_MB_2U_LIB.S9S_MB_2U(SCH_1):SMB_RISER2_0_3V3AUX_SDA
    2  SMB_PCIE0_3V3AUX_SDA_R1      B  @S9S_MB_2U_LIB.S9S_MB_2U(SCH_1):SMB_PCIE0_3V3AUX_SDA_R1

Q_RES  I176  R660   [Q_RES_0402LF-0,5%,1/16W,CHIP,CA]
    1  SMB_RISER2_0_3V3AUX_SCL      A  @S9S_MB_2U_LIB.S9S_MB_2U(SCH_1):SMB_RISER2_0_3V3AUX_SCL
    2  SMB_PCIE0_3V3AUX_SCL_R1      B  @S9S_MB_2U_LIB.S9S_MB_2U(SCH_1):SMB_PCIE0_3V3AUX_SCL_R1

Q_RES  I11  R661   [Q_RES_0402LF-1K,1%,1/16W,CHIP,A]
    1  PD_I3C_SPD_DDR_CPU1_OE_N      A  @S9S_MB_2U_LIB.S9S_MB_2U(SCH_1):PD_I3C_SPD_DDR_CPU1_OE_N
    2  GND                B  @S9S_MB_2U_LIB.S9S_MB_2U(SCH_1):GND

Q_RES  I49  R662   [Q_RES_0402LF-249,1%,1/16W,CHIPA]
    1  PVNN_TERM_CPU1      A  @S9S_MB_2U_LIB.S9S_MB_2U(SCH_1):PVNN_TERM_CPU1
    2  I3C_SPD_DDRABCD_CPU1_SCL      B  @S9S_MB_2U_LIB.S9S_MB_2U(SCH_1):I3C_SPD_DDRABCD_CPU1_SCL

Q_RES  I48  R663   [Q_RES_0402LF-249,1%,1/16W,CHIPA]
    1  PVNN_TERM_CPU1      A  @S9S_MB_2U_LIB.S9S_MB_2U(SCH_1):PVNN_TERM_CPU1
    2  I3C_SPD_DDRABCD_CPU1_SDA      B  @S9S_MB_2U_LIB.S9S_MB_2U(SCH_1):I3C_SPD_DDRABCD_CPU1_SDA

Q_RES  I47  R664   [Q_RES_0402LF-249,1%,1/16W,CHIPA]
    1  PVNN_TERM_CPU1      A  @S9S_MB_2U_LIB.S9S_MB_2U(SCH_1):PVNN_TERM_CPU1
    2  I3C_SPD_DDREFGH_CPU1_SCL      B  @S9S_MB_2U_LIB.S9S_MB_2U(SCH_1):I3C_SPD_DDREFGH_CPU1_SCL

Q_RES  I18  R665   [Q_RES_0402LF-0,5%,1/16W,EMPTY,A]
    1  I3C_SPD_DDRABCD_CPU1_R_SCL      A  @S9S_MB_2U_LIB.S9S_MB_2U(SCH_1):I3C_SPD_DDRABCD_CPU1_R_SCL
    2  I3C_SPD_DDRABCD_CPU1_LVC1_R_SCL      B  @S9S_MB_2U_LIB.S9S_MB_2U(SCH_1):I3C_SPD_DDRABCD_CPU1_LVC1_R_SCL

Q_RES  I16  R666   [Q_RES_0402LF-0,5%,1/16W,EMPTY,A]
    1  I3C_SPD_DDRABCD_CPU1_R_SDA      A  @S9S_MB_2U_LIB.S9S_MB_2U(SCH_1):I3C_SPD_DDRABCD_CPU1_R_SDA
    2  I3C_SPD_DDRABCD_CPU1_LVC1_R_SDA      B  @S9S_MB_2U_LIB.S9S_MB_2U(SCH_1):I3C_SPD_DDRABCD_CPU1_LVC1_R_SDA

Q_RES  I15  R667   [Q_RES_0402LF-0,5%,1/16W,EMPTY,A]
    1  I3C_SPD_DDREFGH_CPU1_R_SCL      A  @S9S_MB_2U_LIB.S9S_MB_2U(SCH_1):I3C_SPD_DDREFGH_CPU1_R_SCL
    2  I3C_SPD_DDREFGH_CPU1_LVC1_R_SCL      B  @S9S_MB_2U_LIB.S9S_MB_2U(SCH_1):I3C_SPD_DDREFGH_CPU1_LVC1_R_SCL

Q_RES  I14  R668   [Q_RES_0402LF-0,5%,1/16W,EMPTY,A]
    1  I3C_SPD_DDREFGH_CPU1_R_SDA      A  @S9S_MB_2U_LIB.S9S_MB_2U(SCH_1):I3C_SPD_DDREFGH_CPU1_R_SDA
    2  I3C_SPD_DDREFGH_CPU1_LVC1_R_SDA      B  @S9S_MB_2U_LIB.S9S_MB_2U(SCH_1):I3C_SPD_DDREFGH_CPU1_LVC1_R_SDA

Q_RES  I46  R669   [Q_RES_0402LF-249,1%,1/16W,CHIPA]
    1  PVNN_TERM_CPU1      A  @S9S_MB_2U_LIB.S9S_MB_2U(SCH_1):PVNN_TERM_CPU1
    2  I3C_SPD_DDREFGH_CPU1_SDA      B  @S9S_MB_2U_LIB.S9S_MB_2U(SCH_1):I3C_SPD_DDREFGH_CPU1_SDA

Q_RES  I27  R670   [Q_RES_0402LF-33.2,1%,1/16W,CHIA]
    1  I3C_SPD_DDRABCD_CPU1_SCL      A  @S9S_MB_2U_LIB.S9S_MB_2U(SCH_1):I3C_SPD_DDRABCD_CPU1_SCL
    2  I3C_SPD_DDRABCD_CPU1_R_SCL      B  @S9S_MB_2U_LIB.S9S_MB_2U(SCH_1):I3C_SPD_DDRABCD_CPU1_R_SCL

Q_RES  I28  R671   [Q_RES_0402LF-33.2,1%,1/16W,CHIA]
    1  I3C_SPD_DDRABCD_CPU1_SDA      A  @S9S_MB_2U_LIB.S9S_MB_2U(SCH_1):I3C_SPD_DDRABCD_CPU1_SDA
    2  I3C_SPD_DDRABCD_CPU1_R_SDA      B  @S9S_MB_2U_LIB.S9S_MB_2U(SCH_1):I3C_SPD_DDRABCD_CPU1_R_SDA

Q_RES  I21  R672   [Q_RES_0402LF-33.2,1%,1/16W,CHIA]
    1  I3C_SPD_DDREFGH_CPU1_SCL      A  @S9S_MB_2U_LIB.S9S_MB_2U(SCH_1):I3C_SPD_DDREFGH_CPU1_SCL
    2  I3C_SPD_DDREFGH_CPU1_R_SCL      B  @S9S_MB_2U_LIB.S9S_MB_2U(SCH_1):I3C_SPD_DDREFGH_CPU1_R_SCL

Q_RES  I22  R673   [Q_RES_0402LF-33.2,1%,1/16W,CHIA]
    1  I3C_SPD_DDREFGH_CPU1_SDA      A  @S9S_MB_2U_LIB.S9S_MB_2U(SCH_1):I3C_SPD_DDREFGH_CPU1_SDA
    2  I3C_SPD_DDREFGH_CPU1_R_SDA      B  @S9S_MB_2U_LIB.S9S_MB_2U(SCH_1):I3C_SPD_DDREFGH_CPU1_R_SDA

Q_RES  I31  R674   [Q_RES_0402LF-0,5%,1/16W,CHIP,CA]
    2  I3C_SPD_DDRABCD_CPU1_LVC1_SCL      B  @S9S_MB_2U_LIB.S9S_MB_2U(SCH_1):I3C_SPD_DDRABCD_CPU1_LVC1_SCL
    1  I3C_SPD_DDRABCD_CPU1_LVC1_R_SCL      A  @S9S_MB_2U_LIB.S9S_MB_2U(SCH_1):I3C_SPD_DDRABCD_CPU1_LVC1_R_SCL

Q_RES  I33  R675   [Q_RES_0402LF-0,5%,1/16W,CHIP,CA]
    2  I3C_SPD_DDRABCD_CPU1_LVC1_SDA      B  @S9S_MB_2U_LIB.S9S_MB_2U(SCH_1):I3C_SPD_DDRABCD_CPU1_LVC1_SDA
    1  I3C_SPD_DDRABCD_CPU1_LVC1_R_SDA      A  @S9S_MB_2U_LIB.S9S_MB_2U(SCH_1):I3C_SPD_DDRABCD_CPU1_LVC1_R_SDA

Q_RES  I32  R676   [Q_RES_0402LF-0,5%,1/16W,CHIP,CA]
    2  I3C_SPD_DDREFGH_CPU1_LVC1_SCL      B  @S9S_MB_2U_LIB.S9S_MB_2U(SCH_1):I3C_SPD_DDREFGH_CPU1_LVC1_SCL
    1  I3C_SPD_DDREFGH_CPU1_LVC1_R_SCL      A  @S9S_MB_2U_LIB.S9S_MB_2U(SCH_1):I3C_SPD_DDREFGH_CPU1_LVC1_R_SCL

Q_RES  I30  R677   [Q_RES_0402LF-0,5%,1/16W,CHIP,CA]
    2  I3C_SPD_DDREFGH_CPU1_LVC1_SDA      B  @S9S_MB_2U_LIB.S9S_MB_2U(SCH_1):I3C_SPD_DDREFGH_CPU1_LVC1_SDA
    1  I3C_SPD_DDREFGH_CPU1_LVC1_R_SDA      A  @S9S_MB_2U_LIB.S9S_MB_2U(SCH_1):I3C_SPD_DDREFGH_CPU1_LVC1_R_SDA

Q_RES  I63  R678   [Q_RES_0402LF-1K,1%,1/16W,CHIP,A]
    1  PD_I3C_SPD_DDR_CPU0_OE_N      A  @S9S_MB_2U_LIB.S9S_MB_2U(SCH_1):PD_I3C_SPD_DDR_CPU0_OE_N
    2  GND                B  @S9S_MB_2U_LIB.S9S_MB_2U(SCH_1):GND

Q_RES  I85  R679   [Q_RES_0402LF-249,1%,1/16W,CHIPA]
    1  PVNN_TERM_CPU0      A  @S9S_MB_2U_LIB.S9S_MB_2U(SCH_1):PVNN_TERM_CPU0
    2  I3C_SPD_DDRABCD_CPU0_SCL      B  @S9S_MB_2U_LIB.S9S_MB_2U(SCH_1):I3C_SPD_DDRABCD_CPU0_SCL

Q_RES  I89  R680   [Q_RES_0402LF-249,1%,1/16W,CHIPA]
    1  PVNN_TERM_CPU0      A  @S9S_MB_2U_LIB.S9S_MB_2U(SCH_1):PVNN_TERM_CPU0
    2  I3C_SPD_DDRABCD_CPU0_SDA      B  @S9S_MB_2U_LIB.S9S_MB_2U(SCH_1):I3C_SPD_DDRABCD_CPU0_SDA

Q_RES  I87  R681   [Q_RES_0402LF-249,1%,1/16W,CHIPA]
    1  PVNN_TERM_CPU0      A  @S9S_MB_2U_LIB.S9S_MB_2U(SCH_1):PVNN_TERM_CPU0
    2  I3C_SPD_DDREFGH_CPU0_SCL      B  @S9S_MB_2U_LIB.S9S_MB_2U(SCH_1):I3C_SPD_DDREFGH_CPU0_SCL

Q_RES  I65  R682   [Q_RES_0402LF-0,5%,1/16W,EMPTY,A]
    1  I3C_SPD_DDRABCD_CPU0_R_SCL      A  @S9S_MB_2U_LIB.S9S_MB_2U(SCH_1):I3C_SPD_DDRABCD_CPU0_R_SCL
    2  I3C_SPD_DDRABCD_CPU0_LVC1_R_SCL      B  @S9S_MB_2U_LIB.S9S_MB_2U(SCH_1):I3C_SPD_DDRABCD_CPU0_LVC1_R_SCL

Q_RES  I66  R683   [Q_RES_0402LF-0,5%,1/16W,EMPTY,A]
    1  I3C_SPD_DDRABCD_CPU0_R_SDA      A  @S9S_MB_2U_LIB.S9S_MB_2U(SCH_1):I3C_SPD_DDRABCD_CPU0_R_SDA
    2  I3C_SPD_DDRABCD_CPU0_LVC1_R_SDA      B  @S9S_MB_2U_LIB.S9S_MB_2U(SCH_1):I3C_SPD_DDRABCD_CPU0_LVC1_R_SDA

Q_RES  I67  R684   [Q_RES_0402LF-0,5%,1/16W,EMPTY,A]
    1  I3C_SPD_DDREFGH_CPU0_R_SCL      A  @S9S_MB_2U_LIB.S9S_MB_2U(SCH_1):I3C_SPD_DDREFGH_CPU0_R_SCL
    2  I3C_SPD_DDREFGH_CPU0_LVC1_R_SCL      B  @S9S_MB_2U_LIB.S9S_MB_2U(SCH_1):I3C_SPD_DDREFGH_CPU0_LVC1_R_SCL

Q_RES  I68  R685   [Q_RES_0402LF-0,5%,1/16W,EMPTY,A]
    1  I3C_SPD_DDREFGH_CPU0_R_SDA      A  @S9S_MB_2U_LIB.S9S_MB_2U(SCH_1):I3C_SPD_DDREFGH_CPU0_R_SDA
    2  I3C_SPD_DDREFGH_CPU0_LVC1_R_SDA      B  @S9S_MB_2U_LIB.S9S_MB_2U(SCH_1):I3C_SPD_DDREFGH_CPU0_LVC1_R_SDA

Q_RES  I86  R686   [Q_RES_0402LF-249,1%,1/16W,CHIPA]
    1  PVNN_TERM_CPU0      A  @S9S_MB_2U_LIB.S9S_MB_2U(SCH_1):PVNN_TERM_CPU0
    2  I3C_SPD_DDREFGH_CPU0_SDA      B  @S9S_MB_2U_LIB.S9S_MB_2U(SCH_1):I3C_SPD_DDREFGH_CPU0_SDA

Q_RES  I27  R687   [Q_RES_0402LF-33.2,1%,1/16W,CHIA]
    1  I3C_SPD_DDRABCD_CPU0_SCL      A  @S9S_MB_2U_LIB.S9S_MB_2U(SCH_1):I3C_SPD_DDRABCD_CPU0_SCL
    2  I3C_SPD_DDRABCD_CPU0_R_SCL      B  @S9S_MB_2U_LIB.S9S_MB_2U(SCH_1):I3C_SPD_DDRABCD_CPU0_R_SCL

Q_RES  I28  R688   [Q_RES_0402LF-33.2,1%,1/16W,CHIA]
    1  I3C_SPD_DDRABCD_CPU0_SDA      A  @S9S_MB_2U_LIB.S9S_MB_2U(SCH_1):I3C_SPD_DDRABCD_CPU0_SDA
    2  I3C_SPD_DDRABCD_CPU0_R_SDA      B  @S9S_MB_2U_LIB.S9S_MB_2U(SCH_1):I3C_SPD_DDRABCD_CPU0_R_SDA

Q_RES  I30  R689   [Q_RES_0402LF-33.2,1%,1/16W,CHIA]
    1  I3C_SPD_DDREFGH_CPU0_SCL      A  @S9S_MB_2U_LIB.S9S_MB_2U(SCH_1):I3C_SPD_DDREFGH_CPU0_SCL
    2  I3C_SPD_DDREFGH_CPU0_R_SCL      B  @S9S_MB_2U_LIB.S9S_MB_2U(SCH_1):I3C_SPD_DDREFGH_CPU0_R_SCL

Q_RES  I29  R690   [Q_RES_0402LF-33.2,1%,1/16W,CHIA]
    1  I3C_SPD_DDREFGH_CPU0_SDA      A  @S9S_MB_2U_LIB.S9S_MB_2U(SCH_1):I3C_SPD_DDREFGH_CPU0_SDA
    2  I3C_SPD_DDREFGH_CPU0_R_SDA      B  @S9S_MB_2U_LIB.S9S_MB_2U(SCH_1):I3C_SPD_DDREFGH_CPU0_R_SDA

Q_RES  I74  R691   [Q_RES_0402LF-0,5%,1/16W,CHIP,CA]
    2  I3C_SPD_DDRABCD_CPU0_LVC1_SCL      B  @S9S_MB_2U_LIB.S9S_MB_2U(SCH_1):I3C_SPD_DDRABCD_CPU0_LVC1_SCL
    1  I3C_SPD_DDRABCD_CPU0_LVC1_R_SCL      A  @S9S_MB_2U_LIB.S9S_MB_2U(SCH_1):I3C_SPD_DDRABCD_CPU0_LVC1_R_SCL

Q_RES  I73  R692   [Q_RES_0402LF-0,5%,1/16W,CHIP,CA]
    2  I3C_SPD_DDRABCD_CPU0_LVC1_SDA      B  @S9S_MB_2U_LIB.S9S_MB_2U(SCH_1):I3C_SPD_DDRABCD_CPU0_LVC1_SDA
    1  I3C_SPD_DDRABCD_CPU0_LVC1_R_SDA      A  @S9S_MB_2U_LIB.S9S_MB_2U(SCH_1):I3C_SPD_DDRABCD_CPU0_LVC1_R_SDA

Q_RES  I75  R693   [Q_RES_0402LF-0,5%,1/16W,CHIP,CA]
    2  I3C_SPD_DDREFGH_CPU0_LVC1_SCL      B  @S9S_MB_2U_LIB.S9S_MB_2U(SCH_1):I3C_SPD_DDREFGH_CPU0_LVC1_SCL
    1  I3C_SPD_DDREFGH_CPU0_LVC1_R_SCL      A  @S9S_MB_2U_LIB.S9S_MB_2U(SCH_1):I3C_SPD_DDREFGH_CPU0_LVC1_R_SCL

Q_RES  I76  R694   [Q_RES_0402LF-0,5%,1/16W,CHIP,CA]
    2  I3C_SPD_DDREFGH_CPU0_LVC1_SDA      B  @S9S_MB_2U_LIB.S9S_MB_2U(SCH_1):I3C_SPD_DDREFGH_CPU0_LVC1_SDA
    1  I3C_SPD_DDREFGH_CPU0_LVC1_R_SDA      A  @S9S_MB_2U_LIB.S9S_MB_2U(SCH_1):I3C_SPD_DDREFGH_CPU0_LVC1_R_SDA

Q_RES  I63  R696   [Q_RES_0402LF-4.75K,1%,1/16W,CHA]
    2  RST_PCH_RSTBTN_R_N      B  @S9S_MB_2U_LIB.S9S_MB_2U(SCH_1):RST_PCH_RSTBTN_R_N
    1  P3V3_AUX           A  @S9S_MB_2U_LIB.S9S_MB_2U(SCH_1):P3V3_AUX

Q_RES  I66  R697   [Q_RES_0402LF-33,5%,1/16W,CHIP,A]
    2  RST_PCH_RSTBTN_R_N      B  @S9S_MB_2U_LIB.S9S_MB_2U(SCH_1):RST_PCH_RSTBTN_R_N
    1  FM_BMC_RSTBTN_OUT_N      A  @S9S_MB_2U_LIB.S9S_MB_2U(SCH_1):FM_BMC_RSTBTN_OUT_N

Q_RES  I32  R698   [Q_RES_0402LF-49.9     ,1%  ,1/A]
    1  FM_ADR_TRIGGER_R_N      A  @S9S_MB_2U_LIB.S9S_MB_2U(SCH_1):FM_ADR_TRIGGER_R_N
    2  FM_ADR_TRIGGER_N      B  @S9S_MB_2U_LIB.S9S_MB_2U(SCH_1):FM_ADR_TRIGGER_N

Q_RES  I102  R699   [Q_RES_0402LF-33,5%,1/16W,CHIP,A]
    1  FM_PCH_CRASHLOG_TRIG_R_N      A  @S9S_MB_2U_LIB.S9S_MB_2U(SCH_1):FM_PCH_CRASHLOG_TRIG_R_N
    2  FM_PCH_CRASHLOG_TRIG_N      B  @S9S_MB_2U_LIB.S9S_MB_2U(SCH_1):FM_PCH_CRASHLOG_TRIG_N

Q_RES  I382  R700   [Q_RES_0402LF-0,5%,1/16W,CHIP,CA]
    1  FM_ADR_ACK_R       A  @S9S_MB_2U_LIB.S9S_MB_2U(SCH_1):FM_ADR_ACK_R
    2  FM_ADR_ACK         B  @S9S_MB_2U_LIB.S9S_MB_2U(SCH_1):FM_ADR_ACK

Q_RES  I63  R701   [Q_RES_0402LF-10K,1%,1/16W,EMPTA]
    1  RST_PLD_CPU1_DRAM_CD_N      A  @S9S_MB_2U_LIB.S9S_MB_2U(SCH_1):RST_PLD_CPU1_DRAM_CD_N
    2  GND                B  @S9S_MB_2U_LIB.S9S_MB_2U(SCH_1):GND

Q_RES  I76  R702   [Q_RES_0402LF-10K,1%,1/16W,EMPTA]
    1  RST_PLD_CPU1_DRAM_GH_N      A  @S9S_MB_2U_LIB.S9S_MB_2U(SCH_1):RST_PLD_CPU1_DRAM_GH_N
    2  GND                B  @S9S_MB_2U_LIB.S9S_MB_2U(SCH_1):GND

Q_RES  I79  R703   [Q_RES_0402LF-10K,1%,1/16W,EMPTA]
    1  RST_PLD_CPU1_DRAM_AB_N      A  @S9S_MB_2U_LIB.S9S_MB_2U(SCH_1):RST_PLD_CPU1_DRAM_AB_N
    2  GND                B  @S9S_MB_2U_LIB.S9S_MB_2U(SCH_1):GND

Q_RES  I75  R704   [Q_RES_0402LF-10K,1%,1/16W,EMPTA]
    1  RST_PLD_CPU1_DRAM_EF_N      A  @S9S_MB_2U_LIB.S9S_MB_2U(SCH_1):RST_PLD_CPU1_DRAM_EF_N
    2  GND                B  @S9S_MB_2U_LIB.S9S_MB_2U(SCH_1):GND

Q_RES  I112  R705   [Q_RES_0402LF-10K,1%,1/16W,EMPTA]
    1  RST_PLD_CPU0_DRAM_GH_N      A  @S9S_MB_2U_LIB.S9S_MB_2U(SCH_1):RST_PLD_CPU0_DRAM_GH_N
    2  GND                B  @S9S_MB_2U_LIB.S9S_MB_2U(SCH_1):GND

Q_RES  I103  R706   [Q_RES_0402LF-10K,1%,1/16W,EMPTA]
    1  RST_PLD_CPU0_DRAM_AB_N      A  @S9S_MB_2U_LIB.S9S_MB_2U(SCH_1):RST_PLD_CPU0_DRAM_AB_N
    2  GND                B  @S9S_MB_2U_LIB.S9S_MB_2U(SCH_1):GND

Q_RES  I106  R707   [Q_RES_0402LF-10K,1%,1/16W,EMPTA]
    1  RST_PLD_CPU0_DRAM_CD_N      A  @S9S_MB_2U_LIB.S9S_MB_2U(SCH_1):RST_PLD_CPU0_DRAM_CD_N
    2  GND                B  @S9S_MB_2U_LIB.S9S_MB_2U(SCH_1):GND

Q_RES  I109  R708   [Q_RES_0402LF-10K,1%,1/16W,EMPTA]
    1  RST_PLD_CPU0_DRAM_EF_N      A  @S9S_MB_2U_LIB.S9S_MB_2U(SCH_1):RST_PLD_CPU0_DRAM_EF_N
    2  GND                B  @S9S_MB_2U_LIB.S9S_MB_2U(SCH_1):GND

Q_RES  I37  R709   [Q_RES_0402LF-33.2,1%,1/16W,CHIA]
    1  SMB_SENSOR_3V3AUX_SDA      A  @S9S_MB_2U_LIB.S9S_MB_2U(SCH_1):SMB_SENSOR_3V3AUX_SDA
    2  SMB_FRU_3V3AUX_SDA_R      B  @S9S_MB_2U_LIB.S9S_MB_2U(SCH_1):SMB_FRU_3V3AUX_SDA_R

Q_RES  I57  R710   [Q_RES_0402LF-1K,1%,1/16W,CHIP,A]
    1  PD_MB_FRU_WP       A  @S9S_MB_2U_LIB.S9S_MB_2U(SCH_1):PD_MB_FRU_WP
    2  GND                B  @S9S_MB_2U_LIB.S9S_MB_2U(SCH_1):GND

Q_RES  I27  R711   [Q_RES_0402LF-10K,1%,1/16W,EMPTA]
    2  TMP75_1_ADDR2      B  @S9S_MB_2U_LIB.S9S_MB_2U(SCH_1):TMP75_1_ADDR2
    1  P3V3_AUX           A  @S9S_MB_2U_LIB.S9S_MB_2U(SCH_1):P3V3_AUX

Q_RES  I30  R712   [Q_RES_0402LF-1K,1%,1/16W,CHIP,A]
    1  TMP75_1_ADDR2      A  @S9S_MB_2U_LIB.S9S_MB_2U(SCH_1):TMP75_1_ADDR2
    2  GND                B  @S9S_MB_2U_LIB.S9S_MB_2U(SCH_1):GND

Q_RES  I47  R713   [Q_RES_0402LF-10K,1%,1/16W,EMPTA]
    1  P3V3_AUX           A  @S9S_MB_2U_LIB.S9S_MB_2U(SCH_1):P3V3_AUX
    2  MB_FRU_ADDR2       B  @S9S_MB_2U_LIB.S9S_MB_2U(SCH_1):MB_FRU_ADDR2

Q_RES  I52  R714   [Q_RES_0402LF-1K,1%,1/16W,CHIP,A]
    1  MB_FRU_ADDR2       A  @S9S_MB_2U_LIB.S9S_MB_2U(SCH_1):MB_FRU_ADDR2
    2  GND                B  @S9S_MB_2U_LIB.S9S_MB_2U(SCH_1):GND

Q_RES  I28  R715   [Q_RES_0402LF-10K,1%,1/16W,EMPTA]
    2  TMP75_1_ADDR1      B  @S9S_MB_2U_LIB.S9S_MB_2U(SCH_1):TMP75_1_ADDR1
    1  P3V3_AUX           A  @S9S_MB_2U_LIB.S9S_MB_2U(SCH_1):P3V3_AUX

Q_RES  I31  R716   [Q_RES_0402LF-1K,1%,1/16W,CHIP,A]
    1  TMP75_1_ADDR1      A  @S9S_MB_2U_LIB.S9S_MB_2U(SCH_1):TMP75_1_ADDR1
    2  GND                B  @S9S_MB_2U_LIB.S9S_MB_2U(SCH_1):GND

Q_RES  I45  R717   [Q_RES_0402LF-10K,1%,1/16W,EMPTA]
    1  P3V3_AUX           A  @S9S_MB_2U_LIB.S9S_MB_2U(SCH_1):P3V3_AUX
    2  MB_FRU_ADDR1       B  @S9S_MB_2U_LIB.S9S_MB_2U(SCH_1):MB_FRU_ADDR1

Q_RES  I50  R718   [Q_RES_0402LF-1K,1%,1/16W,CHIP,A]
    1  MB_FRU_ADDR1       A  @S9S_MB_2U_LIB.S9S_MB_2U(SCH_1):MB_FRU_ADDR1
    2  GND                B  @S9S_MB_2U_LIB.S9S_MB_2U(SCH_1):GND

Q_RES  I29  R719   [Q_RES_0402LF-10K,1%,1/16W,CHIPA]
    2  TMP75_1_ADDR0      B  @S9S_MB_2U_LIB.S9S_MB_2U(SCH_1):TMP75_1_ADDR0
    1  P3V3_AUX           A  @S9S_MB_2U_LIB.S9S_MB_2U(SCH_1):P3V3_AUX

Q_RES  I32  R720   [Q_RES_0402LF-1K,1%,1/16W,EMPTYA]
    1  TMP75_1_ADDR0      A  @S9S_MB_2U_LIB.S9S_MB_2U(SCH_1):TMP75_1_ADDR0
    2  GND                B  @S9S_MB_2U_LIB.S9S_MB_2U(SCH_1):GND

Q_RES  I62  R721   [Q_RES_0402LF-10K,1%,1/16W,CHIPA]
    1  P3V3_AUX           A  @S9S_MB_2U_LIB.S9S_MB_2U(SCH_1):P3V3_AUX
    2  MB_FRU_ADDR0       B  @S9S_MB_2U_LIB.S9S_MB_2U(SCH_1):MB_FRU_ADDR0

Q_RES  I61  R722   [Q_RES_0402LF-1K,1%,1/16W,EMPTYA]
    1  MB_FRU_ADDR0       A  @S9S_MB_2U_LIB.S9S_MB_2U(SCH_1):MB_FRU_ADDR0
    2  GND                B  @S9S_MB_2U_LIB.S9S_MB_2U(SCH_1):GND

Q_RES  I154  R723   [Q_RES_0402LF-33,5%,1/16W,CHIP,A]
    1  SMB_FAN_3V3AUX_SCL_R1      A  @S9S_MB_2U_LIB.S9S_MB_2U(SCH_1):SMB_FAN_3V3AUX_SCL_R1
    2  SMB_FAN_3V3AUX_SCL      B  @S9S_MB_2U_LIB.S9S_MB_2U(SCH_1):SMB_FAN_3V3AUX_SCL

Q_RES  I166  R724   [Q_RES_0402LF-33,5%,1/16W,CHIP,A]
    1  SMB_FAN_3V3AUX_SDA_R1      A  @S9S_MB_2U_LIB.S9S_MB_2U(SCH_1):SMB_FAN_3V3AUX_SDA_R1
    2  SMB_FAN_3V3AUX_SDA      B  @S9S_MB_2U_LIB.S9S_MB_2U(SCH_1):SMB_FAN_3V3AUX_SDA

Q_RES  I92  R725   [Q_RES_0402LF-33.2,1%,1/16W,CHIA]
    2  SMB_TMP75_2_3V3AUX_SDA_R      B  @S9S_MB_2U_LIB.S9S_MB_2U(SCH_1):SMB_TMP75_2_3V3AUX_SDA_R
    1  SMB_SENSOR_3V3AUX_SDA      A  @S9S_MB_2U_LIB.S9S_MB_2U(SCH_1):SMB_SENSOR_3V3AUX_SDA

Q_RES  I91  R726   [Q_RES_0402LF-33.2,1%,1/16W,CHIA]
    2  SMB_TMP75_2_3V3AUX_SCL_R      B  @S9S_MB_2U_LIB.S9S_MB_2U(SCH_1):SMB_TMP75_2_3V3AUX_SCL_R
    1  SMB_SENSOR_3V3AUX_SCL      A  @S9S_MB_2U_LIB.S9S_MB_2U(SCH_1):SMB_SENSOR_3V3AUX_SCL

Q_RES  I236  R727   [Q_RES_0402LF-10K,1%,1/16W,CHIPA]
    1  PU_OC4_USB_N       A  @S9S_MB_2U_LIB.S9S_MB_2U(SCH_1):PU_OC4_USB_N
    2  P3V3_AUX           B  @S9S_MB_2U_LIB.S9S_MB_2U(SCH_1):P3V3_AUX

Q_RES  I87  R728   [Q_RES_0402LF-10K,1%,1/16W,EMPTA]
    2  TMP75_2_ADDR2      B  @S9S_MB_2U_LIB.S9S_MB_2U(SCH_1):TMP75_2_ADDR2
    1  P3V3_AUX           A  @S9S_MB_2U_LIB.S9S_MB_2U(SCH_1):P3V3_AUX

Q_RES  I90  R729   [Q_RES_0402LF-1K,1%,1/16W,CHIP,A]
    1  TMP75_2_ADDR2      A  @S9S_MB_2U_LIB.S9S_MB_2U(SCH_1):TMP75_2_ADDR2
    2  GND                B  @S9S_MB_2U_LIB.S9S_MB_2U(SCH_1):GND

Q_RES  I86  R730   [Q_RES_0402LF-10K,1%,1/16W,CHIPA]
    2  TMP75_2_ADDR1      B  @S9S_MB_2U_LIB.S9S_MB_2U(SCH_1):TMP75_2_ADDR1
    1  P3V3_AUX           A  @S9S_MB_2U_LIB.S9S_MB_2U(SCH_1):P3V3_AUX

Q_RES  I89  R731   [Q_RES_0402LF-1K,1%,1/16W,EMPTYA]
    1  TMP75_2_ADDR1      A  @S9S_MB_2U_LIB.S9S_MB_2U(SCH_1):TMP75_2_ADDR1
    2  GND                B  @S9S_MB_2U_LIB.S9S_MB_2U(SCH_1):GND

Q_RES  I85  R732   [Q_RES_0402LF-10K,1%,1/16W,EMPTA]
    2  TMP75_2_ADDR0      B  @S9S_MB_2U_LIB.S9S_MB_2U(SCH_1):TMP75_2_ADDR0
    1  P3V3_AUX           A  @S9S_MB_2U_LIB.S9S_MB_2U(SCH_1):P3V3_AUX

Q_RES  I88  R733   [Q_RES_0402LF-1K,1%,1/16W,CHIP,A]
    1  TMP75_2_ADDR0      A  @S9S_MB_2U_LIB.S9S_MB_2U(SCH_1):TMP75_2_ADDR0
    2  GND                B  @S9S_MB_2U_LIB.S9S_MB_2U(SCH_1):GND

Q_RES  I283  R734   [Q_RES_0402LF-4.75K,1%,1/16W,CHA]
    2  GND                B  @S9S_MB_2U_LIB.S9S_MB_2U(SCH_1):GND
    1  CLK_CK440_SMB_ADDR1      A  @S9S_MB_2U_LIB.S9S_MB_2U(SCH_1):CLK_CK440_SMB_ADDR1

Q_RES  I123  R735   [Q_RES_0402LF-10K,1%,1/16W,CHIPA]
    1  P3V3_AUX           A  @S9S_MB_2U_LIB.S9S_MB_2U(SCH_1):P3V3_AUX
    2  FM_DIMM_12V_CPS_SX_N      B  @S9S_MB_2U_LIB.S9S_MB_2U(SCH_1):FM_DIMM_12V_CPS_SX_N

Q_RES  I125  R736   [Q_RES_0402LF-1K,1%,1/16W,EMPTYA]
    2  GND                B  @S9S_MB_2U_LIB.S9S_MB_2U(SCH_1):GND
    1  FM_DIMM_12V_CPS_SX_N      A  @S9S_MB_2U_LIB.S9S_MB_2U(SCH_1):FM_DIMM_12V_CPS_SX_N

Q_RES  I106  R737   [Q_RES_0402LF-0,5%,1/16W,CHIP,CA]
    2  FM_CPU1_SKTOCC_N      B  @S9S_MB_2U_LIB.S9S_MB_2U(SCH_1):FM_CPU1_SKTOCC_N
    1  FM_CPU1_SKTOCC_LVT3_N      A  @S9S_MB_2U_LIB.S9S_MB_2U(SCH_1):FM_CPU1_SKTOCC_LVT3_N

Q_RES  I110  R738   [Q_RES_0402LF-0,5%,1/16W,CHIP,CA]
    2  FM_CPU0_SKTOCC_N      B  @S9S_MB_2U_LIB.S9S_MB_2U(SCH_1):FM_CPU0_SKTOCC_N
    1  FM_CPU0_SKTOCC_LVT3_N      A  @S9S_MB_2U_LIB.S9S_MB_2U(SCH_1):FM_CPU0_SKTOCC_LVT3_N

Q_RES  I109  R739   [Q_RES_0402LF-10K,1%,1/16W,CHIPA]
    1  P3V3_AUX           A  @S9S_MB_2U_LIB.S9S_MB_2U(SCH_1):P3V3_AUX
    2  FM_CPU1_SKTOCC_N      B  @S9S_MB_2U_LIB.S9S_MB_2U(SCH_1):FM_CPU1_SKTOCC_N

Q_RES  I107  R740   [Q_RES_0402LF-10K,1%,1/16W,CHIPA]
    1  P3V3_AUX           A  @S9S_MB_2U_LIB.S9S_MB_2U(SCH_1):P3V3_AUX
    2  FM_CPU0_SKTOCC_N      B  @S9S_MB_2U_LIB.S9S_MB_2U(SCH_1):FM_CPU0_SKTOCC_N

Q_RES  I66  R741   [Q_RES_0402LF-150,1%,1/16W,CHIPA]
    1  PVNN_TERM_CPU0      A  @S9S_MB_2U_LIB.S9S_MB_2U(SCH_1):PVNN_TERM_CPU0
    2  JTAG_MUX_CPU0_GTL_TDI      B  @S9S_MB_2U_LIB.S9S_MB_2U(SCH_1):JTAG_MUX_CPU0_GTL_TDI

Q_RES  I78  R742   [Q_RES_0402LF-75,1%,1/16W,CHIP,A]
    1  PVNN_TERM_CPU1      A  @S9S_MB_2U_LIB.S9S_MB_2U(SCH_1):PVNN_TERM_CPU1
    2  JTAG_CPU1_MUX_GTL_TDO      B  @S9S_MB_2U_LIB.S9S_MB_2U(SCH_1):JTAG_CPU1_MUX_GTL_TDO

Q_RES  I65  R743   [Q_RES_0402LF-150,1%,1/16W,CHIPA]
    1  PVNN_TERM_CPU1      A  @S9S_MB_2U_LIB.S9S_MB_2U(SCH_1):PVNN_TERM_CPU1
    2  JTAG_MUX_CPU1_GTL_TDI      B  @S9S_MB_2U_LIB.S9S_MB_2U(SCH_1):JTAG_MUX_CPU1_GTL_TDI

Q_RES  I77  R744   [Q_RES_0402LF-75,1%,1/16W,CHIP,A]
    1  PVNN_TERM_CPU0      A  @S9S_MB_2U_LIB.S9S_MB_2U(SCH_1):PVNN_TERM_CPU0
    2  JTAG_CPU0_MUX_GTL_TDO      B  @S9S_MB_2U_LIB.S9S_MB_2U(SCH_1):JTAG_CPU0_MUX_GTL_TDO

Q_RES  I97  R745   [Q_RES_0402LF-33,5%,1/16W,CHIP,A]
    2  FM_CPU_EN_R        B  @S9S_MB_2U_LIB.S9S_MB_2U(SCH_1):FM_CPU_EN_R
    1  FM_CPU_EN          A  @S9S_MB_2U_LIB.S9S_MB_2U(SCH_1):FM_CPU_EN

Q_RES  I90  R746   [Q_RES_0402LF-0,5%,1/16W,CHIP,CA]
    1  PD_74CB_A9         A  @S9S_MB_2U_LIB.S9S_MB_2U(SCH_1):PD_74CB_A9
    2  GND                B  @S9S_MB_2U_LIB.S9S_MB_2U(SCH_1):GND

Q_RES  I176  R747   [Q_RES_0402LF-150,1%,1/16W,CHIPA]
    1  P1V05_PCH_AUX      A  @S9S_MB_2U_LIB.S9S_MB_2U(SCH_1):P1V05_PCH_AUX
    2  JTAG_DBP_TDO_PCH      B  @S9S_MB_2U_LIB.S9S_MB_2U(SCH_1):JTAG_DBP_TDO_PCH

Q_RES  I180  R748   [Q_RES_0402LF-75,1%,1/16W,CHIP,A]
    1  P1V05_PCH_AUX      A  @S9S_MB_2U_LIB.S9S_MB_2U(SCH_1):P1V05_PCH_AUX
    2  JTAG_DBP_TDI_PCH      B  @S9S_MB_2U_LIB.S9S_MB_2U(SCH_1):JTAG_DBP_TDI_PCH

Q_RES  I179  R749   [Q_RES_0402LF-75,1%,1/16W,CHIP,A]
    1  P1V05_PCH_AUX      A  @S9S_MB_2U_LIB.S9S_MB_2U(SCH_1):P1V05_PCH_AUX
    2  JTAG_DBP_TMS_PCH      B  @S9S_MB_2U_LIB.S9S_MB_2U(SCH_1):JTAG_DBP_TMS_PCH

Q_RES  I178  R750   [Q_RES_0402LF-150,1%,1/16W,CHIPA]
    1  P1V05_PCH_AUX      A  @S9S_MB_2U_LIB.S9S_MB_2U(SCH_1):P1V05_PCH_AUX
    2  H_DBP_PREQ_N_PCH      B  @S9S_MB_2U_LIB.S9S_MB_2U(SCH_1):H_DBP_PREQ_N_PCH

Q_RES  I177  R751   [Q_RES_0402LF-150,1%,1/16W,CHIPA]
    1  P1V05_PCH_AUX      A  @S9S_MB_2U_LIB.S9S_MB_2U(SCH_1):P1V05_PCH_AUX
    2  H_DBP_PRDY_N_PCH      B  @S9S_MB_2U_LIB.S9S_MB_2U(SCH_1):H_DBP_PRDY_N_PCH

Q_RES  I127  R752   [Q_RES_0402LF-10,1%,1/16W,CHIP,A]
    2  JTAG_DBP_TDO_PCH      B  @S9S_MB_2U_LIB.S9S_MB_2U(SCH_1):JTAG_DBP_TDO_PCH
    1  JTAG_DBP_TDO       A  @S9S_MB_2U_LIB.S9S_MB_2U(SCH_1):JTAG_DBP_TDO

Q_RES  I128  R753   [Q_RES_0402LF-10,1%,1/16W,CHIP,A]
    2  JTAG_DBP_TDI_PCH      B  @S9S_MB_2U_LIB.S9S_MB_2U(SCH_1):JTAG_DBP_TDI_PCH
    1  JTAG_DBP_TDI       A  @S9S_MB_2U_LIB.S9S_MB_2U(SCH_1):JTAG_DBP_TDI

Q_RES  I126  R754   [Q_RES_0402LF-10,1%,1/16W,CHIP,A]
    2  JTAG_DBP_TMS_PCH      B  @S9S_MB_2U_LIB.S9S_MB_2U(SCH_1):JTAG_DBP_TMS_PCH
    1  JTAG_DBP_TMS       A  @S9S_MB_2U_LIB.S9S_MB_2U(SCH_1):JTAG_DBP_TMS

Q_RES  I147  R755   [Q_RES_0402LF-10,1%,1/16W,CHIP,A]
    1  JTAG_DBP_PREQ_N      A  @S9S_MB_2U_LIB.S9S_MB_2U(SCH_1):JTAG_DBP_PREQ_N
    2  H_DBP_PREQ_N_PCH      B  @S9S_MB_2U_LIB.S9S_MB_2U(SCH_1):H_DBP_PREQ_N_PCH

Q_RES  I148  R756   [Q_RES_0402LF-10,1%,1/16W,CHIP,A]
    1  JTAG_DBP_PRDY_N      A  @S9S_MB_2U_LIB.S9S_MB_2U(SCH_1):JTAG_DBP_PRDY_N
    2  H_DBP_PRDY_N_PCH      B  @S9S_MB_2U_LIB.S9S_MB_2U(SCH_1):H_DBP_PRDY_N_PCH

Q_RES  I166  R757   [Q_RES_0402LF-120,1%,1/16W,CHIPA]
    1  PVNN_TERM_CPU0      A  @S9S_MB_2U_LIB.S9S_MB_2U(SCH_1):PVNN_TERM_CPU0
    2  JTAG_DBP_CPU_QS_GTL_TMS      B  @S9S_MB_2U_LIB.S9S_MB_2U(SCH_1):JTAG_DBP_CPU_QS_GTL_TMS

Q_RES  I168  R758   [Q_RES_0402LF-150,1%,1/16W,CHIPA]
    1  PVNN_TERM_CPU0      A  @S9S_MB_2U_LIB.S9S_MB_2U(SCH_1):PVNN_TERM_CPU0
    2  H_CPU_PREQ_QS_GTL_N      B  @S9S_MB_2U_LIB.S9S_MB_2U(SCH_1):H_CPU_PREQ_QS_GTL_N

Q_RES  I169  R759   [Q_RES_0402LF-150,1%,1/16W,CHIPA]
    1  PVNN_TERM_CPU0      A  @S9S_MB_2U_LIB.S9S_MB_2U(SCH_1):PVNN_TERM_CPU0
    2  H_CPU_PRDY_QS_GTL_N      B  @S9S_MB_2U_LIB.S9S_MB_2U(SCH_1):H_CPU_PRDY_QS_GTL_N

Q_RES  I174  R760   [Q_RES_0402LF-499,1%,1/16W,CHIPA]
    1  PVNN_TERM_CPU0      A  @S9S_MB_2U_LIB.S9S_MB_2U(SCH_1):PVNN_TERM_CPU0
    2  DBP_CPU_HOOK8_MBP2_GTL_QS_N      B  @S9S_MB_2U_LIB.S9S_MB_2U(SCH_1):DBP_CPU_HOOK8_MBP2_GTL_QS_N

Q_RES  I175  R761   [Q_RES_0402LF-499,1%,1/16W,CHIPA]
    1  PVNN_TERM_CPU0      A  @S9S_MB_2U_LIB.S9S_MB_2U(SCH_1):PVNN_TERM_CPU0
    2  DBP_CPU_HOOK9_MBP3_GTL_QS_N      B  @S9S_MB_2U_LIB.S9S_MB_2U(SCH_1):DBP_CPU_HOOK9_MBP3_GTL_QS_N

Q_RES  I71  R762   [Q_RES_0402LF-0,5%,1/16W,CHIP,CA]
    2  JTAG_DBP_CPU_GTL_TCK_R      B  @S9S_MB_2U_LIB.S9S_MB_2U(SCH_1):JTAG_DBP_CPU_GTL_TCK_R
    1  JTAG_DBP_CPU_GTL_TCK      A  @S9S_MB_2U_LIB.S9S_MB_2U(SCH_1):JTAG_DBP_CPU_GTL_TCK

Q_RES  I70  R763   [Q_RES_0402LF-10,1%,1/16W,CHIP,A]
    2  JTAG_DBP_TDI_R      B  @S9S_MB_2U_LIB.S9S_MB_2U(SCH_1):JTAG_DBP_TDI_R
    1  JTAG_DBP_TDI       A  @S9S_MB_2U_LIB.S9S_MB_2U(SCH_1):JTAG_DBP_TDI

Q_RES  I83  R764   [Q_RES_0402LF-0,5%,1/16W,CHIP,CA]
    2  JTAG_DBP_PRDY_R1_N      B  @S9S_MB_2U_LIB.S9S_MB_2U(SCH_1):JTAG_DBP_PRDY_R1_N
    1  JTAG_DBP_PRDY_N      A  @S9S_MB_2U_LIB.S9S_MB_2U(SCH_1):JTAG_DBP_PRDY_N

Q_RES  I74  R765   [Q_RES_0402LF-0,5%,1/16W,CHIP,CA]
    2  JTAG_DBP_TCK_R_TCK      B  @S9S_MB_2U_LIB.S9S_MB_2U(SCH_1):JTAG_DBP_TCK_R_TCK
    1  JTAG_DBP_TCK_PCH      A  @S9S_MB_2U_LIB.S9S_MB_2U(SCH_1):JTAG_DBP_TCK_PCH

Q_RES  I111  R766   [Q_RES_0402LF-1K,1%,1/16W,EMPTYA]
    1  P3V3_AUX           A  @S9S_MB_2U_LIB.S9S_MB_2U(SCH_1):P3V3_AUX
    2  JTAG_DBP_POWER_BTN_N      B  @S9S_MB_2U_LIB.S9S_MB_2U(SCH_1):JTAG_DBP_POWER_BTN_N

Q_RES  I113  R767   [Q_RES_0402LF-1K,1%,1/16W,CHIP,A]
    1  P3V3_AUX           A  @S9S_MB_2U_LIB.S9S_MB_2U(SCH_1):P3V3_AUX
    2  JTAG_RST_DBP_RST_CO_N      B  @S9S_MB_2U_LIB.S9S_MB_2U(SCH_1):JTAG_RST_DBP_RST_CO_N

Q_RES  I112  R768   [Q_RES_0402LF-1K,1%,1/16W,CHIP,A]
    1  P3V3_AUX           A  @S9S_MB_2U_LIB.S9S_MB_2U(SCH_1):P3V3_AUX
    2  JTAG_DBP_PRESENT_R_N      B  @S9S_MB_2U_LIB.S9S_MB_2U(SCH_1):JTAG_DBP_PRESENT_R_N

Q_RES  I102  R769   [Q_RES_0402LF-10K,1%,1/16W,CHIPA]
    1  PD_TRST_P3         A  @S9S_MB_2U_LIB.S9S_MB_2U(SCH_1):PD_TRST_P3
    2  GND                B  @S9S_MB_2U_LIB.S9S_MB_2U(SCH_1):GND

Q_RES  I239  R770   [Q_RES_0402LF-10K,1%,1/16W,CHIPA]
    1  PU_OC5_USB_N       A  @S9S_MB_2U_LIB.S9S_MB_2U(SCH_1):PU_OC5_USB_N
    2  P3V3_AUX           B  @S9S_MB_2U_LIB.S9S_MB_2U(SCH_1):P3V3_AUX

Q_RES  I120  R771   [Q_RES_0402LF-1K,1%,1/16W,CHIP,A]
    1  JTAG_DBP_PCH_DEBUG_CONSENT_N      A  @S9S_MB_2U_LIB.S9S_MB_2U(SCH_1):JTAG_DBP_PCH_DEBUG_CONSENT_N
    2  FM_PCH_CONSENT_STRAP_N      B  @S9S_MB_2U_LIB.S9S_MB_2U(SCH_1):FM_PCH_CONSENT_STRAP_N

Q_RES  I118  R772   [Q_RES_0402LF-1K,1%,1/16W,CHIP,A]
    2  RST_RSMRST_PCH_N      B  @S9S_MB_2U_LIB.S9S_MB_2U(SCH_1):RST_RSMRST_PCH_N
    1  JTAG_RST_DBP_RSMRST_N      A  @S9S_MB_2U_LIB.S9S_MB_2U(SCH_1):JTAG_RST_DBP_RSMRST_N

Q_RES  I124  R773   [Q_RES_0402LF-1K,1%,1/16W,CHIP,A]
    1  JTAG_DBP_BOOT_HALT_N      A  @S9S_MB_2U_LIB.S9S_MB_2U(SCH_1):JTAG_DBP_BOOT_HALT_N
    2  FM_ADR_MODE0       B  @S9S_MB_2U_LIB.S9S_MB_2U(SCH_1):FM_ADR_MODE0

Q_RES  I132  R774   [Q_RES_0402LF-75,1%,1/16W,CHIP,A]
    1  JTAG_DBP_CPU_GTL_TCK      A  @S9S_MB_2U_LIB.S9S_MB_2U(SCH_1):JTAG_DBP_CPU_GTL_TCK
    2  GND                B  @S9S_MB_2U_LIB.S9S_MB_2U(SCH_1):GND

Q_RES  I5   R775   [Q_RES_0402LF-10,1%,1/16W,CHIP,A]
    1  JTAG_DBP_TMS_R      A  @S9S_MB_2U_LIB.S9S_MB_2U(SCH_1):JTAG_DBP_TMS_R
    2  JTAG_DBP_TMS       B  @S9S_MB_2U_LIB.S9S_MB_2U(SCH_1):JTAG_DBP_TMS

Q_RES  I7   R776   [Q_RES_0402LF-100,1%,1/16W,CHIPA]
    1  JTAG_DBP_TDO_R      A  @S9S_MB_2U_LIB.S9S_MB_2U(SCH_1):JTAG_DBP_TDO_R
    2  JTAG_DBP_TDO       B  @S9S_MB_2U_LIB.S9S_MB_2U(SCH_1):JTAG_DBP_TDO

Q_RES  I10  R777   [Q_RES_0402LF-10,1%,1/16W,CHIP,A]
    1  JTAG_DBP_PREQ_N_R      A  @S9S_MB_2U_LIB.S9S_MB_2U(SCH_1):JTAG_DBP_PREQ_N_R
    2  JTAG_DBP_PREQ_N      B  @S9S_MB_2U_LIB.S9S_MB_2U(SCH_1):JTAG_DBP_PREQ_N

Q_RES  I15  R778   [Q_RES_0402LF-1K,1%,1/16W,CHIP,A]
    1  P3V3_AUX           A  @S9S_MB_2U_LIB.S9S_MB_2U(SCH_1):P3V3_AUX
    2  JTAG_DBP_BOOT_HALT_N      B  @S9S_MB_2U_LIB.S9S_MB_2U(SCH_1):JTAG_DBP_BOOT_HALT_N

Q_RES  I95  R779   [Q_RES_0402LF-150,5%,1/16W,CHIPA]
    1  PVNN_TERM_CPU0      A  @S9S_MB_2U_LIB.S9S_MB_2U(SCH_1):PVNN_TERM_CPU0
    2  FM_CPU_FBRK_DEBUG_N      B  @S9S_MB_2U_LIB.S9S_MB_2U(SCH_1):FM_CPU_FBRK_DEBUG_N

Q_RES  I92  R780   [Q_RES_0402LF-49.9     ,1%  ,1/A]
    2  FM_CPU_FBRK_DEBUG_R_N      B  @S9S_MB_2U_LIB.S9S_MB_2U(SCH_1):FM_CPU_FBRK_DEBUG_R_N
    1  FM_CPU_FBRK_DEBUG_N      A  @S9S_MB_2U_LIB.S9S_MB_2U(SCH_1):FM_CPU_FBRK_DEBUG_N

Q_RES  I9   R781   [Q_RES_0402LF-10K,1%,1/16W,EMPTA]
    2  PCA9548_PCIE2_ADDR2      B  @S9S_MB_2U_LIB.S9S_MB_2U(SCH_1):PCA9548_PCIE2_ADDR2
    1  P3V3_AUX           A  @S9S_MB_2U_LIB.S9S_MB_2U(SCH_1):P3V3_AUX

Q_RES  I6   R782   [Q_RES_0402LF-1K,1%,1/16W,CHIP,A]
    1  PCA9548_PCIE2_ADDR2      A  @S9S_MB_2U_LIB.S9S_MB_2U(SCH_1):PCA9548_PCIE2_ADDR2
    2  GND                B  @S9S_MB_2U_LIB.S9S_MB_2U(SCH_1):GND

Q_RES  I10  R783   [Q_RES_0402LF-10K,1%,1/16W,CHIPA]
    2  PCA9548_PCIE2_ADDR1      B  @S9S_MB_2U_LIB.S9S_MB_2U(SCH_1):PCA9548_PCIE2_ADDR1
    1  P3V3_AUX           A  @S9S_MB_2U_LIB.S9S_MB_2U(SCH_1):P3V3_AUX

Q_RES  I8   R784   [Q_RES_0402LF-1K,1%,1/16W,EMPTYA]
    1  PCA9548_PCIE2_ADDR1      A  @S9S_MB_2U_LIB.S9S_MB_2U(SCH_1):PCA9548_PCIE2_ADDR1
    2  GND                B  @S9S_MB_2U_LIB.S9S_MB_2U(SCH_1):GND

Q_RES  I13  R785   [Q_RES_0402LF-10K,1%,1/16W,EMPTA]
    2  PCA9548_PCIE2_ADDR0      B  @S9S_MB_2U_LIB.S9S_MB_2U(SCH_1):PCA9548_PCIE2_ADDR0
    1  P3V3_AUX           A  @S9S_MB_2U_LIB.S9S_MB_2U(SCH_1):P3V3_AUX

Q_RES  I12  R786   [Q_RES_0402LF-1K,1%,1/16W,CHIP,A]
    1  PCA9548_PCIE2_ADDR0      A  @S9S_MB_2U_LIB.S9S_MB_2U(SCH_1):PCA9548_PCIE2_ADDR0
    2  GND                B  @S9S_MB_2U_LIB.S9S_MB_2U(SCH_1):GND

Q_RES  I85  R787   [Q_RES_0402LF-0,5%,1/16W,CHIP,CA]
    1  SMB_EDSFF1A_3V3AUX_SCL_R1      A  @S9S_MB_2U_LIB.S9S_MB_2U(SCH_1):SMB_EDSFF1A_3V3AUX_SCL_R1
    2  SMB_EDSFF1A_3V3AUX_SCL_R      B  @S9S_MB_2U_LIB.S9S_MB_2U(SCH_1):SMB_EDSFF1A_3V3AUX_SCL_R

Q_RES  I84  R788   [Q_RES_0402LF-0,5%,1/16W,CHIP,CA]
    1  SMB_EDSFF1A_3V3AUX_SDA_R1      A  @S9S_MB_2U_LIB.S9S_MB_2U(SCH_1):SMB_EDSFF1A_3V3AUX_SDA_R1
    2  SMB_EDSFF1A_3V3AUX_SDA_R      B  @S9S_MB_2U_LIB.S9S_MB_2U(SCH_1):SMB_EDSFF1A_3V3AUX_SDA_R

Q_RES  I87  R789   [Q_RES_0402LF-0,5%,1/16W,CHIP,CA]
    1  SMB_EDSFF2A_3V3AUX_SCL_R1      A  @S9S_MB_2U_LIB.S9S_MB_2U(SCH_1):SMB_EDSFF2A_3V3AUX_SCL_R1
    2  SMB_EDSFF2A_3V3AUX_SCL_R      B  @S9S_MB_2U_LIB.S9S_MB_2U(SCH_1):SMB_EDSFF2A_3V3AUX_SCL_R

Q_RES  I86  R790   [Q_RES_0402LF-0,5%,1/16W,CHIP,CA]
    1  SMB_EDSFF2A_3V3AUX_SDA_R1      A  @S9S_MB_2U_LIB.S9S_MB_2U(SCH_1):SMB_EDSFF2A_3V3AUX_SDA_R1
    2  SMB_EDSFF2A_3V3AUX_SDA_R      B  @S9S_MB_2U_LIB.S9S_MB_2U(SCH_1):SMB_EDSFF2A_3V3AUX_SDA_R

Q_RES  I33  R791   [Q_RES_0402LF-2.2K ,5%,1/16W,CHA]
    2  SMB_EDSFF1A_3V3AUX_SCL_R      B  @S9S_MB_2U_LIB.S9S_MB_2U(SCH_1):SMB_EDSFF1A_3V3AUX_SCL_R
    1  P3V3_AUX           A  @S9S_MB_2U_LIB.S9S_MB_2U(SCH_1):P3V3_AUX

Q_RES  I32  R792   [Q_RES_0402LF-2.2K ,5%,1/16W,CHA]
    2  SMB_EDSFF1A_3V3AUX_SDA_R      B  @S9S_MB_2U_LIB.S9S_MB_2U(SCH_1):SMB_EDSFF1A_3V3AUX_SDA_R
    1  P3V3_AUX           A  @S9S_MB_2U_LIB.S9S_MB_2U(SCH_1):P3V3_AUX

Q_RES  I116  R793   [Q_RES_0402LF-2.2K ,5%,1/16W,CHA]
    2  SMB_EDSFF2A_3V3AUX_SCL_R      B  @S9S_MB_2U_LIB.S9S_MB_2U(SCH_1):SMB_EDSFF2A_3V3AUX_SCL_R
    1  P3V3_AUX           A  @S9S_MB_2U_LIB.S9S_MB_2U(SCH_1):P3V3_AUX

Q_RES  I117  R794   [Q_RES_0402LF-2.2K ,5%,1/16W,CHA]
    2  SMB_EDSFF2A_3V3AUX_SDA_R      B  @S9S_MB_2U_LIB.S9S_MB_2U(SCH_1):SMB_EDSFF2A_3V3AUX_SDA_R
    1  P3V3_AUX           A  @S9S_MB_2U_LIB.S9S_MB_2U(SCH_1):P3V3_AUX

Q_RES  I134  R795   [Q_RES_0402LF-2.2K ,5%,1/16W,CHA]
    2  SMB_EDSFF3_3V3AUX_SCL_R      B  @S9S_MB_2U_LIB.S9S_MB_2U(SCH_1):SMB_EDSFF3_3V3AUX_SCL_R
    1  P3V3_AUX           A  @S9S_MB_2U_LIB.S9S_MB_2U(SCH_1):P3V3_AUX

Q_RES  I135  R796   [Q_RES_0402LF-2.2K ,5%,1/16W,CHA]
    2  SMB_EDSFF3_3V3AUX_SDA_R      B  @S9S_MB_2U_LIB.S9S_MB_2U(SCH_1):SMB_EDSFF3_3V3AUX_SDA_R
    1  P3V3_AUX           A  @S9S_MB_2U_LIB.S9S_MB_2U(SCH_1):P3V3_AUX

Q_RES  I136  R797   [Q_RES_0402LF-2.2K ,5%,1/16W,CHA]
    2  SMB_EDSFF4A_3V3AUX_SCL_R      B  @S9S_MB_2U_LIB.S9S_MB_2U(SCH_1):SMB_EDSFF4A_3V3AUX_SCL_R
    1  P3V3_AUX           A  @S9S_MB_2U_LIB.S9S_MB_2U(SCH_1):P3V3_AUX

Q_RES  I137  R798   [Q_RES_0402LF-2.2K ,5%,1/16W,CHA]
    2  SMB_EDSFF4A_3V3AUX_SDA_R      B  @S9S_MB_2U_LIB.S9S_MB_2U(SCH_1):SMB_EDSFF4A_3V3AUX_SDA_R
    1  P3V3_AUX           A  @S9S_MB_2U_LIB.S9S_MB_2U(SCH_1):P3V3_AUX

Q_RES  I68  R799   [Q_RES_0402LF-0,5%,1/16W,CHIP,CA]
    1  SMB_EDSFF4A_3V3AUX_SCL_R1      A  @S9S_MB_2U_LIB.S9S_MB_2U(SCH_1):SMB_EDSFF4A_3V3AUX_SCL_R1
    2  SMB_EDSFF4A_3V3AUX_SCL_R      B  @S9S_MB_2U_LIB.S9S_MB_2U(SCH_1):SMB_EDSFF4A_3V3AUX_SCL_R

Q_RES  I65  R800   [Q_RES_0402LF-0,5%,1/16W,CHIP,CA]
    1  SMB_EDSFF4A_3V3AUX_SDA_R1      A  @S9S_MB_2U_LIB.S9S_MB_2U(SCH_1):SMB_EDSFF4A_3V3AUX_SDA_R1
    2  SMB_EDSFF4A_3V3AUX_SDA_R      B  @S9S_MB_2U_LIB.S9S_MB_2U(SCH_1):SMB_EDSFF4A_3V3AUX_SDA_R

Q_RES  I63  R801   [Q_RES_0402LF-0,5%,1/16W,CHIP,CA]
    1  SMB_EDSFF3_3V3AUX_SCL_R1      A  @S9S_MB_2U_LIB.S9S_MB_2U(SCH_1):SMB_EDSFF3_3V3AUX_SCL_R1
    2  SMB_EDSFF3_3V3AUX_SCL_R      B  @S9S_MB_2U_LIB.S9S_MB_2U(SCH_1):SMB_EDSFF3_3V3AUX_SCL_R

Q_RES  I64  R802   [Q_RES_0402LF-0,5%,1/16W,CHIP,CA]
    1  SMB_EDSFF3_3V3AUX_SDA_R1      A  @S9S_MB_2U_LIB.S9S_MB_2U(SCH_1):SMB_EDSFF3_3V3AUX_SDA_R1
    2  SMB_EDSFF3_3V3AUX_SDA_R      B  @S9S_MB_2U_LIB.S9S_MB_2U(SCH_1):SMB_EDSFF3_3V3AUX_SDA_R

Q_RES  I19  R803   [Q_RES_0402LF-33,5%,1/16W,CHIP,A]
    1  JTAG_PLD_TDI_R      A  @S9S_MB_2U_LIB.S9S_MB_2U(SCH_1):JTAG_PLD_TDI_R
    2  JTAG_BMC_PLD_TDI      B  @S9S_MB_2U_LIB.S9S_MB_2U(SCH_1):JTAG_BMC_PLD_TDI

Q_RES  I20  R804   [Q_RES_0402LF-33,5%,1/16W,CHIP,A]
    1  JTAG_PLD_TDO_R      A  @S9S_MB_2U_LIB.S9S_MB_2U(SCH_1):JTAG_PLD_TDO_R
    2  JTAG_BMC_PLD_TDO      B  @S9S_MB_2U_LIB.S9S_MB_2U(SCH_1):JTAG_BMC_PLD_TDO

Q_RES  I25  R805   [Q_RES_0402LF-33,5%,1/16W,CHIP,A]
    1  JTAG_PLD_TMS_R      A  @S9S_MB_2U_LIB.S9S_MB_2U(SCH_1):JTAG_PLD_TMS_R
    2  JTAG_BMC_PLD_TMS      B  @S9S_MB_2U_LIB.S9S_MB_2U(SCH_1):JTAG_BMC_PLD_TMS

Q_RES  I54  R806   [Q_RES_0402LF-33,5%,1/16W,CHIP,A]
    1  JTAG_PLD_TCK_R      A  @S9S_MB_2U_LIB.S9S_MB_2U(SCH_1):JTAG_PLD_TCK_R
    2  JTAG_BMC_PLD_TCK      B  @S9S_MB_2U_LIB.S9S_MB_2U(SCH_1):JTAG_BMC_PLD_TCK

Q_RES  I11  R815   [Q_RES_0402LF-0,5%,1/16W,CHIP,CA]
    1  RST_PLD_CPU1_DRAM_GH_N      A  @S9S_MB_2U_LIB.S9S_MB_2U(SCH_1):RST_PLD_CPU1_DRAM_GH_N
    2  RST_M_GH_CPU1_FPGA_N      B  @S9S_MB_2U_LIB.S9S_MB_2U(SCH_1):RST_M_GH_CPU1_FPGA_N

Q_RES  I37  R816   [Q_RES_0402LF-0,5%,1/16W,CHIP,CA]
    1  RST_PLD_CPU1_DRAM_AB_N      A  @S9S_MB_2U_LIB.S9S_MB_2U(SCH_1):RST_PLD_CPU1_DRAM_AB_N
    2  RST_M_AB_CPU1_FPGA_N      B  @S9S_MB_2U_LIB.S9S_MB_2U(SCH_1):RST_M_AB_CPU1_FPGA_N

Q_RES  I26  R817   [Q_RES_0402LF-0,5%,1/16W,CHIP,CA]
    1  RST_PLD_CPU1_DRAM_CD_N      A  @S9S_MB_2U_LIB.S9S_MB_2U(SCH_1):RST_PLD_CPU1_DRAM_CD_N
    2  RST_M_CD_CPU1_FPGA_N      B  @S9S_MB_2U_LIB.S9S_MB_2U(SCH_1):RST_M_CD_CPU1_FPGA_N

Q_RES  I22  R818   [Q_RES_0402LF-0,5%,1/16W,CHIP,CA]
    1  RST_PLD_CPU1_DRAM_EF_N      A  @S9S_MB_2U_LIB.S9S_MB_2U(SCH_1):RST_PLD_CPU1_DRAM_EF_N
    2  RST_M_EF_CPU1_FPGA_N      B  @S9S_MB_2U_LIB.S9S_MB_2U(SCH_1):RST_M_EF_CPU1_FPGA_N

Q_RES  I90  R819   [Q_RES_0402LF-1K,1%,1/16W,EMPTYA]
    2  RST_M_GH_CPU1_FPGA_N      B  @S9S_MB_2U_LIB.S9S_MB_2U(SCH_1):RST_M_GH_CPU1_FPGA_N
    1  PVCCD_HV_CPU1      A  @S9S_MB_2U_LIB.S9S_MB_2U(SCH_1):PVCCD_HV_CPU1

Q_RES  I82  R820   [Q_RES_0402LF-1K,1%,1/16W,EMPTYA]
    2  RST_M_AB_CPU1_FPGA_N      B  @S9S_MB_2U_LIB.S9S_MB_2U(SCH_1):RST_M_AB_CPU1_FPGA_N
    1  PVCCD_HV_CPU1      A  @S9S_MB_2U_LIB.S9S_MB_2U(SCH_1):PVCCD_HV_CPU1

Q_RES  I84  R821   [Q_RES_0402LF-1K,1%,1/16W,EMPTYA]
    2  RST_M_CD_CPU1_FPGA_N      B  @S9S_MB_2U_LIB.S9S_MB_2U(SCH_1):RST_M_CD_CPU1_FPGA_N
    1  PVCCD_HV_CPU1      A  @S9S_MB_2U_LIB.S9S_MB_2U(SCH_1):PVCCD_HV_CPU1

Q_RES  I88  R822   [Q_RES_0402LF-1K,1%,1/16W,EMPTYA]
    2  RST_M_EF_CPU1_FPGA_N      B  @S9S_MB_2U_LIB.S9S_MB_2U(SCH_1):RST_M_EF_CPU1_FPGA_N
    1  PVCCD_HV_CPU1      A  @S9S_MB_2U_LIB.S9S_MB_2U(SCH_1):PVCCD_HV_CPU1

Q_RES  I86  R835   [Q_RES_0402LF-0,5%,1/16W,CHIP,CA]
    1  RST_PLD_CPU0_DRAM_GH_N      A  @S9S_MB_2U_LIB.S9S_MB_2U(SCH_1):RST_PLD_CPU0_DRAM_GH_N
    2  RST_M_GH_CPU0_FPGA_N      B  @S9S_MB_2U_LIB.S9S_MB_2U(SCH_1):RST_M_GH_CPU0_FPGA_N

Q_RES  I26  R836   [Q_RES_0402LF-0,5%,1/16W,CHIP,CA]
    1  RST_PLD_CPU0_DRAM_AB_N      A  @S9S_MB_2U_LIB.S9S_MB_2U(SCH_1):RST_PLD_CPU0_DRAM_AB_N
    2  RST_M_AB_CPU0_FPGA_N      B  @S9S_MB_2U_LIB.S9S_MB_2U(SCH_1):RST_M_AB_CPU0_FPGA_N

Q_RES  I59  R837   [Q_RES_0402LF-0,5%,1/16W,CHIP,CA]
    1  RST_PLD_CPU0_DRAM_CD_N      A  @S9S_MB_2U_LIB.S9S_MB_2U(SCH_1):RST_PLD_CPU0_DRAM_CD_N
    2  RST_M_CD_CPU0_FPGA_N      B  @S9S_MB_2U_LIB.S9S_MB_2U(SCH_1):RST_M_CD_CPU0_FPGA_N

Q_RES  I76  R838   [Q_RES_0402LF-0,5%,1/16W,CHIP,CA]
    1  RST_PLD_CPU0_DRAM_EF_N      A  @S9S_MB_2U_LIB.S9S_MB_2U(SCH_1):RST_PLD_CPU0_DRAM_EF_N
    2  RST_M_EF_CPU0_FPGA_N      B  @S9S_MB_2U_LIB.S9S_MB_2U(SCH_1):RST_M_EF_CPU0_FPGA_N

Q_RES  I125  R839   [Q_RES_0402LF-1K,1%,1/16W,EMPTYA]
    2  RST_M_GH_CPU0_FPGA_N      B  @S9S_MB_2U_LIB.S9S_MB_2U(SCH_1):RST_M_GH_CPU0_FPGA_N
    1  PVCCD_HV_CPU0      A  @S9S_MB_2U_LIB.S9S_MB_2U(SCH_1):PVCCD_HV_CPU0

Q_RES  I119  R840   [Q_RES_0402LF-1K,1%,1/16W,EMPTYA]
    2  RST_M_AB_CPU0_FPGA_N      B  @S9S_MB_2U_LIB.S9S_MB_2U(SCH_1):RST_M_AB_CPU0_FPGA_N
    1  PVCCD_HV_CPU0      A  @S9S_MB_2U_LIB.S9S_MB_2U(SCH_1):PVCCD_HV_CPU0

Q_RES  I121  R841   [Q_RES_0402LF-1K,1%,1/16W,EMPTYA]
    2  RST_M_CD_CPU0_FPGA_N      B  @S9S_MB_2U_LIB.S9S_MB_2U(SCH_1):RST_M_CD_CPU0_FPGA_N
    1  PVCCD_HV_CPU0      A  @S9S_MB_2U_LIB.S9S_MB_2U(SCH_1):PVCCD_HV_CPU0

Q_RES  I123  R842   [Q_RES_0402LF-1K,1%,1/16W,EMPTYA]
    2  RST_M_EF_CPU0_FPGA_N      B  @S9S_MB_2U_LIB.S9S_MB_2U(SCH_1):RST_M_EF_CPU0_FPGA_N
    1  PVCCD_HV_CPU0      A  @S9S_MB_2U_LIB.S9S_MB_2U(SCH_1):PVCCD_HV_CPU0

Q_RES  I12  R851   [Q_RES_0402LF-0,5%,1/16W,CHIP,CA]
    2  RST_CPU0_DRAM_AB_PLD_N      B  @S9S_MB_2U_LIB.S9S_MB_2U(SCH_1):RST_CPU0_DRAM_AB_PLD_N
    1  RST_CPU0_DRAM_AB_N      A  @S9S_MB_2U_LIB.S9S_MB_2U(SCH_1):RST_CPU0_DRAM_AB_N

Q_RES  I11  R852   [Q_RES_0402LF-0,5%,1/16W,CHIP,CA]
    2  RST_CPU0_DRAM_CD_PLD_N      B  @S9S_MB_2U_LIB.S9S_MB_2U(SCH_1):RST_CPU0_DRAM_CD_PLD_N
    1  RST_CPU0_DRAM_CD_N      A  @S9S_MB_2U_LIB.S9S_MB_2U(SCH_1):RST_CPU0_DRAM_CD_N

Q_RES  I10  R853   [Q_RES_0402LF-0,5%,1/16W,CHIP,CA]
    2  RST_CPU0_DRAM_EF_PLD_N      B  @S9S_MB_2U_LIB.S9S_MB_2U(SCH_1):RST_CPU0_DRAM_EF_PLD_N
    1  RST_CPU0_DRAM_EF_N      A  @S9S_MB_2U_LIB.S9S_MB_2U(SCH_1):RST_CPU0_DRAM_EF_N

Q_RES  I9   R854   [Q_RES_0402LF-0,5%,1/16W,CHIP,CA]
    2  RST_CPU0_DRAM_GH_PLD_N      B  @S9S_MB_2U_LIB.S9S_MB_2U(SCH_1):RST_CPU0_DRAM_GH_PLD_N
    1  RST_CPU0_DRAM_GH_N      A  @S9S_MB_2U_LIB.S9S_MB_2U(SCH_1):RST_CPU0_DRAM_GH_N

Q_RES  I50  R859   [Q_RES_0402LF-0,5%,1/16W,CHIP,CA]
    2  RST_CPU1_DRAM_AB_PLD_N      B  @S9S_MB_2U_LIB.S9S_MB_2U(SCH_1):RST_CPU1_DRAM_AB_PLD_N
    1  RST_CPU1_DRAM_AB_N      A  @S9S_MB_2U_LIB.S9S_MB_2U(SCH_1):RST_CPU1_DRAM_AB_N

Q_RES  I51  R860   [Q_RES_0402LF-0,5%,1/16W,CHIP,CA]
    2  RST_CPU1_DRAM_CD_PLD_N      B  @S9S_MB_2U_LIB.S9S_MB_2U(SCH_1):RST_CPU1_DRAM_CD_PLD_N
    1  RST_CPU1_DRAM_CD_N      A  @S9S_MB_2U_LIB.S9S_MB_2U(SCH_1):RST_CPU1_DRAM_CD_N

Q_RES  I48  R861   [Q_RES_0402LF-0,5%,1/16W,CHIP,CA]
    2  RST_CPU1_DRAM_EF_PLD_N      B  @S9S_MB_2U_LIB.S9S_MB_2U(SCH_1):RST_CPU1_DRAM_EF_PLD_N
    1  RST_CPU1_DRAM_EF_N      A  @S9S_MB_2U_LIB.S9S_MB_2U(SCH_1):RST_CPU1_DRAM_EF_N

Q_RES  I49  R862   [Q_RES_0402LF-0,5%,1/16W,CHIP,CA]
    2  RST_CPU1_DRAM_GH_PLD_N      B  @S9S_MB_2U_LIB.S9S_MB_2U(SCH_1):RST_CPU1_DRAM_GH_PLD_N
    1  RST_CPU1_DRAM_GH_N      A  @S9S_MB_2U_LIB.S9S_MB_2U(SCH_1):RST_CPU1_DRAM_GH_N

Q_RES  I34  R877   [Q_RES_0402LF-33,5%,1/16W,CHIP,A]
    2  PWRGD_FAIL_CPU0_AB      B  @S9S_MB_2U_LIB.S9S_MB_2U(SCH_1):PWRGD_FAIL_CPU0_AB
    1  PWRGD_CHA_CPU0_DIMM1      A  @S9S_MB_2U_LIB.S9S_MB_2U(SCH_1):PWRGD_CHA_CPU0_DIMM1

Q_RES  I59  R878   [Q_RES_0402LF-33,5%,1/16W,CHIP,A]
    2  PWRGD_FAIL_CPU0_AB      B  @S9S_MB_2U_LIB.S9S_MB_2U(SCH_1):PWRGD_FAIL_CPU0_AB
    1  PWRGD_CHA_CPU0_DIMM2      A  @S9S_MB_2U_LIB.S9S_MB_2U(SCH_1):PWRGD_CHA_CPU0_DIMM2

Q_RES  I63  R879   [Q_RES_0402LF-33,5%,1/16W,CHIP,A]
    2  PWRGD_FAIL_CPU0_AB      B  @S9S_MB_2U_LIB.S9S_MB_2U(SCH_1):PWRGD_FAIL_CPU0_AB
    1  PWRGD_CHB_CPU0_DIMM1      A  @S9S_MB_2U_LIB.S9S_MB_2U(SCH_1):PWRGD_CHB_CPU0_DIMM1

Q_RES  I61  R880   [Q_RES_0402LF-33,5%,1/16W,CHIP,A]
    2  PWRGD_FAIL_CPU0_AB      B  @S9S_MB_2U_LIB.S9S_MB_2U(SCH_1):PWRGD_FAIL_CPU0_AB
    1  PWRGD_CHB_CPU0_DIMM2      A  @S9S_MB_2U_LIB.S9S_MB_2U(SCH_1):PWRGD_CHB_CPU0_DIMM2

Q_RES  I71  R881   [Q_RES_0402LF-33,5%,1/16W,CHIP,A]
    2  PWRGD_FAIL_CPU0_CD      B  @S9S_MB_2U_LIB.S9S_MB_2U(SCH_1):PWRGD_FAIL_CPU0_CD
    1  PWRGD_CHC_CPU0_DIMM1      A  @S9S_MB_2U_LIB.S9S_MB_2U(SCH_1):PWRGD_CHC_CPU0_DIMM1

Q_RES  I72  R882   [Q_RES_0402LF-33,5%,1/16W,CHIP,A]
    2  PWRGD_FAIL_CPU0_CD      B  @S9S_MB_2U_LIB.S9S_MB_2U(SCH_1):PWRGD_FAIL_CPU0_CD
    1  PWRGD_CHC_CPU0_DIMM2      A  @S9S_MB_2U_LIB.S9S_MB_2U(SCH_1):PWRGD_CHC_CPU0_DIMM2

Q_RES  I73  R883   [Q_RES_0402LF-33,5%,1/16W,CHIP,A]
    2  PWRGD_FAIL_CPU0_CD      B  @S9S_MB_2U_LIB.S9S_MB_2U(SCH_1):PWRGD_FAIL_CPU0_CD
    1  PWRGD_CHD_CPU0_DIMM1      A  @S9S_MB_2U_LIB.S9S_MB_2U(SCH_1):PWRGD_CHD_CPU0_DIMM1

Q_RES  I74  R884   [Q_RES_0402LF-33,5%,1/16W,CHIP,A]
    2  PWRGD_FAIL_CPU0_CD      B  @S9S_MB_2U_LIB.S9S_MB_2U(SCH_1):PWRGD_FAIL_CPU0_CD
    1  PWRGD_CHD_CPU0_DIMM2      A  @S9S_MB_2U_LIB.S9S_MB_2U(SCH_1):PWRGD_CHD_CPU0_DIMM2

Q_RES  I81  R885   [Q_RES_0402LF-33,5%,1/16W,CHIP,A]
    2  PWRGD_FAIL_CPU0_EF      B  @S9S_MB_2U_LIB.S9S_MB_2U(SCH_1):PWRGD_FAIL_CPU0_EF
    1  PWRGD_CHE_CPU0_DIMM1      A  @S9S_MB_2U_LIB.S9S_MB_2U(SCH_1):PWRGD_CHE_CPU0_DIMM1

Q_RES  I82  R886   [Q_RES_0402LF-33,5%,1/16W,CHIP,A]
    2  PWRGD_FAIL_CPU0_EF      B  @S9S_MB_2U_LIB.S9S_MB_2U(SCH_1):PWRGD_FAIL_CPU0_EF
    1  PWRGD_CHE_CPU0_DIMM2      A  @S9S_MB_2U_LIB.S9S_MB_2U(SCH_1):PWRGD_CHE_CPU0_DIMM2

Q_RES  I83  R887   [Q_RES_0402LF-33,5%,1/16W,CHIP,A]
    2  PWRGD_FAIL_CPU0_EF      B  @S9S_MB_2U_LIB.S9S_MB_2U(SCH_1):PWRGD_FAIL_CPU0_EF
    1  PWRGD_CHF_CPU0_DIMM1      A  @S9S_MB_2U_LIB.S9S_MB_2U(SCH_1):PWRGD_CHF_CPU0_DIMM1

Q_RES  I84  R888   [Q_RES_0402LF-33,5%,1/16W,CHIP,A]
    2  PWRGD_FAIL_CPU0_EF      B  @S9S_MB_2U_LIB.S9S_MB_2U(SCH_1):PWRGD_FAIL_CPU0_EF
    1  PWRGD_CHF_CPU0_DIMM2      A  @S9S_MB_2U_LIB.S9S_MB_2U(SCH_1):PWRGD_CHF_CPU0_DIMM2

Q_RES  I86  R889   [Q_RES_0402LF-33,5%,1/16W,CHIP,A]
    2  PWRGD_FAIL_CPU0_GH      B  @S9S_MB_2U_LIB.S9S_MB_2U(SCH_1):PWRGD_FAIL_CPU0_GH
    1  PWRGD_CHG_CPU0_DIMM1      A  @S9S_MB_2U_LIB.S9S_MB_2U(SCH_1):PWRGD_CHG_CPU0_DIMM1

Q_RES  I85  R890   [Q_RES_0402LF-33,5%,1/16W,CHIP,A]
    2  PWRGD_FAIL_CPU0_GH      B  @S9S_MB_2U_LIB.S9S_MB_2U(SCH_1):PWRGD_FAIL_CPU0_GH
    1  PWRGD_CHG_CPU0_DIMM2      A  @S9S_MB_2U_LIB.S9S_MB_2U(SCH_1):PWRGD_CHG_CPU0_DIMM2

Q_RES  I87  R891   [Q_RES_0402LF-33,5%,1/16W,CHIP,A]
    2  PWRGD_FAIL_CPU0_GH      B  @S9S_MB_2U_LIB.S9S_MB_2U(SCH_1):PWRGD_FAIL_CPU0_GH
    1  PWRGD_CHH_CPU0_DIMM1      A  @S9S_MB_2U_LIB.S9S_MB_2U(SCH_1):PWRGD_CHH_CPU0_DIMM1

Q_RES  I76  R892   [Q_RES_0402LF-33,5%,1/16W,CHIP,A]
    2  PWRGD_FAIL_CPU0_GH      B  @S9S_MB_2U_LIB.S9S_MB_2U(SCH_1):PWRGD_FAIL_CPU0_GH
    1  PWRGD_CHH_CPU0_DIMM2      A  @S9S_MB_2U_LIB.S9S_MB_2U(SCH_1):PWRGD_CHH_CPU0_DIMM2

Q_RES  I104  R893   [Q_RES_0402LF-33,5%,1/16W,CHIP,A]
    2  PWRGD_FAIL_CPU1_AB      B  @S9S_MB_2U_LIB.S9S_MB_2U(SCH_1):PWRGD_FAIL_CPU1_AB
    1  PWRGD_CHA_CPU1_DIMM1      A  @S9S_MB_2U_LIB.S9S_MB_2U(SCH_1):PWRGD_CHA_CPU1_DIMM1

Q_RES  I105  R894   [Q_RES_0402LF-33,5%,1/16W,CHIP,A]
    2  PWRGD_FAIL_CPU1_AB      B  @S9S_MB_2U_LIB.S9S_MB_2U(SCH_1):PWRGD_FAIL_CPU1_AB
    1  PWRGD_CHA_CPU1_DIMM2      A  @S9S_MB_2U_LIB.S9S_MB_2U(SCH_1):PWRGD_CHA_CPU1_DIMM2

Q_RES  I106  R895   [Q_RES_0402LF-33,5%,1/16W,CHIP,A]
    2  PWRGD_FAIL_CPU1_AB      B  @S9S_MB_2U_LIB.S9S_MB_2U(SCH_1):PWRGD_FAIL_CPU1_AB
    1  PWRGD_CHB_CPU1_DIMM1      A  @S9S_MB_2U_LIB.S9S_MB_2U(SCH_1):PWRGD_CHB_CPU1_DIMM1

Q_RES  I107  R896   [Q_RES_0402LF-33,5%,1/16W,CHIP,A]
    2  PWRGD_FAIL_CPU1_AB      B  @S9S_MB_2U_LIB.S9S_MB_2U(SCH_1):PWRGD_FAIL_CPU1_AB
    1  PWRGD_CHB_CPU1_DIMM2      A  @S9S_MB_2U_LIB.S9S_MB_2U(SCH_1):PWRGD_CHB_CPU1_DIMM2

Q_RES  I109  R897   [Q_RES_0402LF-33,5%,1/16W,CHIP,A]
    2  PWRGD_FAIL_CPU1_CD      B  @S9S_MB_2U_LIB.S9S_MB_2U(SCH_1):PWRGD_FAIL_CPU1_CD
    1  PWRGD_CHC_CPU1_DIMM1      A  @S9S_MB_2U_LIB.S9S_MB_2U(SCH_1):PWRGD_CHC_CPU1_DIMM1

Q_RES  I108  R898   [Q_RES_0402LF-33,5%,1/16W,CHIP,A]
    2  PWRGD_FAIL_CPU1_CD      B  @S9S_MB_2U_LIB.S9S_MB_2U(SCH_1):PWRGD_FAIL_CPU1_CD
    1  PWRGD_CHC_CPU1_DIMM2      A  @S9S_MB_2U_LIB.S9S_MB_2U(SCH_1):PWRGD_CHC_CPU1_DIMM2

Q_RES  I110  R899   [Q_RES_0402LF-33,5%,1/16W,CHIP,A]
    2  PWRGD_FAIL_CPU1_CD      B  @S9S_MB_2U_LIB.S9S_MB_2U(SCH_1):PWRGD_FAIL_CPU1_CD
    1  PWRGD_CHD_CPU1_DIMM1      A  @S9S_MB_2U_LIB.S9S_MB_2U(SCH_1):PWRGD_CHD_CPU1_DIMM1

Q_RES  I111  R900   [Q_RES_0402LF-33,5%,1/16W,CHIP,A]
    2  PWRGD_FAIL_CPU1_CD      B  @S9S_MB_2U_LIB.S9S_MB_2U(SCH_1):PWRGD_FAIL_CPU1_CD
    1  PWRGD_CHD_CPU1_DIMM2      A  @S9S_MB_2U_LIB.S9S_MB_2U(SCH_1):PWRGD_CHD_CPU1_DIMM2

Q_RES  I112  R901   [Q_RES_0402LF-33,5%,1/16W,CHIP,A]
    2  PWRGD_FAIL_CPU1_EF      B  @S9S_MB_2U_LIB.S9S_MB_2U(SCH_1):PWRGD_FAIL_CPU1_EF
    1  PWRGD_CHE_CPU1_DIMM1      A  @S9S_MB_2U_LIB.S9S_MB_2U(SCH_1):PWRGD_CHE_CPU1_DIMM1

Q_RES  I113  R902   [Q_RES_0402LF-33,5%,1/16W,CHIP,A]
    2  PWRGD_FAIL_CPU1_EF      B  @S9S_MB_2U_LIB.S9S_MB_2U(SCH_1):PWRGD_FAIL_CPU1_EF
    1  PWRGD_CHE_CPU1_DIMM2      A  @S9S_MB_2U_LIB.S9S_MB_2U(SCH_1):PWRGD_CHE_CPU1_DIMM2

Q_RES  I114  R903   [Q_RES_0402LF-33,5%,1/16W,CHIP,A]
    2  PWRGD_FAIL_CPU1_EF      B  @S9S_MB_2U_LIB.S9S_MB_2U(SCH_1):PWRGD_FAIL_CPU1_EF
    1  PWRGD_CHF_CPU1_DIMM1      A  @S9S_MB_2U_LIB.S9S_MB_2U(SCH_1):PWRGD_CHF_CPU1_DIMM1

Q_RES  I115  R904   [Q_RES_0402LF-33,5%,1/16W,CHIP,A]
    2  PWRGD_FAIL_CPU1_EF      B  @S9S_MB_2U_LIB.S9S_MB_2U(SCH_1):PWRGD_FAIL_CPU1_EF
    1  PWRGD_CHF_CPU1_DIMM2      A  @S9S_MB_2U_LIB.S9S_MB_2U(SCH_1):PWRGD_CHF_CPU1_DIMM2

Q_RES  I116  R905   [Q_RES_0402LF-33,5%,1/16W,CHIP,A]
    2  PWRGD_FAIL_CPU1_GH      B  @S9S_MB_2U_LIB.S9S_MB_2U(SCH_1):PWRGD_FAIL_CPU1_GH
    1  PWRGD_CHG_CPU1_DIMM1      A  @S9S_MB_2U_LIB.S9S_MB_2U(SCH_1):PWRGD_CHG_CPU1_DIMM1

Q_RES  I117  R906   [Q_RES_0402LF-33,5%,1/16W,CHIP,A]
    2  PWRGD_FAIL_CPU1_GH      B  @S9S_MB_2U_LIB.S9S_MB_2U(SCH_1):PWRGD_FAIL_CPU1_GH
    1  PWRGD_CHG_CPU1_DIMM2      A  @S9S_MB_2U_LIB.S9S_MB_2U(SCH_1):PWRGD_CHG_CPU1_DIMM2

Q_RES  I118  R907   [Q_RES_0402LF-33,5%,1/16W,CHIP,A]
    2  PWRGD_FAIL_CPU1_GH      B  @S9S_MB_2U_LIB.S9S_MB_2U(SCH_1):PWRGD_FAIL_CPU1_GH
    1  PWRGD_CHH_CPU1_DIMM1      A  @S9S_MB_2U_LIB.S9S_MB_2U(SCH_1):PWRGD_CHH_CPU1_DIMM1

Q_RES  I119  R908   [Q_RES_0402LF-33,5%,1/16W,CHIP,A]
    2  PWRGD_FAIL_CPU1_GH      B  @S9S_MB_2U_LIB.S9S_MB_2U(SCH_1):PWRGD_FAIL_CPU1_GH
    1  PWRGD_CHH_CPU1_DIMM2      A  @S9S_MB_2U_LIB.S9S_MB_2U(SCH_1):PWRGD_CHH_CPU1_DIMM2

Q_RES  I26  R909   [Q_RES_0402LF-33.2,1%,1/16W,CHIA]
    1  SMB_PEHPCPU0_GTL_SDA      A  @S9S_MB_2U_LIB.S9S_MB_2U(SCH_1):SMB_PEHPCPU0_GTL_SDA
    2  SMB_PEHPCPU0_GTL_R_SDA      B  @S9S_MB_2U_LIB.S9S_MB_2U(SCH_1):SMB_PEHPCPU0_GTL_R_SDA

Q_RES  I24  R910   [Q_RES_0402LF-240,1%,1/16W,CHIPA]
    2  SMB_PEHPCPU0_GTL_R_SCL      B  @S9S_MB_2U_LIB.S9S_MB_2U(SCH_1):SMB_PEHPCPU0_GTL_R_SCL
    1  PVNN_TERM_CPU0      A  @S9S_MB_2U_LIB.S9S_MB_2U(SCH_1):PVNN_TERM_CPU0

Q_RES  I22  R911   [Q_RES_0402LF-240,1%,1/16W,CHIPA]
    2  SMB_PEHPCPU0_GTL_R_SDA      B  @S9S_MB_2U_LIB.S9S_MB_2U(SCH_1):SMB_PEHPCPU0_GTL_R_SDA
    1  PVNN_TERM_CPU0      A  @S9S_MB_2U_LIB.S9S_MB_2U(SCH_1):PVNN_TERM_CPU0

Q_RES  I278  R912   [Q_RES_0402LF-4.75K,1%,1/16W,EMA]
    1  P3V3_AUX           A  @S9S_MB_2U_LIB.S9S_MB_2U(SCH_1):P3V3_AUX
    2  CLK_CK440_SMB_ADDR0      B  @S9S_MB_2U_LIB.S9S_MB_2U(SCH_1):CLK_CK440_SMB_ADDR0

Q_RES  I241  R913   [Q_RES_0402LF-10K,1%,1/16W,CHIPA]
    1  PU_OC6_USB_N       A  @S9S_MB_2U_LIB.S9S_MB_2U(SCH_1):PU_OC6_USB_N
    2  P3V3_AUX           B  @S9S_MB_2U_LIB.S9S_MB_2U(SCH_1):P3V3_AUX

Q_RES  I162  R914   [Q_RES_0402LF-2.2K ,5%,1/16W,CHA]
    2  SMB_PCIE1_3V3AUX_SCL      B  @S9S_MB_2U_LIB.S9S_MB_2U(SCH_1):SMB_PCIE1_3V3AUX_SCL
    1  P3V3_AUX           A  @S9S_MB_2U_LIB.S9S_MB_2U(SCH_1):P3V3_AUX

Q_RES  I103  R915   [Q_RES_0402LF-33.2,1%,1/16W,CHIA]
    2  SPI_SYS_MOSI       B  @S9S_MB_2U_LIB.S9S_MB_2U(SCH_1):SPI_SYS_MOSI
    1  SPI_PCH_IO0        A  @S9S_MB_2U_LIB.S9S_MB_2U(SCH_1):SPI_PCH_IO0

Q_RES  I105  R916   [Q_RES_0402LF-33.2,1%,1/16W,CHIA]
    2  SPI_SYS_MISO       B  @S9S_MB_2U_LIB.S9S_MB_2U(SCH_1):SPI_SYS_MISO
    1  SPI_PCH_IO1        A  @S9S_MB_2U_LIB.S9S_MB_2U(SCH_1):SPI_PCH_IO1

Q_RES  I107  R917   [Q_RES_0402LF-33.2,1%,1/16W,CHIA]
    2  SPI_SYS_HOLD_IO3      B  @S9S_MB_2U_LIB.S9S_MB_2U(SCH_1):SPI_SYS_HOLD_IO3
    1  SPI_PCH_IO3        A  @S9S_MB_2U_LIB.S9S_MB_2U(SCH_1):SPI_PCH_IO3

Q_RES  I104  R918   [Q_RES_0402LF-33.2,1%,1/16W,CHIA]
    2  SPI_SYS_WP_IO2      B  @S9S_MB_2U_LIB.S9S_MB_2U(SCH_1):SPI_SYS_WP_IO2
    1  SPI_PCH_IO2        A  @S9S_MB_2U_LIB.S9S_MB_2U(SCH_1):SPI_PCH_IO2

Q_RES  I75  R919   [Q_RES_0402LF-10K,1%,1/16W,CHIPA]
    1  P3V3_AUX           A  @S9S_MB_2U_LIB.S9S_MB_2U(SCH_1):P3V3_AUX
    2  JTAG_PLD_JTAGEN      B  @S9S_MB_2U_LIB.S9S_MB_2U(SCH_1):JTAG_PLD_JTAGEN

Q_RES  I76  R920   [Q_RES_0402LF-1K,5%,1/16W,EMPTYA]
    1  JTAG_PLD_JTAGEN      A  @S9S_MB_2U_LIB.S9S_MB_2U(SCH_1):JTAG_PLD_JTAGEN
    2  GND                B  @S9S_MB_2U_LIB.S9S_MB_2U(SCH_1):GND

Q_RES  I118  R923   [Q_RES_0402LF-33.2,1%,1/16W,CHIA]
    2  OCP_SFF_AUX_PWR_EN_R2      B  @S9S_MB_2U_LIB.S9S_MB_2U(SCH_1):OCP_SFF_AUX_PWR_EN_R2
    1  OCP_SFF_AUX_PWR_EN      A  @S9S_MB_2U_LIB.S9S_MB_2U(SCH_1):OCP_SFF_AUX_PWR_EN

Q_RES  I61  R927   [Q_RES_0402LF-10K,1%,1/16W,CHIPA]
    1  P3V3_AUX           A  @S9S_MB_2U_LIB.S9S_MB_2U(SCH_1):P3V3_AUX
    2  JTAG_BMC_PLD_TDI      B  @S9S_MB_2U_LIB.S9S_MB_2U(SCH_1):JTAG_BMC_PLD_TDI

Q_RES  I60  R928   [Q_RES_0402LF-10K,1%,1/16W,CHIPA]
    1  P3V3_AUX           A  @S9S_MB_2U_LIB.S9S_MB_2U(SCH_1):P3V3_AUX
    2  JTAG_BMC_PLD_TDO      B  @S9S_MB_2U_LIB.S9S_MB_2U(SCH_1):JTAG_BMC_PLD_TDO

Q_RES  I59  R929   [Q_RES_0402LF-10K,1%,1/16W,CHIPA]
    1  P3V3_AUX           A  @S9S_MB_2U_LIB.S9S_MB_2U(SCH_1):P3V3_AUX
    2  JTAG_BMC_PLD_TMS      B  @S9S_MB_2U_LIB.S9S_MB_2U(SCH_1):JTAG_BMC_PLD_TMS

Q_RES  I63  R930   [Q_RES_0402LF-4.7K,1%,1/16W,CHIA]
    1  JTAG_BMC_PLD_TCK      A  @S9S_MB_2U_LIB.S9S_MB_2U(SCH_1):JTAG_BMC_PLD_TCK
    2  GND                B  @S9S_MB_2U_LIB.S9S_MB_2U(SCH_1):GND

Q_RES  I48  R931   [Q_RES_0402LF-0,5%,1/16W,CHIP,CA]
    2  JTAG_PLD_JTAGEN_R      B  @S9S_MB_2U_LIB.S9S_MB_2U(SCH_1):JTAG_PLD_JTAGEN_R
    1  JTAG_PLD_JTAGEN      A  @S9S_MB_2U_LIB.S9S_MB_2U(SCH_1):JTAG_PLD_JTAGEN

Q_RES  I80  R932   [Q_RES_0402LF-10K,1%,1/16W,CHIPA]
    1  RST_CPU0_DRAM_AB_N      A  @S9S_MB_2U_LIB.S9S_MB_2U(SCH_1):RST_CPU0_DRAM_AB_N
    2  GND                B  @S9S_MB_2U_LIB.S9S_MB_2U(SCH_1):GND

Q_RES  I82  R933   [Q_RES_0402LF-10K,1%,1/16W,CHIPA]
    1  RST_CPU1_DRAM_AB_N      A  @S9S_MB_2U_LIB.S9S_MB_2U(SCH_1):RST_CPU1_DRAM_AB_N
    2  GND                B  @S9S_MB_2U_LIB.S9S_MB_2U(SCH_1):GND

Q_RES  I79  R934   [Q_RES_0402LF-10K,1%,1/16W,CHIPA]
    1  RST_CPU0_DRAM_CD_N      A  @S9S_MB_2U_LIB.S9S_MB_2U(SCH_1):RST_CPU0_DRAM_CD_N
    2  GND                B  @S9S_MB_2U_LIB.S9S_MB_2U(SCH_1):GND

Q_RES  I86  R935   [Q_RES_0402LF-10K,1%,1/16W,CHIPA]
    1  RST_CPU1_DRAM_CD_N      A  @S9S_MB_2U_LIB.S9S_MB_2U(SCH_1):RST_CPU1_DRAM_CD_N
    2  GND                B  @S9S_MB_2U_LIB.S9S_MB_2U(SCH_1):GND

Q_RES  I78  R936   [Q_RES_0402LF-10K,1%,1/16W,CHIPA]
    1  RST_CPU0_DRAM_EF_N      A  @S9S_MB_2U_LIB.S9S_MB_2U(SCH_1):RST_CPU0_DRAM_EF_N
    2  GND                B  @S9S_MB_2U_LIB.S9S_MB_2U(SCH_1):GND

Q_RES  I85  R937   [Q_RES_0402LF-10K,1%,1/16W,CHIPA]
    1  RST_CPU1_DRAM_EF_N      A  @S9S_MB_2U_LIB.S9S_MB_2U(SCH_1):RST_CPU1_DRAM_EF_N
    2  GND                B  @S9S_MB_2U_LIB.S9S_MB_2U(SCH_1):GND

Q_RES  I77  R938   [Q_RES_0402LF-10K,1%,1/16W,CHIPA]
    1  RST_CPU0_DRAM_GH_N      A  @S9S_MB_2U_LIB.S9S_MB_2U(SCH_1):RST_CPU0_DRAM_GH_N
    2  GND                B  @S9S_MB_2U_LIB.S9S_MB_2U(SCH_1):GND

Q_RES  I83  R939   [Q_RES_0402LF-10K,1%,1/16W,CHIPA]
    1  RST_CPU1_DRAM_GH_N      A  @S9S_MB_2U_LIB.S9S_MB_2U(SCH_1):RST_CPU1_DRAM_GH_N
    2  GND                B  @S9S_MB_2U_LIB.S9S_MB_2U(SCH_1):GND

Q_RES  I145  R940   [Q_RES_0402LF-1K,1%,1/16W,CHIP,A]
    2  PWRGD_FAIL_CPU0_AB      B  @S9S_MB_2U_LIB.S9S_MB_2U(SCH_1):PWRGD_FAIL_CPU0_AB
    1  P3V3_AUX           A  @S9S_MB_2U_LIB.S9S_MB_2U(SCH_1):P3V3_AUX

Q_RES  I146  R941   [Q_RES_0402LF-1K,1%,1/16W,CHIP,A]
    2  PWRGD_FAIL_CPU0_CD      B  @S9S_MB_2U_LIB.S9S_MB_2U(SCH_1):PWRGD_FAIL_CPU0_CD
    1  P3V3_AUX           A  @S9S_MB_2U_LIB.S9S_MB_2U(SCH_1):P3V3_AUX

Q_RES  I147  R942   [Q_RES_0402LF-1K,1%,1/16W,CHIP,A]
    2  PWRGD_FAIL_CPU0_EF      B  @S9S_MB_2U_LIB.S9S_MB_2U(SCH_1):PWRGD_FAIL_CPU0_EF
    1  P3V3_AUX           A  @S9S_MB_2U_LIB.S9S_MB_2U(SCH_1):P3V3_AUX

Q_RES  I148  R943   [Q_RES_0402LF-1K,1%,1/16W,CHIP,A]
    2  PWRGD_FAIL_CPU0_GH      B  @S9S_MB_2U_LIB.S9S_MB_2U(SCH_1):PWRGD_FAIL_CPU0_GH
    1  P3V3_AUX           A  @S9S_MB_2U_LIB.S9S_MB_2U(SCH_1):P3V3_AUX

Q_RES  I153  R944   [Q_RES_0402LF-1K,1%,1/16W,CHIP,A]
    2  PWRGD_FAIL_CPU1_AB      B  @S9S_MB_2U_LIB.S9S_MB_2U(SCH_1):PWRGD_FAIL_CPU1_AB
    1  P3V3_AUX           A  @S9S_MB_2U_LIB.S9S_MB_2U(SCH_1):P3V3_AUX

Q_RES  I154  R945   [Q_RES_0402LF-1K,1%,1/16W,CHIP,A]
    2  PWRGD_FAIL_CPU1_CD      B  @S9S_MB_2U_LIB.S9S_MB_2U(SCH_1):PWRGD_FAIL_CPU1_CD
    1  P3V3_AUX           A  @S9S_MB_2U_LIB.S9S_MB_2U(SCH_1):P3V3_AUX

Q_RES  I156  R946   [Q_RES_0402LF-1K,1%,1/16W,CHIP,A]
    2  PWRGD_FAIL_CPU1_EF      B  @S9S_MB_2U_LIB.S9S_MB_2U(SCH_1):PWRGD_FAIL_CPU1_EF
    1  P3V3_AUX           A  @S9S_MB_2U_LIB.S9S_MB_2U(SCH_1):P3V3_AUX

Q_RES  I157  R947   [Q_RES_0402LF-1K,1%,1/16W,CHIP,A]
    2  PWRGD_FAIL_CPU1_GH      B  @S9S_MB_2U_LIB.S9S_MB_2U(SCH_1):PWRGD_FAIL_CPU1_GH
    1  P3V3_AUX           A  @S9S_MB_2U_LIB.S9S_MB_2U(SCH_1):P3V3_AUX

Q_RES  I206  R948   [Q_RES_0402LF-0,5%,1/16W,CHIP,CA]
    1  IRQ_PDB_R_N        A  @S9S_MB_2U_LIB.S9S_MB_2U(SCH_1):IRQ_PDB_R_N
    2  FM_UV_ADR_TRIGGER_N      B  @S9S_MB_2U_LIB.S9S_MB_2U(SCH_1):FM_UV_ADR_TRIGGER_N

Q_RES  I178  R951   [Q_RES_0402LF-0,5%,1/16W,CHIP,CA]
    2  IRQ_SML1_PMBUS_ALERT_R_N      B  @S9S_MB_2U_LIB.S9S_MB_2U(SCH_1):IRQ_SML1_PMBUS_ALERT_R_N
    1  IRQ_SML1_PMBUS_ALERT_N      A  @S9S_MB_2U_LIB.S9S_MB_2U(SCH_1):IRQ_SML1_PMBUS_ALERT_N

Q_RES  I201  R952   [Q_RES_0402LF-4.7K,1%,1/16W,EMPA]
    1  P3V3_AUX           A  @S9S_MB_2U_LIB.S9S_MB_2U(SCH_1):P3V3_AUX
    2  IRQ_PDB_R_N        B  @S9S_MB_2U_LIB.S9S_MB_2U(SCH_1):IRQ_PDB_R_N

Q_RES  I282  R953   [Q_RES_0402LF-4.75K,1%,1/16W,CHA]
    2  GND                B  @S9S_MB_2U_LIB.S9S_MB_2U(SCH_1):GND
    1  CLK_CK440_SMB_ADDR0      A  @S9S_MB_2U_LIB.S9S_MB_2U(SCH_1):CLK_CK440_SMB_ADDR0

Q_RES  I208  R955   [Q_RES_0402LF-33,5%,1/16W,CHIP,A]
    2  PWRGD_PS_PWROK_PLD      B  @S9S_MB_2U_LIB.S9S_MB_2U(SCH_1):PWRGD_PS_PWROK_PLD
    1  PWRGD_HSC_P12V_PWROK      A  @S9S_MB_2U_LIB.S9S_MB_2U(SCH_1):PWRGD_HSC_P12V_PWROK

Q_RES  I25  R960   [Q_RES_0402LF-33.2,1%,1/16W,CHIA]
    1  SMB_PEHPCPU0_GTL_SCL      A  @S9S_MB_2U_LIB.S9S_MB_2U(SCH_1):SMB_PEHPCPU0_GTL_SCL
    2  SMB_PEHPCPU0_GTL_R_SCL      B  @S9S_MB_2U_LIB.S9S_MB_2U(SCH_1):SMB_PEHPCPU0_GTL_R_SCL

Q_RES  I49  R961   [Q_RES_0402LF-33.2,1%,1/16W,CHIA]
    1  SMB_PEHPCPU1_GTL_SCL      A  @S9S_MB_2U_LIB.S9S_MB_2U(SCH_1):SMB_PEHPCPU1_GTL_SCL
    2  SMB_PEHPCPU1_GTL_R_SCL      B  @S9S_MB_2U_LIB.S9S_MB_2U(SCH_1):SMB_PEHPCPU1_GTL_R_SCL

Q_RES  I50  R962   [Q_RES_0402LF-33.2,1%,1/16W,CHIA]
    1  SMB_PEHPCPU1_GTL_SDA      A  @S9S_MB_2U_LIB.S9S_MB_2U(SCH_1):SMB_PEHPCPU1_GTL_SDA
    2  SMB_PEHPCPU1_GTL_R_SDA      B  @S9S_MB_2U_LIB.S9S_MB_2U(SCH_1):SMB_PEHPCPU1_GTL_R_SDA

Q_RES  I48  R963   [Q_RES_0402LF-240,1%,1/16W,CHIPA]
    2  SMB_PEHPCPU1_GTL_R_SCL      B  @S9S_MB_2U_LIB.S9S_MB_2U(SCH_1):SMB_PEHPCPU1_GTL_R_SCL
    1  PVNN_TERM_CPU1      A  @S9S_MB_2U_LIB.S9S_MB_2U(SCH_1):PVNN_TERM_CPU1

Q_RES  I46  R964   [Q_RES_0402LF-240,1%,1/16W,CHIPA]
    2  SMB_PEHPCPU1_GTL_R_SDA      B  @S9S_MB_2U_LIB.S9S_MB_2U(SCH_1):SMB_PEHPCPU1_GTL_R_SDA
    1  PVNN_TERM_CPU1      A  @S9S_MB_2U_LIB.S9S_MB_2U(SCH_1):PVNN_TERM_CPU1

Q_RES  I15  R965   [Q_RES_0402LF-1K,1%,1/16W,CHIP,A]
    2  SMB_PEHPCPU0_LVC3_SCL      B  @S9S_MB_2U_LIB.S9S_MB_2U(SCH_1):SMB_PEHPCPU0_LVC3_SCL
    1  P3V3_AUX           A  @S9S_MB_2U_LIB.S9S_MB_2U(SCH_1):P3V3_AUX

Q_RES  I29  R966   [Q_RES_0402LF-1K,1%,1/16W,CHIP,A]
    2  SMB_PEHPCPU1_LVC3_SCL      B  @S9S_MB_2U_LIB.S9S_MB_2U(SCH_1):SMB_PEHPCPU1_LVC3_SCL
    1  P3V3_AUX           A  @S9S_MB_2U_LIB.S9S_MB_2U(SCH_1):P3V3_AUX

Q_RES  I14  R967   [Q_RES_0402LF-1K,1%,1/16W,CHIP,A]
    2  SMB_PEHPCPU0_LVC3_SDA      B  @S9S_MB_2U_LIB.S9S_MB_2U(SCH_1):SMB_PEHPCPU0_LVC3_SDA
    1  P3V3_AUX           A  @S9S_MB_2U_LIB.S9S_MB_2U(SCH_1):P3V3_AUX

Q_RES  I27  R968   [Q_RES_0402LF-1K,1%,1/16W,CHIP,A]
    2  SMB_PEHPCPU1_LVC3_SDA      B  @S9S_MB_2U_LIB.S9S_MB_2U(SCH_1):SMB_PEHPCPU1_LVC3_SDA
    1  P3V3_AUX           A  @S9S_MB_2U_LIB.S9S_MB_2U(SCH_1):P3V3_AUX

Q_RES  I43  R969   [Q_RES_0402LF-240,1%,1/16W,CHIPA]
    2  SMB_S3M_CPU0_R_SCL      B  @S9S_MB_2U_LIB.S9S_MB_2U(SCH_1):SMB_S3M_CPU0_R_SCL
    1  PVNN_TERM_CPU0      A  @S9S_MB_2U_LIB.S9S_MB_2U(SCH_1):PVNN_TERM_CPU0

Q_RES  I50  R970   [Q_RES_0402LF-240,1%,1/16W,CHIPA]
    2  SMB_S3M_CPU1_R_SCL      B  @S9S_MB_2U_LIB.S9S_MB_2U(SCH_1):SMB_S3M_CPU1_R_SCL
    1  PVNN_TERM_CPU1      A  @S9S_MB_2U_LIB.S9S_MB_2U(SCH_1):PVNN_TERM_CPU1

Q_RES  I42  R971   [Q_RES_0402LF-240,1%,1/16W,CHIPA]
    2  SMB_S3M_CPU0_R_SDA      B  @S9S_MB_2U_LIB.S9S_MB_2U(SCH_1):SMB_S3M_CPU0_R_SDA
    1  PVNN_TERM_CPU0      A  @S9S_MB_2U_LIB.S9S_MB_2U(SCH_1):PVNN_TERM_CPU0

Q_RES  I49  R972   [Q_RES_0402LF-240,1%,1/16W,CHIPA]
    2  SMB_S3M_CPU1_R_SDA      B  @S9S_MB_2U_LIB.S9S_MB_2U(SCH_1):SMB_S3M_CPU1_R_SDA
    1  PVNN_TERM_CPU1      A  @S9S_MB_2U_LIB.S9S_MB_2U(SCH_1):PVNN_TERM_CPU1

Q_RES  I27  R973   [Q_RES_0402LF-33.2,1%,1/16W,CHIA]
    1  SMB_S3M_CPU0_R_SCL      A  @S9S_MB_2U_LIB.S9S_MB_2U(SCH_1):SMB_S3M_CPU0_R_SCL
    2  SMB_S3M_CPU0_LVC1_SCL      B  @S9S_MB_2U_LIB.S9S_MB_2U(SCH_1):SMB_S3M_CPU0_LVC1_SCL

Q_RES  I30  R974   [Q_RES_0402LF-33.2,1%,1/16W,CHIA]
    1  SMB_S3M_CPU0_R_SDA      A  @S9S_MB_2U_LIB.S9S_MB_2U(SCH_1):SMB_S3M_CPU0_R_SDA
    2  SMB_S3M_CPU0_LVC1_SDA      B  @S9S_MB_2U_LIB.S9S_MB_2U(SCH_1):SMB_S3M_CPU0_LVC1_SDA

Q_RES  I39  R975   [Q_RES_0402LF-33.2,1%,1/16W,CHIA]
    1  SMB_S3M_CPU1_R_SCL      A  @S9S_MB_2U_LIB.S9S_MB_2U(SCH_1):SMB_S3M_CPU1_R_SCL
    2  SMB_S3M_CPU1_LVC1_SCL      B  @S9S_MB_2U_LIB.S9S_MB_2U(SCH_1):SMB_S3M_CPU1_LVC1_SCL

Q_RES  I40  R976   [Q_RES_0402LF-33.2,1%,1/16W,CHIA]
    1  SMB_S3M_CPU1_R_SDA      A  @S9S_MB_2U_LIB.S9S_MB_2U(SCH_1):SMB_S3M_CPU1_R_SDA
    2  SMB_S3M_CPU1_LVC1_SDA      B  @S9S_MB_2U_LIB.S9S_MB_2U(SCH_1):SMB_S3M_CPU1_LVC1_SDA

Q_RES  I8   R977   [Q_RES_0402LF-412,1%,1/16W,CHIPA]
    2  SMB_S3M_CPU0_3V3AUX_SCL      B  @S9S_MB_2U_LIB.S9S_MB_2U(SCH_1):SMB_S3M_CPU0_3V3AUX_SCL
    1  P3V3_AUX           A  @S9S_MB_2U_LIB.S9S_MB_2U(SCH_1):P3V3_AUX

Q_RES  I16  R978   [Q_RES_0402LF-412,1%,1/16W,CHIPA]
    2  SMB_S3M_CPU1_3V3AUX_SCL      B  @S9S_MB_2U_LIB.S9S_MB_2U(SCH_1):SMB_S3M_CPU1_3V3AUX_SCL
    1  P3V3_AUX           A  @S9S_MB_2U_LIB.S9S_MB_2U(SCH_1):P3V3_AUX

Q_RES  I6   R979   [Q_RES_0402LF-412,1%,1/16W,CHIPA]
    2  SMB_S3M_CPU0_3V3AUX_SDA      B  @S9S_MB_2U_LIB.S9S_MB_2U(SCH_1):SMB_S3M_CPU0_3V3AUX_SDA
    1  P3V3_AUX           A  @S9S_MB_2U_LIB.S9S_MB_2U(SCH_1):P3V3_AUX

Q_RES  I14  R980   [Q_RES_0402LF-412,1%,1/16W,CHIPA]
    2  SMB_S3M_CPU1_3V3AUX_SDA      B  @S9S_MB_2U_LIB.S9S_MB_2U(SCH_1):SMB_S3M_CPU1_3V3AUX_SDA
    1  P3V3_AUX           A  @S9S_MB_2U_LIB.S9S_MB_2U(SCH_1):P3V3_AUX

Q_RES  I9   R981   [Q_RES_0402LF-33,5%,1/16W,CHIP,A]
    1  FM_PVCCIN_CPU0_R_EN      A  @S9S_MB_2U_LIB.S9S_MB_2U(SCH_1):FM_PVCCIN_CPU0_R_EN
    2  FM_PVCCIN_CPU0_EN      B  @S9S_MB_2U_LIB.S9S_MB_2U(SCH_1):FM_PVCCIN_CPU0_EN

Q_RES  I10  R982   [Q_RES_0402LF-33,5%,1/16W,CHIP,A]
    1  FM_PVCCFA_EHV_CPU0_R_EN      A  @S9S_MB_2U_LIB.S9S_MB_2U(SCH_1):FM_PVCCFA_EHV_CPU0_R_EN
    2  FM_PVCCFA_EHV_CPU0_EN      B  @S9S_MB_2U_LIB.S9S_MB_2U(SCH_1):FM_PVCCFA_EHV_CPU0_EN

Q_RES  I13  R983   [Q_RES_0402LF-33,5%,1/16W,CHIP,A]
    1  FM_PVCCINFAON_CPU0_R_EN      A  @S9S_MB_2U_LIB.S9S_MB_2U(SCH_1):FM_PVCCINFAON_CPU0_R_EN
    2  FM_PVCCINFAON_CPU0_EN      B  @S9S_MB_2U_LIB.S9S_MB_2U(SCH_1):FM_PVCCINFAON_CPU0_EN

Q_RES  I15  R984   [Q_RES_0402LF-33,5%,1/16W,CHIP,A]
    1  FM_PVCCFA_EHV_FIVRA_CPU0_R_EN      A  @S9S_MB_2U_LIB.S9S_MB_2U(SCH_1):FM_PVCCFA_EHV_FIVRA_CPU0_R_EN
    2  FM_PVCCFA_EHV_FIVRA_CPU0_EN      B  @S9S_MB_2U_LIB.S9S_MB_2U(SCH_1):FM_PVCCFA_EHV_FIVRA_CPU0_EN

Q_RES  I21  R985   [Q_RES_0402LF-33,5%,1/16W,CHIP,A]
    1  FM_PVCCIN_CPU1_R_EN      A  @S9S_MB_2U_LIB.S9S_MB_2U(SCH_1):FM_PVCCIN_CPU1_R_EN
    2  FM_PVCCIN_CPU1_EN      B  @S9S_MB_2U_LIB.S9S_MB_2U(SCH_1):FM_PVCCIN_CPU1_EN

Q_RES  I25  R986   [Q_RES_0402LF-33,5%,1/16W,CHIP,A]
    1  FM_PVCCFA_EHV_CPU1_R_EN      A  @S9S_MB_2U_LIB.S9S_MB_2U(SCH_1):FM_PVCCFA_EHV_CPU1_R_EN
    2  FM_PVCCFA_EHV_CPU1_EN      B  @S9S_MB_2U_LIB.S9S_MB_2U(SCH_1):FM_PVCCFA_EHV_CPU1_EN

Q_RES  I24  R987   [Q_RES_0402LF-33,5%,1/16W,CHIP,A]
    1  FM_PVCCINFAON_CPU1_R_EN      A  @S9S_MB_2U_LIB.S9S_MB_2U(SCH_1):FM_PVCCINFAON_CPU1_R_EN
    2  FM_PVCCINFAON_CPU1_EN      B  @S9S_MB_2U_LIB.S9S_MB_2U(SCH_1):FM_PVCCINFAON_CPU1_EN

Q_RES  I23  R988   [Q_RES_0402LF-33,5%,1/16W,CHIP,A]
    1  FM_PVCCFA_EHV_FIVRA_CPU1_R_EN      A  @S9S_MB_2U_LIB.S9S_MB_2U(SCH_1):FM_PVCCFA_EHV_FIVRA_CPU1_R_EN
    2  FM_PVCCFA_EHV_FIVRA_CPU1_EN      B  @S9S_MB_2U_LIB.S9S_MB_2U(SCH_1):FM_PVCCFA_EHV_FIVRA_CPU1_EN

Q_RES  I68  R989   [Q_RES_0402LF-10K,1%,1/16W,CHIPA]
    2  P3V3_RTC_AUX       B  @S9S_MB_2U_LIB.S9S_MB_2U(SCH_1):P3V3_RTC_AUX
    1  FM_INTRUDER_HDR_PCH_N      A  @S9S_MB_2U_LIB.S9S_MB_2U(SCH_1):FM_INTRUDER_HDR_PCH_N

Q_RES  I18  R990   [Q_RES_0402LF-2K,1%,1/16W,CHIP,A]
    2  GND                B  @S9S_MB_2U_LIB.S9S_MB_2U(SCH_1):GND
    1  FM_PLD_CLK_25M_R_EN      A  @S9S_MB_2U_LIB.S9S_MB_2U(SCH_1):FM_PLD_CLK_25M_R_EN

Q_RES  I20  R991   [Q_RES_0402LF-2K,1%,1/16W,CHIP,A]
    2  GND                B  @S9S_MB_2U_LIB.S9S_MB_2U(SCH_1):GND
    1  FM_AUX_SW_EN       A  @S9S_MB_2U_LIB.S9S_MB_2U(SCH_1):FM_AUX_SW_EN

Q_RES  I21  R992   [Q_RES_0402LF-2K,1%,1/16W,CHIP,A]
    1  PWRGD_CPU0_LVC1_R      A  @S9S_MB_2U_LIB.S9S_MB_2U(SCH_1):PWRGD_CPU0_LVC1_R
    2  GND                B  @S9S_MB_2U_LIB.S9S_MB_2U(SCH_1):GND

Q_RES  I44  R993   [Q_RES_0402LF-33.2,1%,1/16W,CHIA]
    1  SMB_S3M_CPU0_SCL      A  @S9S_MB_2U_LIB.S9S_MB_2U(SCH_1):SMB_S3M_CPU0_SCL
    2  SMB_S3M_CPU0_R_SCL      B  @S9S_MB_2U_LIB.S9S_MB_2U(SCH_1):SMB_S3M_CPU0_R_SCL

Q_RES  I45  R994   [Q_RES_0402LF-33.2,1%,1/16W,CHIA]
    1  SMB_S3M_CPU0_SDA      A  @S9S_MB_2U_LIB.S9S_MB_2U(SCH_1):SMB_S3M_CPU0_SDA
    2  SMB_S3M_CPU0_R_SDA      B  @S9S_MB_2U_LIB.S9S_MB_2U(SCH_1):SMB_S3M_CPU0_R_SDA

Q_RES  I51  R995   [Q_RES_0402LF-33.2,1%,1/16W,CHIA]
    1  SMB_S3M_CPU1_SCL      A  @S9S_MB_2U_LIB.S9S_MB_2U(SCH_1):SMB_S3M_CPU1_SCL
    2  SMB_S3M_CPU1_R_SCL      B  @S9S_MB_2U_LIB.S9S_MB_2U(SCH_1):SMB_S3M_CPU1_R_SCL

Q_RES  I52  R996   [Q_RES_0402LF-33.2,1%,1/16W,CHIA]
    1  SMB_S3M_CPU1_SDA      A  @S9S_MB_2U_LIB.S9S_MB_2U(SCH_1):SMB_S3M_CPU1_SDA
    2  SMB_S3M_CPU1_R_SDA      B  @S9S_MB_2U_LIB.S9S_MB_2U(SCH_1):SMB_S3M_CPU1_R_SDA

Q_RES  I31  R997   [Q_RES_0402LF-10K,1%,1/16W,EMPTA]
    1  PU_PIROM_CPU0_SM_WP      A  @S9S_MB_2U_LIB.S9S_MB_2U(SCH_1):PU_PIROM_CPU0_SM_WP
    2  GND                B  @S9S_MB_2U_LIB.S9S_MB_2U(SCH_1):GND

Q_RES  I53  R998   [Q_RES_0402LF-0,5%,1/16W,CHIP,CA]
    2  FM_SMB_PEHPCPU0_PCIE_ALERT_R_N      B  @S9S_MB_2U_LIB.S9S_MB_2U(SCH_1):FM_SMB_PEHPCPU0_PCIE_ALERT_R_N
    1  FM_SMB_PEHPCPU0_PCIE_ALERT_N      A  @S9S_MB_2U_LIB.S9S_MB_2U(SCH_1):FM_SMB_PEHPCPU0_PCIE_ALERT_N

Q_RES  I69  R999   [Q_RES_0402LF-0,5%,1/16W,CHIP,CA]
    2  FM_SMB_PEHPCPU1_PCIE_ALERT_R_N      B  @S9S_MB_2U_LIB.S9S_MB_2U(SCH_1):FM_SMB_PEHPCPU1_PCIE_ALERT_R_N
    1  FM_SMB_PEHPCPU1_PCIE_ALERT_N      A  @S9S_MB_2U_LIB.S9S_MB_2U(SCH_1):FM_SMB_PEHPCPU1_PCIE_ALERT_N

Q_RES  I52  R1000  [Q_RES_0402LF-4.7K,5%,1/16W,CHIA]
    1  P3V3               A  @S9S_MB_2U_LIB.S9S_MB_2U(SCH_1):P3V3
    2  FM_SMB_PEHPCPU0_PCIE_ALERT_R_N      B  @S9S_MB_2U_LIB.S9S_MB_2U(SCH_1):FM_SMB_PEHPCPU0_PCIE_ALERT_R_N

Q_RES  I55  R1001  [Q_RES_0402LF-4.7K,5%,1/16W,CHIA]
    1  P3V3               A  @S9S_MB_2U_LIB.S9S_MB_2U(SCH_1):P3V3
    2  FM_SMB_PEHPCPU1_PCIE_ALERT_R_N      B  @S9S_MB_2U_LIB.S9S_MB_2U(SCH_1):FM_SMB_PEHPCPU1_PCIE_ALERT_R_N

Q_RES  I34  R1002  [Q_RES_0402LF-4.7K,5%,1/16W,CHIA]
    1  P3V3               A  @S9S_MB_2U_LIB.S9S_MB_2U(SCH_1):P3V3
    2  FM_SMB_CPU0_ALERT_R1      B  @S9S_MB_2U_LIB.S9S_MB_2U(SCH_1):FM_SMB_CPU0_ALERT_R1

Q_RES  I38  R1003  [Q_RES_0402LF-4.7K,5%,1/16W,CHIA]
    1  P3V3               A  @S9S_MB_2U_LIB.S9S_MB_2U(SCH_1):P3V3
    2  FM_SMB_CPU1_ALERT_R1      B  @S9S_MB_2U_LIB.S9S_MB_2U(SCH_1):FM_SMB_CPU1_ALERT_R1

Q_RES  I35  R1004  [Q_RES_0402LF-1K,1%,1/16W,CHIP,A]
    2  PU_PIROM_CPU1_SM_WP      B  @S9S_MB_2U_LIB.S9S_MB_2U(SCH_1):PU_PIROM_CPU1_SM_WP
    1  P3V3_AUX           A  @S9S_MB_2U_LIB.S9S_MB_2U(SCH_1):P3V3_AUX

Q_RES  I36  R1005  [Q_RES_0402LF-10K,1%,1/16W,EMPTA]
    1  PU_PIROM_CPU1_SM_WP      A  @S9S_MB_2U_LIB.S9S_MB_2U(SCH_1):PU_PIROM_CPU1_SM_WP
    2  GND                B  @S9S_MB_2U_LIB.S9S_MB_2U(SCH_1):GND

Q_RES  I8   R1006  [Q_RES_0402LF-4.7K,5%,1/16W,CHIA]
    1  PVNN_TERM_CPU0      A  @S9S_MB_2U_LIB.S9S_MB_2U(SCH_1):PVNN_TERM_CPU0
    2  FM_PEHPCPU0_ALERT_N      B  @S9S_MB_2U_LIB.S9S_MB_2U(SCH_1):FM_PEHPCPU0_ALERT_N

Q_RES  I12  R1007  [Q_RES_0402LF-4.7K,5%,1/16W,CHIA]
    1  PVNN_TERM_CPU1      A  @S9S_MB_2U_LIB.S9S_MB_2U(SCH_1):PVNN_TERM_CPU1
    2  FM_PEHPCPU1_ALERT_N      B  @S9S_MB_2U_LIB.S9S_MB_2U(SCH_1):FM_PEHPCPU1_ALERT_N

Q_RES  I139  R1008  [Q_RES_0402LF-1K,1%,1/16W,EMPTYA]
    1  PVNN_TERM_CPU1      A  @S9S_MB_2U_LIB.S9S_MB_2U(SCH_1):PVNN_TERM_CPU1
    2  PU_TAP_ODT_CPU1_EN      B  @S9S_MB_2U_LIB.S9S_MB_2U(SCH_1):PU_TAP_ODT_CPU1_EN

Q_RES  I136  R1009  [Q_RES_0402LF-1K,1%,1/16W,EMPTYA]
    1  PVNN_TERM_CPU0      A  @S9S_MB_2U_LIB.S9S_MB_2U(SCH_1):PVNN_TERM_CPU0
    2  PU_TAP_ODT_CPU0_EN      B  @S9S_MB_2U_LIB.S9S_MB_2U(SCH_1):PU_TAP_ODT_CPU0_EN

Q_RES  I22  R1010  [Q_RES_0402LF-0,5%,1/16W,CHIP,CA]
    2  CLK_25M_PCH_REF_NS_DP      B  @S9S_MB_2U_LIB.S9S_MB_2U(SCH_1):CLK_25M_PCH_REF_NS_DP
    1  CLK_25M_CK440_ISCLK_REF_DP      A  @S9S_MB_2U_LIB.S9S_MB_2U(SCH_1):CLK_25M_CK440_ISCLK_REF_DP

Q_RES  I29  R1011  [Q_RES_0402LF-0,5%,1/16W,CHIP,CA]
    2  CLK_25M_PCH_REF_NS_DN      B  @S9S_MB_2U_LIB.S9S_MB_2U(SCH_1):CLK_25M_PCH_REF_NS_DN
    1  CLK_25M_CK440_ISCLK_REF_DN      A  @S9S_MB_2U_LIB.S9S_MB_2U(SCH_1):CLK_25M_CK440_ISCLK_REF_DN

Q_RES  I10  R1012  [Q_RES_0402LF-0,5%,1/16W,CHIP,CA]
    2  CLK_25M_CK440_CPU0_R_DP      B  @S9S_MB_2U_LIB.S9S_MB_2U(SCH_1):CLK_25M_CK440_CPU0_R_DP
    1  CLK_25M_CK440_CPU0_DP      A  @S9S_MB_2U_LIB.S9S_MB_2U(SCH_1):CLK_25M_CK440_CPU0_DP

Q_RES  I11  R1013  [Q_RES_0402LF-0,5%,1/16W,EMPTY,A]
    1  CLK_25M_PCH_CPU0_DP      A  @S9S_MB_2U_LIB.S9S_MB_2U(SCH_1):CLK_25M_PCH_CPU0_DP
    2  CLK_25M_NSSC_CPU0_DP      B  @S9S_MB_2U_LIB.S9S_MB_2U(SCH_1):CLK_25M_NSSC_CPU0_DP

Q_RES  I13  R1014  [Q_RES_0402LF-0,5%,1/16W,CHIP,CA]
    2  CLK_25M_CK440_CPU0_R_DN      B  @S9S_MB_2U_LIB.S9S_MB_2U(SCH_1):CLK_25M_CK440_CPU0_R_DN
    1  CLK_25M_CK440_CPU0_DN      A  @S9S_MB_2U_LIB.S9S_MB_2U(SCH_1):CLK_25M_CK440_CPU0_DN

Q_RES  I12  R1015  [Q_RES_0402LF-0,5%,1/16W,EMPTY,A]
    1  CLK_25M_PCH_CPU0_DN      A  @S9S_MB_2U_LIB.S9S_MB_2U(SCH_1):CLK_25M_PCH_CPU0_DN
    2  CLK_25M_NSSC_CPU0_DN      B  @S9S_MB_2U_LIB.S9S_MB_2U(SCH_1):CLK_25M_NSSC_CPU0_DN

Q_RES  I18  R1016  [Q_RES_0402LF-0,5%,1/16W,CHIP,CA]
    2  CLK_25M_CK440_CPU1_R_DP      B  @S9S_MB_2U_LIB.S9S_MB_2U(SCH_1):CLK_25M_CK440_CPU1_R_DP
    1  CLK_25M_CK440_CPU1_DP      A  @S9S_MB_2U_LIB.S9S_MB_2U(SCH_1):CLK_25M_CK440_CPU1_DP

Q_RES  I19  R1017  [Q_RES_0402LF-0,5%,1/16W,EMPTY,A]
    1  CLK_25M_PCH_CPU1_DP      A  @S9S_MB_2U_LIB.S9S_MB_2U(SCH_1):CLK_25M_PCH_CPU1_DP
    2  CLK_25M_NSSC_CPU1_DP      B  @S9S_MB_2U_LIB.S9S_MB_2U(SCH_1):CLK_25M_NSSC_CPU1_DP

Q_RES  I20  R1018  [Q_RES_0402LF-0,5%,1/16W,CHIP,CA]
    2  CLK_25M_CK440_CPU1_R_DN      B  @S9S_MB_2U_LIB.S9S_MB_2U(SCH_1):CLK_25M_CK440_CPU1_R_DN
    1  CLK_25M_CK440_CPU1_DN      A  @S9S_MB_2U_LIB.S9S_MB_2U(SCH_1):CLK_25M_CK440_CPU1_DN

Q_RES  I21  R1019  [Q_RES_0402LF-0,5%,1/16W,EMPTY,A]
    1  CLK_25M_PCH_CPU1_DN      A  @S9S_MB_2U_LIB.S9S_MB_2U(SCH_1):CLK_25M_PCH_CPU1_DN
    2  CLK_25M_NSSC_CPU1_DN      B  @S9S_MB_2U_LIB.S9S_MB_2U(SCH_1):CLK_25M_NSSC_CPU1_DN

Q_RES  I5   R1020  [Q_RES_0402LF-0,5%,1/16W,CHIP,CA]
    2  CLK_25M_NSSC_CPU0_DP      B  @S9S_MB_2U_LIB.S9S_MB_2U(SCH_1):CLK_25M_NSSC_CPU0_DP
    1  CLK_25M_CK440_CPU0_R_DP      A  @S9S_MB_2U_LIB.S9S_MB_2U(SCH_1):CLK_25M_CK440_CPU0_R_DP

Q_RES  I6   R1021  [Q_RES_0402LF-0,5%,1/16W,CHIP,CA]
    2  CLK_25M_NSSC_CPU0_DN      B  @S9S_MB_2U_LIB.S9S_MB_2U(SCH_1):CLK_25M_NSSC_CPU0_DN
    1  CLK_25M_CK440_CPU0_R_DN      A  @S9S_MB_2U_LIB.S9S_MB_2U(SCH_1):CLK_25M_CK440_CPU0_R_DN

Q_RES  I7   R1022  [Q_RES_0402LF-0,5%,1/16W,CHIP,CA]
    2  CLK_25M_NSSC_CPU1_DP      B  @S9S_MB_2U_LIB.S9S_MB_2U(SCH_1):CLK_25M_NSSC_CPU1_DP
    1  CLK_25M_CK440_CPU1_R_DP      A  @S9S_MB_2U_LIB.S9S_MB_2U(SCH_1):CLK_25M_CK440_CPU1_R_DP

Q_RES  I8   R1023  [Q_RES_0402LF-0,5%,1/16W,CHIP,CA]
    2  CLK_25M_NSSC_CPU1_DN      B  @S9S_MB_2U_LIB.S9S_MB_2U(SCH_1):CLK_25M_NSSC_CPU1_DN
    1  CLK_25M_CK440_CPU1_R_DN      A  @S9S_MB_2U_LIB.S9S_MB_2U(SCH_1):CLK_25M_CK440_CPU1_R_DN

Q_RES  I41  R1024  [Q_RES_0402LF-100,1%,1/16W,CHIPA]
    1  JTAG_DBP_TCK_PCH      A  @S9S_MB_2U_LIB.S9S_MB_2U(SCH_1):JTAG_DBP_TCK_PCH
    2  GND                B  @S9S_MB_2U_LIB.S9S_MB_2U(SCH_1):GND

Q_RES  I38  R1025  [Q_RES_0402LF-75,1%,1/16W,EMPTYA]
    1  JTAG_DBP_CPU_GTL_TCK      A  @S9S_MB_2U_LIB.S9S_MB_2U(SCH_1):JTAG_DBP_CPU_GTL_TCK
    2  GND                B  @S9S_MB_2U_LIB.S9S_MB_2U(SCH_1):GND

Q_RES  I37  R1026  [Q_RES_0402LF-1K,1%,1/16W,CHIP,A]
    2  P1V05_PCH_AUX      B  @S9S_MB_2U_LIB.S9S_MB_2U(SCH_1):P1V05_PCH_AUX
    1  JTAG_DBP_PMODE      A  @S9S_MB_2U_LIB.S9S_MB_2U(SCH_1):JTAG_DBP_PMODE

Q_RES  I178  R1051  [Q_RES_0402LF-0,5%,1/16W,CHIP,CA]
    2  SMB_RISER2_1_3V3AUX_SCL      B  @S9S_MB_2U_LIB.S9S_MB_2U(SCH_1):SMB_RISER2_1_3V3AUX_SCL
    1  SMB_PCIE0_3V3AUX_SCL_R2      A  @S9S_MB_2U_LIB.S9S_MB_2U(SCH_1):SMB_PCIE0_3V3AUX_SCL_R2

Q_RES  I177  R1052  [Q_RES_0402LF-0,5%,1/16W,CHIP,CA]
    2  SMB_RISER2_1_3V3AUX_SDA      B  @S9S_MB_2U_LIB.S9S_MB_2U(SCH_1):SMB_RISER2_1_3V3AUX_SDA
    1  SMB_PCIE0_3V3AUX_SDA_R2      A  @S9S_MB_2U_LIB.S9S_MB_2U(SCH_1):SMB_PCIE0_3V3AUX_SDA_R2

Q_RES  I108  R1053  [Q_RES_0402LF-0,5%,1/16W,CHIP,CA]
    2  SMB_PCIE_3V3AUX_SCL_R4      B  @S9S_MB_2U_LIB.S9S_MB_2U(SCH_1):SMB_PCIE_3V3AUX_SCL_R4
    1  SMB_OCP_SFF_3V3AUX_SCL      A  @S9S_MB_2U_LIB.S9S_MB_2U(SCH_1):SMB_OCP_SFF_3V3AUX_SCL

Q_RES  I109  R1054  [Q_RES_0402LF-0,5%,1/16W,CHIP,CA]
    2  SMB_PCIE_3V3AUX_SDA_R4      B  @S9S_MB_2U_LIB.S9S_MB_2U(SCH_1):SMB_PCIE_3V3AUX_SDA_R4
    1  SMB_OCP_SFF_3V3AUX_SDA      A  @S9S_MB_2U_LIB.S9S_MB_2U(SCH_1):SMB_OCP_SFF_3V3AUX_SDA

Q_RES  I106  R1055  [Q_RES_0402LF-0,5%,1/16W,CHIP,CA]
    1  SMB_RISER3_3V3AUX_SCL      A  @S9S_MB_2U_LIB.S9S_MB_2U(SCH_1):SMB_RISER3_3V3AUX_SCL
    2  SMB_PCIE_3V3AUX_SCL_R3      B  @S9S_MB_2U_LIB.S9S_MB_2U(SCH_1):SMB_PCIE_3V3AUX_SCL_R3

Q_RES  I107  R1056  [Q_RES_0402LF-0,5%,1/16W,CHIP,CA]
    1  SMB_RISER3_3V3AUX_SDA      A  @S9S_MB_2U_LIB.S9S_MB_2U(SCH_1):SMB_RISER3_3V3AUX_SDA
    2  SMB_PCIE_3V3AUX_SDA_R3      B  @S9S_MB_2U_LIB.S9S_MB_2U(SCH_1):SMB_PCIE_3V3AUX_SDA_R3

Q_RES  I186  R1057  [Q_RES_0402LF-33.2,1%,1/16W,CHIA]
    2  SMB_PCIE1_3V3AUX_SCL_R0      B  @S9S_MB_2U_LIB.S9S_MB_2U(SCH_1):SMB_PCIE1_3V3AUX_SCL_R0
    1  SMB_E1S_0_3V3AUX_SCL      A  @S9S_MB_2U_LIB.S9S_MB_2U(SCH_1):SMB_E1S_0_3V3AUX_SCL

Q_RES  I187  R1058  [Q_RES_0402LF-0,5%,1/16W,CHIP,CA]
    2  SMB_PCIE1_3V3AUX_SDA_R0      B  @S9S_MB_2U_LIB.S9S_MB_2U(SCH_1):SMB_PCIE1_3V3AUX_SDA_R0
    1  SMB_E1S_0_3V3AUX_SDA      A  @S9S_MB_2U_LIB.S9S_MB_2U(SCH_1):SMB_E1S_0_3V3AUX_SDA

Q_RES  I188  R1059  [Q_RES_0402LF-0,5%,1/16W,CHIP,CA]
    2  SMB_PCIE1_3V3AUX_SCL_R1      B  @S9S_MB_2U_LIB.S9S_MB_2U(SCH_1):SMB_PCIE1_3V3AUX_SCL_R1
    1  SMB_E1S_1_3V3AUX_SCL      A  @S9S_MB_2U_LIB.S9S_MB_2U(SCH_1):SMB_E1S_1_3V3AUX_SCL

Q_RES  I189  R1060  [Q_RES_0402LF-0,5%,1/16W,CHIP,CA]
    2  SMB_PCIE1_3V3AUX_SDA_R1      B  @S9S_MB_2U_LIB.S9S_MB_2U(SCH_1):SMB_PCIE1_3V3AUX_SDA_R1
    1  SMB_E1S_1_3V3AUX_SDA      A  @S9S_MB_2U_LIB.S9S_MB_2U(SCH_1):SMB_E1S_1_3V3AUX_SDA

Q_RES  I131  R1061  [Q_RES_0402LF-0,5%,1/16W,CHIP,CA]
    1  SMB_PCIE1_3V3AUX_SCL_R2      A  @S9S_MB_2U_LIB.S9S_MB_2U(SCH_1):SMB_PCIE1_3V3AUX_SCL_R2
    2  SMB_E1S_2_3V3AUX_SCL      B  @S9S_MB_2U_LIB.S9S_MB_2U(SCH_1):SMB_E1S_2_3V3AUX_SCL

Q_RES  I130  R1062  [Q_RES_0402LF-0,5%,1/16W,CHIP,CA]
    1  SMB_PCIE1_3V3AUX_SDA_R2      A  @S9S_MB_2U_LIB.S9S_MB_2U(SCH_1):SMB_PCIE1_3V3AUX_SDA_R2
    2  SMB_E1S_2_3V3AUX_SDA      B  @S9S_MB_2U_LIB.S9S_MB_2U(SCH_1):SMB_E1S_2_3V3AUX_SDA

Q_RES  I133  R1063  [Q_RES_0402LF-0,5%,1/16W,CHIP,CA]
    1  SMB_PCIE1_3V3AUX_SCL_R3      A  @S9S_MB_2U_LIB.S9S_MB_2U(SCH_1):SMB_PCIE1_3V3AUX_SCL_R3
    2  SMB_E1S_3_3V3AUX_SCL      B  @S9S_MB_2U_LIB.S9S_MB_2U(SCH_1):SMB_E1S_3_3V3AUX_SCL

Q_RES  I132  R1064  [Q_RES_0402LF-0,5%,1/16W,CHIP,CA]
    1  SMB_PCIE1_3V3AUX_SDA_R3      A  @S9S_MB_2U_LIB.S9S_MB_2U(SCH_1):SMB_PCIE1_3V3AUX_SDA_R3
    2  SMB_E1S_3_3V3AUX_SDA      B  @S9S_MB_2U_LIB.S9S_MB_2U(SCH_1):SMB_E1S_3_3V3AUX_SDA

Q_RES  I146  R1065  [Q_RES_0402LF-2.2K ,5%,1/16W,EMA]
    2  SMB_E1S_0_3V3AUX_SCL      B  @S9S_MB_2U_LIB.S9S_MB_2U(SCH_1):SMB_E1S_0_3V3AUX_SCL
    1  P3V3_AUX           A  @S9S_MB_2U_LIB.S9S_MB_2U(SCH_1):P3V3_AUX

Q_RES  I145  R1066  [Q_RES_0402LF-2.2K ,5%,1/16W,EMA]
    2  SMB_E1S_0_3V3AUX_SDA      B  @S9S_MB_2U_LIB.S9S_MB_2U(SCH_1):SMB_E1S_0_3V3AUX_SDA
    1  P3V3_AUX           A  @S9S_MB_2U_LIB.S9S_MB_2U(SCH_1):P3V3_AUX

Q_RES  I148  R1067  [Q_RES_0402LF-2.2K ,5%,1/16W,EMA]
    2  SMB_E1S_1_3V3AUX_SCL      B  @S9S_MB_2U_LIB.S9S_MB_2U(SCH_1):SMB_E1S_1_3V3AUX_SCL
    1  P3V3_AUX           A  @S9S_MB_2U_LIB.S9S_MB_2U(SCH_1):P3V3_AUX

Q_RES  I147  R1068  [Q_RES_0402LF-2.2K ,5%,1/16W,EMA]
    2  SMB_E1S_1_3V3AUX_SDA      B  @S9S_MB_2U_LIB.S9S_MB_2U(SCH_1):SMB_E1S_1_3V3AUX_SDA
    1  P3V3_AUX           A  @S9S_MB_2U_LIB.S9S_MB_2U(SCH_1):P3V3_AUX

Q_RES  I149  R1069  [Q_RES_0402LF-2.2K ,5%,1/16W,EMA]
    2  SMB_E1S_2_3V3AUX_SCL      B  @S9S_MB_2U_LIB.S9S_MB_2U(SCH_1):SMB_E1S_2_3V3AUX_SCL
    1  P3V3_AUX           A  @S9S_MB_2U_LIB.S9S_MB_2U(SCH_1):P3V3_AUX

Q_RES  I150  R1070  [Q_RES_0402LF-2.2K ,5%,1/16W,EMA]
    2  SMB_E1S_2_3V3AUX_SDA      B  @S9S_MB_2U_LIB.S9S_MB_2U(SCH_1):SMB_E1S_2_3V3AUX_SDA
    1  P3V3_AUX           A  @S9S_MB_2U_LIB.S9S_MB_2U(SCH_1):P3V3_AUX

Q_RES  I154  R1071  [Q_RES_0402LF-2.2K ,5%,1/16W,EMA]
    2  SMB_E1S_3_3V3AUX_SCL      B  @S9S_MB_2U_LIB.S9S_MB_2U(SCH_1):SMB_E1S_3_3V3AUX_SCL
    1  P3V3_AUX           A  @S9S_MB_2U_LIB.S9S_MB_2U(SCH_1):P3V3_AUX

Q_RES  I151  R1072  [Q_RES_0402LF-2.2K ,5%,1/16W,EMA]
    2  SMB_E1S_3_3V3AUX_SDA      B  @S9S_MB_2U_LIB.S9S_MB_2U(SCH_1):SMB_E1S_3_3V3AUX_SDA
    1  P3V3_AUX           A  @S9S_MB_2U_LIB.S9S_MB_2U(SCH_1):P3V3_AUX

Q_RES  I31  R1089  [Q_RES_0402LF-2.2K ,5%,1/16W,CHA]
    2  SMB_SENSOR_M2_P0_3V3AUX_SCL      B  @S9S_MB_2U_LIB.S9S_MB_2U(SCH_1):SMB_SENSOR_M2_P0_3V3AUX_SCL
    1  P3V3_AUX           A  @S9S_MB_2U_LIB.S9S_MB_2U(SCH_1):P3V3_AUX

Q_RES  I32  R1090  [Q_RES_0402LF-2.2K ,5%,1/16W,CHA]
    2  SMB_SENSOR_M2_P0_3V3AUX_SDA      B  @S9S_MB_2U_LIB.S9S_MB_2U(SCH_1):SMB_SENSOR_M2_P0_3V3AUX_SDA
    1  P3V3_AUX           A  @S9S_MB_2U_LIB.S9S_MB_2U(SCH_1):P3V3_AUX

Q_RES  I30  R1091  [Q_RES_0402LF-2.2K ,5%,1/16W,CHA]
    2  SMB_RISER1_3V3AUX_SCL      B  @S9S_MB_2U_LIB.S9S_MB_2U(SCH_1):SMB_RISER1_3V3AUX_SCL
    1  P3V3_AUX           A  @S9S_MB_2U_LIB.S9S_MB_2U(SCH_1):P3V3_AUX

Q_RES  I29  R1092  [Q_RES_0402LF-2.2K ,5%,1/16W,CHA]
    2  SMB_RISER1_3V3AUX_SDA      B  @S9S_MB_2U_LIB.S9S_MB_2U(SCH_1):SMB_RISER1_3V3AUX_SDA
    1  P3V3_AUX           A  @S9S_MB_2U_LIB.S9S_MB_2U(SCH_1):P3V3_AUX

Q_RES  I136  R1099  [Q_RES_0402LF-10K,1%,1/16W,CHIPA]
    2  PU_CLK25M_OSC_FPGA_EN      B  @S9S_MB_2U_LIB.S9S_MB_2U(SCH_1):PU_CLK25M_OSC_FPGA_EN
    1  P3V3_AUX           A  @S9S_MB_2U_LIB.S9S_MB_2U(SCH_1):P3V3_AUX

Q_RES  I139  R1100  [Q_RES_0402LF-33.2,1%,1/16W,CHIA]
    2  CLK_25M_OSC_MAIN_FPGA      B  @S9S_MB_2U_LIB.S9S_MB_2U(SCH_1):CLK_25M_OSC_MAIN_FPGA
    1  CLK_25M_OSC_FPGA_R      A  @S9S_MB_2U_LIB.S9S_MB_2U(SCH_1):CLK_25M_OSC_FPGA_R

Q_RES  I48  R1103  [Q_RES_0402LF-1.33K,1%,1/16W,CHA]
    1  P3V3_E1S_0_ILM      A  @S9S_MB_2U_LIB.S9S_MB_2U(SCH_1):P3V3_E1S_0_ILM
    2  GND                B  @S9S_MB_2U_LIB.S9S_MB_2U(SCH_1):GND

Q_RES  I51  R1104  [Q_RES_0402LF-10K,1%,1/16W,CHIPA]
    2  P3V3_E1S_0_FLT_N      B  @S9S_MB_2U_LIB.S9S_MB_2U(SCH_1):P3V3_E1S_0_FLT_N
    1  P3V3_AUX           A  @S9S_MB_2U_LIB.S9S_MB_2U(SCH_1):P3V3_AUX

Q_RES  I415  R1106  [Q_RES_0402LF-10K,1%,1/16W,CHIPA]
    1  P3V3_AUX           A  @S9S_MB_2U_LIB.S9S_MB_2U(SCH_1):P3V3_AUX
    2  FM_PLD_REV_R_N      B  @S9S_MB_2U_LIB.S9S_MB_2U(SCH_1):FM_PLD_REV_R_N

Q_RES  I142  R1123  [Q_RES_0402LF-1K,5%,1/16W,EMPTYA]
    2  PD_SMB_OCP1_HP_ADD2      B  @S9S_MB_2U_LIB.S9S_MB_2U(SCH_1):PD_SMB_OCP1_HP_ADD2
    1  P3V3_AUX           A  @S9S_MB_2U_LIB.S9S_MB_2U(SCH_1):P3V3_AUX

Q_RES  I143  R1124  [Q_RES_0402LF-1K,5%,1/16W,CHIP,A]
    1  PD_SMB_OCP1_HP_ADD2      A  @S9S_MB_2U_LIB.S9S_MB_2U(SCH_1):PD_SMB_OCP1_HP_ADD2
    2  GND                B  @S9S_MB_2U_LIB.S9S_MB_2U(SCH_1):GND

Q_RES  I134  R1125  [Q_RES_0402LF-1K,5%,1/16W,EMPTYA]
    2  PD_SMB_OCP1_HP_ADD1      B  @S9S_MB_2U_LIB.S9S_MB_2U(SCH_1):PD_SMB_OCP1_HP_ADD1
    1  P3V3_AUX           A  @S9S_MB_2U_LIB.S9S_MB_2U(SCH_1):P3V3_AUX

Q_RES  I140  R1126  [Q_RES_0402LF-1K,5%,1/16W,CHIP,A]
    1  PD_SMB_OCP1_HP_ADD1      A  @S9S_MB_2U_LIB.S9S_MB_2U(SCH_1):PD_SMB_OCP1_HP_ADD1
    2  GND                B  @S9S_MB_2U_LIB.S9S_MB_2U(SCH_1):GND

Q_RES  I133  R1127  [Q_RES_0402LF-1K,5%,1/16W,EMPTYA]
    2  PD_SMB_OCP1_HP_ADD0      B  @S9S_MB_2U_LIB.S9S_MB_2U(SCH_1):PD_SMB_OCP1_HP_ADD0
    1  P3V3_AUX           A  @S9S_MB_2U_LIB.S9S_MB_2U(SCH_1):P3V3_AUX

Q_RES  I137  R1128  [Q_RES_0402LF-1K,5%,1/16W,CHIP,A]
    1  PD_SMB_OCP1_HP_ADD0      A  @S9S_MB_2U_LIB.S9S_MB_2U(SCH_1):PD_SMB_OCP1_HP_ADD0
    2  GND                B  @S9S_MB_2U_LIB.S9S_MB_2U(SCH_1):GND

Q_RES  I172  R1129  [Q_RES_0402LF-1K,5%,1/16W,CHIP,A]
    1  P3V3_AUX           A  @S9S_MB_2U_LIB.S9S_MB_2U(SCH_1):P3V3_AUX
    2  HP_LVC3_OCP_V3_1_PRSNT2      B  @S9S_MB_2U_LIB.S9S_MB_2U(SCH_1):HP_LVC3_OCP_V3_1_PRSNT2

Q_RES  I130  R1130  [Q_RES_0402LF-33,5%,1/16W,CHIP,A]
    1  SMB_PEHPCPU0_LVC3_SCL      A  @S9S_MB_2U_LIB.S9S_MB_2U(SCH_1):SMB_PEHPCPU0_LVC3_SCL
    2  SMB_PEHPCPU0_LVC3_R_SCL      B  @S9S_MB_2U_LIB.S9S_MB_2U(SCH_1):SMB_PEHPCPU0_LVC3_R_SCL

Q_RES  I131  R1131  [Q_RES_0402LF-33,5%,1/16W,CHIP,A]
    1  SMB_PEHPCPU0_LVC3_SDA      A  @S9S_MB_2U_LIB.S9S_MB_2U(SCH_1):SMB_PEHPCPU0_LVC3_SDA
    2  SMB_PEHPCPU0_LVC3_R_SDA      B  @S9S_MB_2U_LIB.S9S_MB_2U(SCH_1):SMB_PEHPCPU0_LVC3_R_SDA

Q_RES  I153  R1132  [Q_RES_0402LF-1K,5%,1/16W,EMPTYA]
    1  P3V3_OCP_SFF       A  @S9S_MB_2U_LIB.S9S_MB_2U(SCH_1):P3V3_OCP_SFF
    2  HP_LVC3_OCP_V3_1_PWRGD      B  @S9S_MB_2U_LIB.S9S_MB_2U(SCH_1):HP_LVC3_OCP_V3_1_PWRGD

Q_RES  I155  R1133  [Q_RES_0402LF-10K,1%,1/16W,CHIPA]
    1  P3V3_AUX           A  @S9S_MB_2U_LIB.S9S_MB_2U(SCH_1):P3V3_AUX
    2  HP_LVC3_OCP_V3_1_PWRGD_N      B  @S9S_MB_2U_LIB.S9S_MB_2U(SCH_1):HP_LVC3_OCP_V3_1_PWRGD_N

Q_RES  I389  R1134  [Q_RES_0402LF-0,5%,1/16W,CHIP,CA]
    1  P12V_OCP_LDSTRT11      A  @S9S_MB_2U_LIB.S9S_MB_2U(SCH_1):P12V_OCP_LDSTRT11
    2  GND                B  @S9S_MB_2U_LIB.S9S_MB_2U(SCH_1):GND

Q_RES  I386  R1135  [Q_RES_0402LF-0,5%,1/16W,EMPTY,A]
    1  P12V_OCP_NRETRY1      A  @S9S_MB_2U_LIB.S9S_MB_2U(SCH_1):P12V_OCP_NRETRY1
    2  GND                B  @S9S_MB_2U_LIB.S9S_MB_2U(SCH_1):GND

Q_RES  I385  R1136  [Q_RES_0402LF-0,5%,1/16W,CHIP,CA]
    1  P12V_OCP_RETRY1      A  @S9S_MB_2U_LIB.S9S_MB_2U(SCH_1):P12V_OCP_RETRY1
    2  GND                B  @S9S_MB_2U_LIB.S9S_MB_2U(SCH_1):GND

Q_RES  I379  R1137  [Q_RES_0402LF-150,1%,1/16W,CHIPA]
    1  P12V_OCP_ILIM1      A  @S9S_MB_2U_LIB.S9S_MB_2U(SCH_1):P12V_OCP_ILIM1
    2  GND                B  @S9S_MB_2U_LIB.S9S_MB_2U(SCH_1):GND

Q_RES  I61  R1138  [Q_RES_0402LF-10K,1%,1/16W,CHIPA]
    1  P3V3_AUX           A  @S9S_MB_2U_LIB.S9S_MB_2U(SCH_1):P3V3_AUX
    2  CLK_50M_EN         B  @S9S_MB_2U_LIB.S9S_MB_2U(SCH_1):CLK_50M_EN

Q_RES  I56  R1139  [Q_RES_0402LF-0,5%,1/16W,CHIP,CA]
    2  CLK_50M_RMII_R      B  @S9S_MB_2U_LIB.S9S_MB_2U(SCH_1):CLK_50M_RMII_R
    1  CLK_50M_RMII       A  @S9S_MB_2U_LIB.S9S_MB_2U(SCH_1):CLK_50M_RMII

Q_RES  I52  R1140  [Q_RES_0402LF-27.4,1%,1/16W,CHIA]
    2  CLK_50M_RMII_BMC_OCP      B  @S9S_MB_2U_LIB.S9S_MB_2U(SCH_1):CLK_50M_RMII_BMC_OCP
    1  CLK_50M_BMC_MAC_R      A  @S9S_MB_2U_LIB.S9S_MB_2U(SCH_1):CLK_50M_BMC_MAC_R

Q_RES  I53  R1141  [Q_RES_0402LF-27.4,1%,1/16W,CHIA]
    2  CLK_50M_NCSI_OCP_SFF      B  @S9S_MB_2U_LIB.S9S_MB_2U(SCH_1):CLK_50M_NCSI_OCP_SFF
    1  CLK_50M_NCSI_OCP_1      A  @S9S_MB_2U_LIB.S9S_MB_2U(SCH_1):CLK_50M_NCSI_OCP_1

Q_RES  I345  R1142  [Q_RES_0402LF-1K,5%,1/16W,CHIP,A]
    1  P3V3_OCP_ILM1      A  @S9S_MB_2U_LIB.S9S_MB_2U(SCH_1):P3V3_OCP_ILM1
    2  GND                B  @S9S_MB_2U_LIB.S9S_MB_2U(SCH_1):GND

Q_RES  I343  R1143  [Q_RES_0402LF-10K,1%,1/16W,CHIPA]
    1  P3V3_AUX           A  @S9S_MB_2U_LIB.S9S_MB_2U(SCH_1):P3V3_AUX
    2  HP_LVC3_OCP_V3_1_FAULT_N      B  @S9S_MB_2U_LIB.S9S_MB_2U(SCH_1):HP_LVC3_OCP_V3_1_FAULT_N

Q_RES  I362  R1144  [Q_RES_0402LF-562,1%,1/16W,CHIPA]
    1  P12V_OCP_IMON_1      A  @S9S_MB_2U_LIB.S9S_MB_2U(SCH_1):P12V_OCP_IMON_1
    2  GND                B  @S9S_MB_2U_LIB.S9S_MB_2U(SCH_1):GND

Q_RES  I358  R1146  [Q_RES_0402LF-1K,1%,1/16W,CHIP,A]
    1  P3V3_AUX           A  @S9S_MB_2U_LIB.S9S_MB_2U(SCH_1):P3V3_AUX
    2  HP_LVC3_OCP_V3_1_HSC_PWRGD      B  @S9S_MB_2U_LIB.S9S_MB_2U(SCH_1):HP_LVC3_OCP_V3_1_HSC_PWRGD

Q_RES  I375  R1147  [Q_RES_0402LF-0,5%,1/16W,CHIP,CA]
    1  HP_LVC3_OCP_V3_1_PRSNT2_N_R      A  @S9S_MB_2U_LIB.S9S_MB_2U(SCH_1):HP_LVC3_OCP_V3_1_PRSNT2_N_R
    2  HP_LVC3_OCP_V3_1_ATTN_OUT_SW_N      B  @S9S_MB_2U_LIB.S9S_MB_2U(SCH_1):HP_LVC3_OCP_V3_1_ATTN_OUT_SW_N

Q_RES  I376  R1148  [Q_RES_0402LF-0,5%,1/16W,CHIP,CA]
    1  HP_LVC3_OCP_V3_1_PRSNT2_N_R      A  @S9S_MB_2U_LIB.S9S_MB_2U(SCH_1):HP_LVC3_OCP_V3_1_PRSNT2_N_R
    2  HP_LVC3_OCP_V3_1_PRSNT2_N      B  @S9S_MB_2U_LIB.S9S_MB_2U(SCH_1):HP_LVC3_OCP_V3_1_PRSNT2_N

Q_RES  I367  R1149  [Q_RES_0402LF-10K,1%,1/16W,CHIPA]
    1  P3V3_AUX           A  @S9S_MB_2U_LIB.S9S_MB_2U(SCH_1):P3V3_AUX
    2  HP_LVC3_OCP_V3_1_ATTN_OUT_SW_N      B  @S9S_MB_2U_LIB.S9S_MB_2U(SCH_1):HP_LVC3_OCP_V3_1_ATTN_OUT_SW_N

Q_RES  I368  R1150  [Q_RES_0402LF-10K,1%,1/16W,CHIPA]
    1  P3V3_AUX           A  @S9S_MB_2U_LIB.S9S_MB_2U(SCH_1):P3V3_AUX
    2  HP_LVC3_OCP_V3_1_PRSNT2_N      B  @S9S_MB_2U_LIB.S9S_MB_2U(SCH_1):HP_LVC3_OCP_V3_1_PRSNT2_N

Q_RES  I14  R1184  [Q_RES_0402LF-0,5%,1/16W,CHIP,CA]
    1  JTAG_BMC_DBP_TMS_R      A  @S9S_MB_2U_LIB.S9S_MB_2U(SCH_1):JTAG_BMC_DBP_TMS_R
    2  JTAG_BMC_DBP_TMS      B  @S9S_MB_2U_LIB.S9S_MB_2U(SCH_1):JTAG_BMC_DBP_TMS

Q_RES  I277  R1194  [Q_RES_0402LF-4.75K,1%,1/16W,EMA]
    1  P3V3_AUX           A  @S9S_MB_2U_LIB.S9S_MB_2U(SCH_1):P3V3_AUX
    2  FM_CK440_MXCK_25M_100M      B  @S9S_MB_2U_LIB.S9S_MB_2U(SCH_1):FM_CK440_MXCK_25M_100M

Q_RES  I241  R1195  [Q_RES_0402LF-750,1%,1/16W,CHIPA]
    2  PU_PLD_HEARTBEAT_LVC3      B  @S9S_MB_2U_LIB.S9S_MB_2U(SCH_1):PU_PLD_HEARTBEAT_LVC3
    1  P3V3_AUX           A  @S9S_MB_2U_LIB.S9S_MB_2U(SCH_1):P3V3_AUX

Q_RES  I281  R1196  [Q_RES_0402LF-4.75K,1%,1/16W,CHA]
    2  GND                B  @S9S_MB_2U_LIB.S9S_MB_2U(SCH_1):GND
    1  FM_CK440_MXCK_25M_100M      A  @S9S_MB_2U_LIB.S9S_MB_2U(SCH_1):FM_CK440_MXCK_25M_100M

Q_RES  I50  R1197  [Q_RES_0402LF-1K,5%,1/16W,EMPTYA]
    2  PD_SUSCLK          B  @S9S_MB_2U_LIB.S9S_MB_2U(SCH_1):PD_SUSCLK
    1  GND                A  @S9S_MB_2U_LIB.S9S_MB_2U(SCH_1):GND

Q_RES  I48  R1198  [Q_RES_0402LF-10K,1%,1/16W,CHIPA]
    2  PU_ACPRESENT       B  @S9S_MB_2U_LIB.S9S_MB_2U(SCH_1):PU_ACPRESENT
    1  P3V3_AUX           A  @S9S_MB_2U_LIB.S9S_MB_2U(SCH_1):P3V3_AUX

Q_RES  I60  R1200  [Q_RES_0402LF-100,1%,1/16W,CHIPA]
    2  FM_PCH_TRIGGER0_R_N      B  @S9S_MB_2U_LIB.S9S_MB_2U(SCH_1):FM_PCH_TRIGGER0_R_N
    1  FM_PCH_TRIGGER0_N      A  @S9S_MB_2U_LIB.S9S_MB_2U(SCH_1):FM_PCH_TRIGGER0_N

Q_RES  I58  R1201  [Q_RES_0402LF-49.9     ,1%  ,1/A]
    2  FM_PCH_TRIGGER1_R_N      B  @S9S_MB_2U_LIB.S9S_MB_2U(SCH_1):FM_PCH_TRIGGER1_R_N
    1  FM_PCH_TRIGGER1_N      A  @S9S_MB_2U_LIB.S9S_MB_2U(SCH_1):FM_PCH_TRIGGER1_N

Q_RES  I70  R1202  [Q_RES_0402LF-20K,1%,1/16W,CHIPA]
    2  RST_SRTCRST_N      B  @S9S_MB_2U_LIB.S9S_MB_2U(SCH_1):RST_SRTCRST_N
    1  P3V3_RTC_AUX       A  @S9S_MB_2U_LIB.S9S_MB_2U(SCH_1):P3V3_RTC_AUX

Q_RES  I62  R1203  [Q_RES_0402LF-1K,1%,1/16W,CHIP,A]
    2  P3V_BAT_R          B  @S9S_MB_2U_LIB.S9S_MB_2U(SCH_1):P3V_BAT_R
    1  P3V_BAT            A  @S9S_MB_2U_LIB.S9S_MB_2U(SCH_1):P3V_BAT

Q_RES  I273  R1204  [Q_RES_0402LF-10K,1%,1/16W,EMPTA]
    2  PU_CK440_SHFT_LD_N      B  @S9S_MB_2U_LIB.S9S_MB_2U(SCH_1):PU_CK440_SHFT_LD_N
    1  P3V3_AUX           A  @S9S_MB_2U_LIB.S9S_MB_2U(SCH_1):P3V3_AUX

Q_RES  I7   R1205  [Q_RES_0402LF-33,5%,1/16W,CHIP,A]
    2  RST_PLTRST_PLD_N      B  @S9S_MB_2U_LIB.S9S_MB_2U(SCH_1):RST_PLTRST_PLD_N
    1  RST_PLTRST_N       A  @S9S_MB_2U_LIB.S9S_MB_2U(SCH_1):RST_PLTRST_N

Q_RES  I10  R1206  [Q_RES_0402LF-33,5%,1/16W,CHIP,A]
    1  RST_MB_STBY_R_N      A  @S9S_MB_2U_LIB.S9S_MB_2U(SCH_1):RST_MB_STBY_R_N
    2  RST_MB_STBY_N      B  @S9S_MB_2U_LIB.S9S_MB_2U(SCH_1):RST_MB_STBY_N

Q_RES  I15  R1207  [Q_RES_0402LF-33,5%,1/16W,CHIP,A]
    1  RST_RSMRST_PLD_R_N      A  @S9S_MB_2U_LIB.S9S_MB_2U(SCH_1):RST_RSMRST_PLD_R_N
    2  RST_RSMRST_PCH_N      B  @S9S_MB_2U_LIB.S9S_MB_2U(SCH_1):RST_RSMRST_PCH_N

Q_RES  I33  R1214  [Q_RES_0402LF-0,5%,1/16W,CHIP,CA]
    2  IRQ_LPC_PIRQA_N_ESPI_ALERT0_R_N      B  @S9S_MB_2U_LIB.S9S_MB_2U(SCH_1):IRQ_LPC_PIRQA_N_ESPI_ALERT0_R_N
    1  IRQ_LPC_PIRQA_N_ESPI_ALERT0_N      A  @S9S_MB_2U_LIB.S9S_MB_2U(SCH_1):IRQ_LPC_PIRQA_N_ESPI_ALERT0_N

Q_RES  I38  R1215  [Q_RES_0402LF-49.9     ,1%  ,1/A]
    2  IRQ_ESPI_LPC_SERIRQ_ALERT_R_N      B  @S9S_MB_2U_LIB.S9S_MB_2U(SCH_1):IRQ_ESPI_LPC_SERIRQ_ALERT_R_N
    1  IRQ_ESPI_LPC_SERIRQ_ALERT_N      A  @S9S_MB_2U_LIB.S9S_MB_2U(SCH_1):IRQ_ESPI_LPC_SERIRQ_ALERT_N

Q_RES  I36  R1216  [Q_RES_0402LF-10K,1%,1/16W,CHIPA]
    1  P3V3_AUX           A  @S9S_MB_2U_LIB.S9S_MB_2U(SCH_1):P3V3_AUX
    2  FM_S3M_CPU0_CPLD_CRC_ERROR      B  @S9S_MB_2U_LIB.S9S_MB_2U(SCH_1):FM_S3M_CPU0_CPLD_CRC_ERROR

Q_RES  I37  R1217  [Q_RES_0402LF-10K,1%,1/16W,CHIPA]
    1  P3V3_AUX           A  @S9S_MB_2U_LIB.S9S_MB_2U(SCH_1):P3V3_AUX
    2  FM_S3M_CPU1_CPLD_CRC_ERROR      B  @S9S_MB_2U_LIB.S9S_MB_2U(SCH_1):FM_S3M_CPU1_CPLD_CRC_ERROR

Q_RES  I26  R1218  [Q_RES_0402LF-33.2,1%,1/16W,CHIA]
    2  PWRGD_S0_PWROK_CPU0_LVC1_R      B  @S9S_MB_2U_LIB.S9S_MB_2U(SCH_1):PWRGD_S0_PWROK_CPU0_LVC1_R
    1  PWRGD_S0_PWROK_CPU0_LVC1      A  @S9S_MB_2U_LIB.S9S_MB_2U(SCH_1):PWRGD_S0_PWROK_CPU0_LVC1

Q_RES  I27  R1219  [Q_RES_0402LF-33.2,1%,1/16W,CHIA]
    2  PWRGD_S0_PWROK_CPU1_LVC1_R      B  @S9S_MB_2U_LIB.S9S_MB_2U(SCH_1):PWRGD_S0_PWROK_CPU1_LVC1_R
    1  PWRGD_S0_PWROK_CPU1_LVC1      A  @S9S_MB_2U_LIB.S9S_MB_2U(SCH_1):PWRGD_S0_PWROK_CPU1_LVC1

Q_RES  I63  R1220  [Q_RES_0402LF-1K,1%,1/16W,EMPTYA]
    1  P3V3_AUX           A  @S9S_MB_2U_LIB.S9S_MB_2U(SCH_1):P3V3_AUX
    2  FM_PCH_MCRO_LDO      B  @S9S_MB_2U_LIB.S9S_MB_2U(SCH_1):FM_PCH_MCRO_LDO

Q_RES  I64  R1221  [Q_RES_0402LF-1K,1%,1/16W,CHIP,A]
    2  GND                B  @S9S_MB_2U_LIB.S9S_MB_2U(SCH_1):GND
    1  FM_PCH_MCRO_LDO      A  @S9S_MB_2U_LIB.S9S_MB_2U(SCH_1):FM_PCH_MCRO_LDO

Q_RES  I57  R1222  [Q_RES_0402LF-5.11K,1%,1/16W,CHA]
    1  P3V3_AUX           A  @S9S_MB_2U_LIB.S9S_MB_2U(SCH_1):P3V3_AUX
    2  FM_PCH_SPARE0      B  @S9S_MB_2U_LIB.S9S_MB_2U(SCH_1):FM_PCH_SPARE0

Q_RES  I49  R1223  [Q_RES_0402LF-10K,1%,1/16W,EMPTA]
    2  P3V3_AUX           B  @S9S_MB_2U_LIB.S9S_MB_2U(SCH_1):P3V3_AUX
    1  JTAG_CPU0_PLD_TDI      A  @S9S_MB_2U_LIB.S9S_MB_2U(SCH_1):JTAG_CPU0_PLD_TDI

Q_RES  I50  R1224  [Q_RES_0402LF-10K,1%,1/16W,CHIPA]
    2  P3V3_AUX           B  @S9S_MB_2U_LIB.S9S_MB_2U(SCH_1):P3V3_AUX
    1  JTAG_CPU0_PLD_TMS      A  @S9S_MB_2U_LIB.S9S_MB_2U(SCH_1):JTAG_CPU0_PLD_TMS

Q_RES  I51  R1225  [Q_RES_0402LF-10K,1%,1/16W,CHIPA]
    2  P3V3_AUX           B  @S9S_MB_2U_LIB.S9S_MB_2U(SCH_1):P3V3_AUX
    1  JTAG_CPU0_PLD_TDO      A  @S9S_MB_2U_LIB.S9S_MB_2U(SCH_1):JTAG_CPU0_PLD_TDO

Q_RES  I52  R1226  [Q_RES_0402LF-1K,1%,1/16W,CHIP,A]
    1  JTAG_CPU0_PLD_TCK      A  @S9S_MB_2U_LIB.S9S_MB_2U(SCH_1):JTAG_CPU0_PLD_TCK
    2  GND                B  @S9S_MB_2U_LIB.S9S_MB_2U(SCH_1):GND

Q_RES  I56  R1227  [Q_RES_0402LF-10K,1%,1/16W,CHIPA]
    1  PD_JTAG_CPU1_PLD_TCK      A  @S9S_MB_2U_LIB.S9S_MB_2U(SCH_1):PD_JTAG_CPU1_PLD_TCK
    2  GND                B  @S9S_MB_2U_LIB.S9S_MB_2U(SCH_1):GND

Q_RES  I169  R1229  [Q_RES_0402LF-240,1%,1/16W,EMPTA]
    1  PVNN_TERM_CPU1      A  @S9S_MB_2U_LIB.S9S_MB_2U(SCH_1):PVNN_TERM_CPU1
    2  PUD_XTAL_CPU1_MODE0      B  @S9S_MB_2U_LIB.S9S_MB_2U(SCH_1):PUD_XTAL_CPU1_MODE0

Q_RES  I170  R1230  [Q_RES_0402LF-240,1%,1/16W,EMPTA]
    1  PVNN_TERM_CPU1      A  @S9S_MB_2U_LIB.S9S_MB_2U(SCH_1):PVNN_TERM_CPU1
    2  PUD_XTAL_CPU1_MODE1      B  @S9S_MB_2U_LIB.S9S_MB_2U(SCH_1):PUD_XTAL_CPU1_MODE1

Q_RES  I156  R1232  [Q_RES_0402LF-240,1%,1/16W,EMPTA]
    1  PVNN_TERM_CPU0      A  @S9S_MB_2U_LIB.S9S_MB_2U(SCH_1):PVNN_TERM_CPU0
    2  PUD_XTAL_CPU0_MODE0      B  @S9S_MB_2U_LIB.S9S_MB_2U(SCH_1):PUD_XTAL_CPU0_MODE0

Q_RES  I158  R1233  [Q_RES_0402LF-240,1%,1/16W,EMPTA]
    1  PVNN_TERM_CPU0      A  @S9S_MB_2U_LIB.S9S_MB_2U(SCH_1):PVNN_TERM_CPU0
    2  PUD_XTAL_CPU0_MODE1      B  @S9S_MB_2U_LIB.S9S_MB_2U(SCH_1):PUD_XTAL_CPU0_MODE1

Q_RES  I172  R1234  [Q_RES_0402LF-240,1%,1/16W,EMPTA]
    2  PD_EXT_CLK_SEL_CPU1      B  @S9S_MB_2U_LIB.S9S_MB_2U(SCH_1):PD_EXT_CLK_SEL_CPU1
    1  GND                A  @S9S_MB_2U_LIB.S9S_MB_2U(SCH_1):GND

Q_RES  I176  R1235  [Q_RES_0402LF-240,1%,1/16W,EMPTA]
    2  PUD_XTAL_CPU1_MODE0      B  @S9S_MB_2U_LIB.S9S_MB_2U(SCH_1):PUD_XTAL_CPU1_MODE0
    1  GND                A  @S9S_MB_2U_LIB.S9S_MB_2U(SCH_1):GND

Q_RES  I177  R1236  [Q_RES_0402LF-240,1%,1/16W,EMPTA]
    2  PUD_XTAL_CPU1_MODE1      B  @S9S_MB_2U_LIB.S9S_MB_2U(SCH_1):PUD_XTAL_CPU1_MODE1
    1  GND                A  @S9S_MB_2U_LIB.S9S_MB_2U(SCH_1):GND

Q_RES  I160  R1237  [Q_RES_0402LF-240,1%,1/16W,EMPTA]
    2  PD_EXT_CLK_SEL_CPU0      B  @S9S_MB_2U_LIB.S9S_MB_2U(SCH_1):PD_EXT_CLK_SEL_CPU0
    1  GND                A  @S9S_MB_2U_LIB.S9S_MB_2U(SCH_1):GND

Q_RES  I161  R1238  [Q_RES_0402LF-240,1%,1/16W,EMPTA]
    2  PUD_XTAL_CPU0_MODE0      B  @S9S_MB_2U_LIB.S9S_MB_2U(SCH_1):PUD_XTAL_CPU0_MODE0
    1  GND                A  @S9S_MB_2U_LIB.S9S_MB_2U(SCH_1):GND

Q_RES  I163  R1239  [Q_RES_0402LF-240,1%,1/16W,EMPTA]
    2  PUD_XTAL_CPU0_MODE1      B  @S9S_MB_2U_LIB.S9S_MB_2U(SCH_1):PUD_XTAL_CPU0_MODE1
    1  GND                A  @S9S_MB_2U_LIB.S9S_MB_2U(SCH_1):GND

Q_RES  I9   R1240  [Q_RES_0402LF-0,5%,1/16W,CHIP,CA]
    2  H_CPU_PM_FAST_WAKE_N      B  @S9S_MB_2U_LIB.S9S_MB_2U(SCH_1):H_CPU_PM_FAST_WAKE_N
    1  H_CPU0_PM_FAST_WAKE_N      A  @S9S_MB_2U_LIB.S9S_MB_2U(SCH_1):H_CPU0_PM_FAST_WAKE_N

Q_RES  I17  R1241  [Q_RES_0402LF-249,1%,1/16W,CHIPA]
    1  H_PMAX_TRIGGER_IO_CPU0      A  @S9S_MB_2U_LIB.S9S_MB_2U(SCH_1):H_PMAX_TRIGGER_IO_CPU0
    2  GND                B  @S9S_MB_2U_LIB.S9S_MB_2U(SCH_1):GND

Q_RES  I13  R1242  [Q_RES_0402LF-301,1%,1/16W,CHIPA]
    1  PVNN_TERM_CPU0      A  @S9S_MB_2U_LIB.S9S_MB_2U(SCH_1):PVNN_TERM_CPU0
    2  H_CPU_PM_FAST_WAKE_N      B  @S9S_MB_2U_LIB.S9S_MB_2U(SCH_1):H_CPU_PM_FAST_WAKE_N

Q_RES  I19  R1243  [Q_RES_0402LF-249,1%,1/16W,CHIPA]
    1  H_PMAX_TRIGGER_IO_CPU1      A  @S9S_MB_2U_LIB.S9S_MB_2U(SCH_1):H_PMAX_TRIGGER_IO_CPU1
    2  GND                B  @S9S_MB_2U_LIB.S9S_MB_2U(SCH_1):GND

Q_RES  I16  R1244  [Q_RES_0402LF-301,1%,1/16W,CHIPA]
    1  PVNN_TERM_CPU1      A  @S9S_MB_2U_LIB.S9S_MB_2U(SCH_1):PVNN_TERM_CPU1
    2  H_CPU_PM_FAST_WAKE_N      B  @S9S_MB_2U_LIB.S9S_MB_2U(SCH_1):H_CPU_PM_FAST_WAKE_N

Q_RES  I10  R1245  [Q_RES_0402LF-0,5%,1/16W,CHIP,CA]
    1  H_CPU_PM_FAST_WAKE_N      A  @S9S_MB_2U_LIB.S9S_MB_2U(SCH_1):H_CPU_PM_FAST_WAKE_N
    2  H_CPU1_PM_FAST_WAKE_N      B  @S9S_MB_2U_LIB.S9S_MB_2U(SCH_1):H_CPU1_PM_FAST_WAKE_N

Q_RES  I14  R1247  [Q_RES_0402LF-0,5%,1/16W,CHIP,CA]
    1  FM_PCH_CPU_PWR_DEBUG_N      A  @S9S_MB_2U_LIB.S9S_MB_2U(SCH_1):FM_PCH_CPU_PWR_DEBUG_N
    2  FM_CPU_FBRK_DEBUG_N      B  @S9S_MB_2U_LIB.S9S_MB_2U(SCH_1):FM_CPU_FBRK_DEBUG_N

Q_RES  I2   R1249  [Q_RES_0402LF-0,5%,1/16W,CHIP,CA]
    2  H_THERMTRIP_LVC1_N      B  @S9S_MB_2U_LIB.S9S_MB_2U(SCH_1):H_THERMTRIP_LVC1_N
    1  FM_THERMTRIP_DLY_LVC1_N      A  @S9S_MB_2U_LIB.S9S_MB_2U(SCH_1):FM_THERMTRIP_DLY_LVC1_N

Q_RES  I23  R1253  [Q_RES_0402LF-1K,1%,1/16W,CHIP,A]
    1  PGPPA_AUX          A  @S9S_MB_2U_LIB.S9S_MB_2U(SCH_1):PGPPA_AUX
    2  IRQ_LPC_PIRQA_N_ESPI_ALERT0_N      B  @S9S_MB_2U_LIB.S9S_MB_2U(SCH_1):IRQ_LPC_PIRQA_N_ESPI_ALERT0_N

Q_RES  I24  R1254  [Q_RES_0402LF-10K,1%,1/16W,CHIPA]
    1  PGPPA_AUX          A  @S9S_MB_2U_LIB.S9S_MB_2U(SCH_1):PGPPA_AUX
    2  IRQ_LPC_SERIRQ_ESPI_CS1_N      B  @S9S_MB_2U_LIB.S9S_MB_2U(SCH_1):IRQ_LPC_SERIRQ_ESPI_CS1_N

Q_RES  I26  R1255  [Q_RES_0402LF-1K,1%,1/16W,CHIP,A]
    1  PGPPA_AUX          A  @S9S_MB_2U_LIB.S9S_MB_2U(SCH_1):PGPPA_AUX
    2  ESPI_ALERT1_N_LPC_RCIN_N      B  @S9S_MB_2U_LIB.S9S_MB_2U(SCH_1):ESPI_ALERT1_N_LPC_RCIN_N

Q_RES  I1   R1256  [Q_RES_0402LF-10K,1%,1/16W,CHIPA]
    1  P3V3_AUX           A  @S9S_MB_2U_LIB.S9S_MB_2U(SCH_1):P3V3_AUX
    2  IRQ_PCH_SCI_WHEA_N      B  @S9S_MB_2U_LIB.S9S_MB_2U(SCH_1):IRQ_PCH_SCI_WHEA_N

Q_RES  I4   R1257  [Q_RES_0402LF-10K,1%,1/16W,CHIPA]
    2  PU_PCH_VRALERT_N      B  @S9S_MB_2U_LIB.S9S_MB_2U(SCH_1):PU_PCH_VRALERT_N
    1  P3V3_AUX           A  @S9S_MB_2U_LIB.S9S_MB_2U(SCH_1):P3V3_AUX

Q_RES  I6   R1258  [Q_RES_0402LF-10K,1%,1/16W,CHIPA]
    1  P3V3_AUX           A  @S9S_MB_2U_LIB.S9S_MB_2U(SCH_1):P3V3_AUX
    2  FM_PCH_GLB_RST_WARN_N      B  @S9S_MB_2U_LIB.S9S_MB_2U(SCH_1):FM_PCH_GLB_RST_WARN_N

Q_RES  I8   R1259  [Q_RES_0402LF-10K,1%,1/16W,CHIPA]
    2  PU_LPC_PME_N       B  @S9S_MB_2U_LIB.S9S_MB_2U(SCH_1):PU_LPC_PME_N
    1  P3V3_AUX           A  @S9S_MB_2U_LIB.S9S_MB_2U(SCH_1):P3V3_AUX

Q_RES  I17  R1260  [Q_RES_0402LF-10K,1%,1/16W,EMPTA]
    1  P1V05_PCH_AUX      A  @S9S_MB_2U_LIB.S9S_MB_2U(SCH_1):P1V05_PCH_AUX
    2  H_CPU_ERR0_PCH_R_N      B  @S9S_MB_2U_LIB.S9S_MB_2U(SCH_1):H_CPU_ERR0_PCH_R_N

Q_RES  I18  R1261  [Q_RES_0402LF-10K,1%,1/16W,EMPTA]
    1  P1V05_PCH_AUX      A  @S9S_MB_2U_LIB.S9S_MB_2U(SCH_1):P1V05_PCH_AUX
    2  H_CPU_ERR1_PCH_R_N      B  @S9S_MB_2U_LIB.S9S_MB_2U(SCH_1):H_CPU_ERR1_PCH_R_N

Q_RES  I11  R1262  [Q_RES_0402LF-10K,1%,1/16W,EMPTA]
    1  P1V05_PCH_AUX      A  @S9S_MB_2U_LIB.S9S_MB_2U(SCH_1):P1V05_PCH_AUX
    2  H_CPU_ERR2_PCH_R_N      B  @S9S_MB_2U_LIB.S9S_MB_2U(SCH_1):H_CPU_ERR2_PCH_R_N

Q_RES  I29  R1263  [Q_RES_0402LF-33,5%,1/16W,CHIP,A]
    1  FM_PLT_BMC_THERMTRIP_R_N      A  @S9S_MB_2U_LIB.S9S_MB_2U(SCH_1):FM_PLT_BMC_THERMTRIP_R_N
    2  FM_PCH_BMC_THERMTRIP_N      B  @S9S_MB_2U_LIB.S9S_MB_2U(SCH_1):FM_PCH_BMC_THERMTRIP_N

Q_RES  I36  R1266  [Q_RES_0402LF-49.9     ,1%  ,1/B]
    1  P1V05_PCH_AUX      A  @S9S_MB_2U_LIB.S9S_MB_2U(SCH_1):P1V05_PCH_AUX
    2  H_THERMTRIP_LVC1_N      B  @S9S_MB_2U_LIB.S9S_MB_2U(SCH_1):H_THERMTRIP_LVC1_N

Q_RES  I276  R1267  [Q_RES_0402LF-1K,1%,1/16W,CHIP,A]
    1  PU_CK440_SHFT_LD_N      A  @S9S_MB_2U_LIB.S9S_MB_2U(SCH_1):PU_CK440_SHFT_LD_N
    2  GND                B  @S9S_MB_2U_LIB.S9S_MB_2U(SCH_1):GND

Q_RES  I222  R1268  [Q_RES_0402LF-33,5%,1/16W,CHIP,A]
    1  IRQ_BMC_PCH_NMI_R1      A  @S9S_MB_2U_LIB.S9S_MB_2U(SCH_1):IRQ_BMC_PCH_NMI_R1
    2  IRQ_BMC_PCH_NMI      B  @S9S_MB_2U_LIB.S9S_MB_2U(SCH_1):IRQ_BMC_PCH_NMI

Q_RES  I225  R1269  [Q_RES_0402LF-4.75K,1%,1/16W,CHA]
    1  IRQ_BMC_PCH_NMI      A  @S9S_MB_2U_LIB.S9S_MB_2U(SCH_1):IRQ_BMC_PCH_NMI
    2  GND                B  @S9S_MB_2U_LIB.S9S_MB_2U(SCH_1):GND

Q_RES  I55  R1270  [Q_RES_0402LF-240,1%,1/16W,EMPTA]
    1  PD_CPU1_PROCDIS_COD_GTL_N      A  @S9S_MB_2U_LIB.S9S_MB_2U(SCH_1):PD_CPU1_PROCDIS_COD_GTL_N
    2  GND                B  @S9S_MB_2U_LIB.S9S_MB_2U(SCH_1):GND

Q_RES  I5   R1271  [Q_RES_0402LF-2.21K    ,1%  ,1/A]
    1  PGPPA_AUX          A  @S9S_MB_2U_LIB.S9S_MB_2U(SCH_1):PGPPA_AUX
    2  FM_PCH_SATA_RAID_KEY      B  @S9S_MB_2U_LIB.S9S_MB_2U(SCH_1):FM_PCH_SATA_RAID_KEY

Q_RES  I166  R1273  [Q_RES_0402LF-0,5%,1/16W,CHIP,CA]
    1  CLK_100M_OCP_SFF_2_R_DP      A  @S9S_MB_2U_LIB.S9S_MB_2U(SCH_1):CLK_100M_OCP_SFF_2_R_DP
    2  CLK_100M_OCP_SFF_2_DP      B  @S9S_MB_2U_LIB.S9S_MB_2U(SCH_1):CLK_100M_OCP_SFF_2_DP

Q_RES  I165  R1274  [Q_RES_0402LF-0,5%,1/16W,CHIP,CA]
    1  CLK_100M_OCP_SFF_2_R_DN      A  @S9S_MB_2U_LIB.S9S_MB_2U(SCH_1):CLK_100M_OCP_SFF_2_R_DN
    2  CLK_100M_OCP_SFF_2_DN      B  @S9S_MB_2U_LIB.S9S_MB_2U(SCH_1):CLK_100M_OCP_SFF_2_DN

Q_RES  I164  R1275  [Q_RES_0402LF-0,5%,1/16W,CHIP,CA]
    1  CLK_100M_OCP_SFF_3_R_DP      A  @S9S_MB_2U_LIB.S9S_MB_2U(SCH_1):CLK_100M_OCP_SFF_3_R_DP
    2  CLK_100M_OCP_SFF_3_DP      B  @S9S_MB_2U_LIB.S9S_MB_2U(SCH_1):CLK_100M_OCP_SFF_3_DP

Q_RES  I163  R1276  [Q_RES_0402LF-0,5%,1/16W,CHIP,CA]
    1  CLK_100M_OCP_SFF_3_R_DN      A  @S9S_MB_2U_LIB.S9S_MB_2U(SCH_1):CLK_100M_OCP_SFF_3_R_DN
    2  CLK_100M_OCP_SFF_3_DN      B  @S9S_MB_2U_LIB.S9S_MB_2U(SCH_1):CLK_100M_OCP_SFF_3_DN

Q_RES  I185  R1277  [Q_RES_0402LF-0,5%,1/16W,CHIP,CA]
    1  CLK_100M_EDSFF1A_R_DP      A  @S9S_MB_2U_LIB.S9S_MB_2U(SCH_1):CLK_100M_EDSFF1A_R_DP
    2  CLK_100M_EDSFF1A_DP      B  @S9S_MB_2U_LIB.S9S_MB_2U(SCH_1):CLK_100M_EDSFF1A_DP

Q_RES  I186  R1278  [Q_RES_0402LF-0,5%,1/16W,CHIP,CA]
    1  CLK_100M_EDSFF1A_R_DN      A  @S9S_MB_2U_LIB.S9S_MB_2U(SCH_1):CLK_100M_EDSFF1A_R_DN
    2  CLK_100M_EDSFF1A_DN      B  @S9S_MB_2U_LIB.S9S_MB_2U(SCH_1):CLK_100M_EDSFF1A_DN

Q_RES  I189  R1279  [Q_RES_0402LF-0,5%,1/16W,CHIP,CA]
    1  CLK_100M_EDSFF1B_R_DP      A  @S9S_MB_2U_LIB.S9S_MB_2U(SCH_1):CLK_100M_EDSFF1B_R_DP
    2  CLK_100M_EDSFF1B_DP      B  @S9S_MB_2U_LIB.S9S_MB_2U(SCH_1):CLK_100M_EDSFF1B_DP

Q_RES  I190  R1280  [Q_RES_0402LF-0,5%,1/16W,CHIP,CA]
    1  CLK_100M_EDSFF1B_R_DN      A  @S9S_MB_2U_LIB.S9S_MB_2U(SCH_1):CLK_100M_EDSFF1B_R_DN
    2  CLK_100M_EDSFF1B_DN      B  @S9S_MB_2U_LIB.S9S_MB_2U(SCH_1):CLK_100M_EDSFF1B_DN

Q_RES  I261  R1281  [Q_RES_0402LF-0,5%,1/16W,CHIP,CA]
    1  CLK_100M_EDSFF3_R_DP      A  @S9S_MB_2U_LIB.S9S_MB_2U(SCH_1):CLK_100M_EDSFF3_R_DP
    2  CLK_100M_EDSFF3_DP      B  @S9S_MB_2U_LIB.S9S_MB_2U(SCH_1):CLK_100M_EDSFF3_DP

Q_RES  I262  R1282  [Q_RES_0402LF-0,5%,1/16W,CHIP,CA]
    1  CLK_100M_EDSFF3_R_DN      A  @S9S_MB_2U_LIB.S9S_MB_2U(SCH_1):CLK_100M_EDSFF3_R_DN
    2  CLK_100M_EDSFF3_DN      B  @S9S_MB_2U_LIB.S9S_MB_2U(SCH_1):CLK_100M_EDSFF3_DN

Q_RES  I208  R1283  [Q_RES_0402LF-0,5%,1/16W,CHIP,CA]
    1  CLK_100M_EDSFF4A_R_DP      A  @S9S_MB_2U_LIB.S9S_MB_2U(SCH_1):CLK_100M_EDSFF4A_R_DP
    2  CLK_100M_EDSFF4A_DP      B  @S9S_MB_2U_LIB.S9S_MB_2U(SCH_1):CLK_100M_EDSFF4A_DP

Q_RES  I210  R1284  [Q_RES_0402LF-0,5%,1/16W,CHIP,CA]
    1  CLK_100M_EDSFF4A_R_DN      A  @S9S_MB_2U_LIB.S9S_MB_2U(SCH_1):CLK_100M_EDSFF4A_R_DN
    2  CLK_100M_EDSFF4A_DN      B  @S9S_MB_2U_LIB.S9S_MB_2U(SCH_1):CLK_100M_EDSFF4A_DN

Q_RES  I56  R1289  [Q_RES_0402LF-100K,1%,1/16W,CHIA]
    2  GND                B  @S9S_MB_2U_LIB.S9S_MB_2U(SCH_1):GND
    1  FB_BMC_ISOLATE      A  @S9S_MB_2U_LIB.S9S_MB_2U(SCH_1):FB_BMC_ISOLATE

Q_RES  I98  R1290  [Q_RES_0402LF-22,1%,1/16W,CHIP,A]
    2  OCP_SFF_RBT_ARB_OUT      B  @S9S_MB_2U_LIB.S9S_MB_2U(SCH_1):OCP_SFF_RBT_ARB_OUT
    1  OCP_SFF_RBT_ARB_IN      A  @S9S_MB_2U_LIB.S9S_MB_2U(SCH_1):OCP_SFF_RBT_ARB_IN

Q_RES  I99  R1291  [Q_RES_0402LF-22,1%,1/16W,CHIP,A]
    2  RMII_OCP_BMC_CRSDV      B  @S9S_MB_2U_LIB.S9S_MB_2U(SCH_1):RMII_OCP_BMC_CRSDV
    1  NCSI_BMC_CRS_DV_R      A  @S9S_MB_2U_LIB.S9S_MB_2U(SCH_1):NCSI_BMC_CRS_DV_R

Q_RES  I100  R1292  [Q_RES_0402LF-22,1%,1/16W,CHIP,A]
    2  RMII_OCP_BMC_RXD_0      B  @S9S_MB_2U_LIB.S9S_MB_2U(SCH_1):RMII_OCP_BMC_RXD_0
    1  NCSI_BMC_RXD0_R      A  @S9S_MB_2U_LIB.S9S_MB_2U(SCH_1):NCSI_BMC_RXD0_R

Q_RES  I101  R1293  [Q_RES_0402LF-22,1%,1/16W,CHIP,A]
    2  RMII_OCP_BMC_RXD_1      B  @S9S_MB_2U_LIB.S9S_MB_2U(SCH_1):RMII_OCP_BMC_RXD_1
    1  NCSI_BMC_RXD1_R      A  @S9S_MB_2U_LIB.S9S_MB_2U(SCH_1):NCSI_BMC_RXD1_R

Q_RES  I102  R1294  [Q_RES_0402LF-22,1%,1/16W,CHIP,A]
    2  RMII_BMC_OCP_TX_EN      B  @S9S_MB_2U_LIB.S9S_MB_2U(SCH_1):RMII_BMC_OCP_TX_EN
    1  NCSI_BMC_TX_EN_R      A  @S9S_MB_2U_LIB.S9S_MB_2U(SCH_1):NCSI_BMC_TX_EN_R

Q_RES  I103  R1295  [Q_RES_0402LF-22,1%,1/16W,CHIP,A]
    2  RMII_BMC_OCP_TXD_0      B  @S9S_MB_2U_LIB.S9S_MB_2U(SCH_1):RMII_BMC_OCP_TXD_0
    1  NCSI_BMC_TXD0_R      A  @S9S_MB_2U_LIB.S9S_MB_2U(SCH_1):NCSI_BMC_TXD0_R

Q_RES  I104  R1296  [Q_RES_0402LF-22,1%,1/16W,CHIP,A]
    2  RMII_BMC_OCP_TXD_1      B  @S9S_MB_2U_LIB.S9S_MB_2U(SCH_1):RMII_BMC_OCP_TXD_1
    1  NCSI_BMC_TXD1_R      A  @S9S_MB_2U_LIB.S9S_MB_2U(SCH_1):NCSI_BMC_TXD1_R

Q_RES  I22  R1298  [Q_RES_0402LF-1K,5%,1/16W,EMPTYA]
    1  P1V05_PCH_AUX      A  @S9S_MB_2U_LIB.S9S_MB_2U(SCH_1):P1V05_PCH_AUX
    2  FM_MFG_MODE        B  @S9S_MB_2U_LIB.S9S_MB_2U(SCH_1):FM_MFG_MODE

Q_RES  I21  R1299  [Q_RES_0402LF-10K,1%,1/16W,CHIPA]
    2  GND                B  @S9S_MB_2U_LIB.S9S_MB_2U(SCH_1):GND
    1  FM_MFG_MODE        A  @S9S_MB_2U_LIB.S9S_MB_2U(SCH_1):FM_MFG_MODE

Q_RES  I5   R1300  [Q_RES_0402LF-33.2,1%,1/16W,CHIA]
    1  FM_BIOS_POST_CMPLT_N      A  @S9S_MB_2U_LIB.S9S_MB_2U(SCH_1):FM_BIOS_POST_CMPLT_N
    2  FM_BIOS_POST_CMPLT_BMC_N      B  @S9S_MB_2U_LIB.S9S_MB_2U(SCH_1):FM_BIOS_POST_CMPLT_BMC_N

Q_RES  I12  R1302  [Q_RES_0402LF-2K,1%,1/16W,CHIP,A]
    1  PWRGD_DRAMPWRGD_CPU0_AB_R_LVC1      A  @S9S_MB_2U_LIB.S9S_MB_2U(SCH_1):PWRGD_DRAMPWRGD_CPU0_AB_R_LVC1
    2  GND                B  @S9S_MB_2U_LIB.S9S_MB_2U(SCH_1):GND

Q_RES  I272  R1305  [Q_RES_0402LF-10K,1%,1/16W,EMPTA]
    1  P3V3_AUX           A  @S9S_MB_2U_LIB.S9S_MB_2U(SCH_1):P3V3_AUX
    2  FM_PLD_CLKS_DEV_EN      B  @S9S_MB_2U_LIB.S9S_MB_2U(SCH_1):FM_PLD_CLKS_DEV_EN

Q_RES  I13  R1306  [Q_RES_0402LF-33.2,1%,1/16W,CHIA]
    2  FM_PS_PWROK_DLY_SEL      B  @S9S_MB_2U_LIB.S9S_MB_2U(SCH_1):FM_PS_PWROK_DLY_SEL
    1  FM_PS_PWROK_DLY_R_SEL      A  @S9S_MB_2U_LIB.S9S_MB_2U(SCH_1):FM_PS_PWROK_DLY_R_SEL

Q_RES  I3   R1307  [Q_RES_0402LF-33.2,1%,1/16W,CHIA]
    2  FM_THROTTLE_R_N      B  @S9S_MB_2U_LIB.S9S_MB_2U(SCH_1):FM_THROTTLE_R_N
    1  FM_THROTTLE_N      A  @S9S_MB_2U_LIB.S9S_MB_2U(SCH_1):FM_THROTTLE_N

Q_RES  I252  R1308  [Q_RES_0402LF-10K,1%,1/16W,EMPTA]
    2  GND                B  @S9S_MB_2U_LIB.S9S_MB_2U(SCH_1):GND
    1  FM_RST_PERST_BIT1      A  @S9S_MB_2U_LIB.S9S_MB_2U(SCH_1):FM_RST_PERST_BIT1

Q_RES  I10  R1309  [Q_RES_0402LF-33.2,1%,1/16W,CHIA]
    1  IRQ_SMI_ACTIVE_N      A  @S9S_MB_2U_LIB.S9S_MB_2U(SCH_1):IRQ_SMI_ACTIVE_N
    2  IRQ_SMI_ACTIVE_BMC_N      B  @S9S_MB_2U_LIB.S9S_MB_2U(SCH_1):IRQ_SMI_ACTIVE_BMC_N

Q_RES  I20  R1310  [Q_RES_0402LF-33.2,1%,1/16W,CHIA]
    1  IRQ_PCH_CPU_NMI_EVENT_R_N      A  @S9S_MB_2U_LIB.S9S_MB_2U(SCH_1):IRQ_PCH_CPU_NMI_EVENT_R_N
    2  IRQ_PCH_CPU_NMI_EVENT_N      B  @S9S_MB_2U_LIB.S9S_MB_2U(SCH_1):IRQ_PCH_CPU_NMI_EVENT_N

Q_RES  I31  R1311  [Q_RES_0402LF-10K,1%,1/16W,CHIPA]
    2  GND                B  @S9S_MB_2U_LIB.S9S_MB_2U(SCH_1):GND
    1  FM_XTAL_INPUT_FREQUENCY_0_MGPIO      A  @S9S_MB_2U_LIB.S9S_MB_2U(SCH_1):FM_XTAL_INPUT_FREQUENCY_0_MGPIO_TEST4

Q_RES  I260  R1312  [Q_RES_0402LF-10K,1%,1/16W,EMPTA]
    2  GND                B  @S9S_MB_2U_LIB.S9S_MB_2U(SCH_1):GND
    1  FM_RST_PERST_BIT2      A  @S9S_MB_2U_LIB.S9S_MB_2U(SCH_1):FM_RST_PERST_BIT2

Q_RES  I21  R1313  [Q_RES_0402LF-33.2,1%,1/16W,CHIA]
    2  FM_PCH_PLD_GLB_RST_WARN_N      B  @S9S_MB_2U_LIB.S9S_MB_2U(SCH_1):FM_PCH_PLD_GLB_RST_WARN_N
    1  FM_PCH_GLB_RST_WARN_N      A  @S9S_MB_2U_LIB.S9S_MB_2U(SCH_1):FM_PCH_GLB_RST_WARN_N

Q_RES  I161  R1314  [Q_RES_0402LF-2.2K ,5%,1/16W,CHA]
    2  SMB_PCIE1_3V3AUX_SDA      B  @S9S_MB_2U_LIB.S9S_MB_2U(SCH_1):SMB_PCIE1_3V3AUX_SDA
    1  P3V3_AUX           A  @S9S_MB_2U_LIB.S9S_MB_2U(SCH_1):P3V3_AUX

Q_RES  I35  R1315  [Q_RES_0402LF-1K,5%,1/16W,EMPTYA]
    1  P1V05_PCH_AUX      A  @S9S_MB_2U_LIB.S9S_MB_2U(SCH_1):P1V05_PCH_AUX
    2  FM_XTAL_INPUT_FREQUENCY_1_MGPIO      B  @S9S_MB_2U_LIB.S9S_MB_2U(SCH_1):FM_XTAL_INPUT_FREQUENCY_1_MGPIO_TEST5

Q_RES  I92  R1316  [Q_RES_0603LF-200K,0.1%,1/10W,EA]
    2  XTAL_PCH_25M_OUT      B  @S9S_MB_2U_LIB.S9S_MB_2U(SCH_1):XTAL_PCH_25M_OUT
    1  XTAL_PCH_25M_IN_R      A  @S9S_MB_2U_LIB.S9S_MB_2U(SCH_1):XTAL_PCH_25M_IN_R

Q_RES  I28  R1317  [Q_RES_0402LF-1K,1%,1/16W,CHIP,A]
    2  PU_BIOS_RCVR_BOOT      B  @S9S_MB_2U_LIB.S9S_MB_2U(SCH_1):PU_BIOS_RCVR_BOOT
    1  P1V05_PCH_AUX      A  @S9S_MB_2U_LIB.S9S_MB_2U(SCH_1):P1V05_PCH_AUX

Q_RES  I47  R1318  [Q_RES_0402LF-33.2,1%,1/16W,CHIA]
    1  FM_THERMTRIP_DLY_LVC1_R_N      A  @S9S_MB_2U_LIB.S9S_MB_2U(SCH_1):FM_THERMTRIP_DLY_LVC1_R_N
    2  FM_THERMTRIP_DLY_LVC1_N      B  @S9S_MB_2U_LIB.S9S_MB_2U(SCH_1):FM_THERMTRIP_DLY_LVC1_N

Q_RES  I2   R1319  [Q_RES_0402LF-2K,1%,1/16W,CHIP,A]
    1  SMB_HOST_3V3AUX_SCL      A  @S9S_MB_2U_LIB.S9S_MB_2U(SCH_1):SMB_HOST_3V3AUX_SCL
    2  P3V3_AUX           B  @S9S_MB_2U_LIB.S9S_MB_2U(SCH_1):P3V3_AUX

Q_RES  I68  R1320  [Q_RES_0402LF-1K,1%,1/16W,CHIP,A]
    2  PU_SWAP_OVERRIDE_N      B  @S9S_MB_2U_LIB.S9S_MB_2U(SCH_1):PU_SWAP_OVERRIDE_N
    1  P3V3_AUX           A  @S9S_MB_2U_LIB.S9S_MB_2U(SCH_1):P3V3_AUX

Q_RES  I3   R1321  [Q_RES_0402LF-2K,1%,1/16W,CHIP,A]
    1  SMB_HOST_3V3AUX_SDA      A  @S9S_MB_2U_LIB.S9S_MB_2U(SCH_1):SMB_HOST_3V3AUX_SDA
    2  P3V3_AUX           B  @S9S_MB_2U_LIB.S9S_MB_2U(SCH_1):P3V3_AUX

Q_RES  I26  R1324  [Q_RES_0402LF-1K,1%,1/16W,CHIP,A]
    2  PD_BIOS_IMAGE_SWAP_N      B  @S9S_MB_2U_LIB.S9S_MB_2U(SCH_1):PD_BIOS_IMAGE_SWAP_N
    1  GND                A  @S9S_MB_2U_LIB.S9S_MB_2U(SCH_1):GND

Q_RES  I75  R1325  [Q_RES_0402LF-1K,1%,1/16W,CHIP,A]
    2  PU_FLASH_SECURITY_STRAP      B  @S9S_MB_2U_LIB.S9S_MB_2U(SCH_1):PU_FLASH_SECURITY_STRAP
    1  P3V3_AUX           A  @S9S_MB_2U_LIB.S9S_MB_2U(SCH_1):P3V3_AUX

Q_RES  I11  R1326  [Q_RES_0402LF-2K,1%,1/16W,CHIP,A]
    1  PWRGD_DRAMPWRGD_CPU0_CD_R_LVC1      A  @S9S_MB_2U_LIB.S9S_MB_2U(SCH_1):PWRGD_DRAMPWRGD_CPU0_CD_R_LVC1
    2  GND                B  @S9S_MB_2U_LIB.S9S_MB_2U(SCH_1):GND

Q_RES  I14  R1327  [Q_RES_0402LF-2K,1%,1/16W,CHIP,A]
    1  PWRGD_DRAMPWRGD_CPU0_EF_R_LVC1      A  @S9S_MB_2U_LIB.S9S_MB_2U(SCH_1):PWRGD_DRAMPWRGD_CPU0_EF_R_LVC1
    2  GND                B  @S9S_MB_2U_LIB.S9S_MB_2U(SCH_1):GND

Q_RES  I13  R1328  [Q_RES_0402LF-2K,1%,1/16W,CHIP,A]
    1  PWRGD_DRAMPWRGD_CPU0_GH_R_LVC1      A  @S9S_MB_2U_LIB.S9S_MB_2U(SCH_1):PWRGD_DRAMPWRGD_CPU0_GH_R_LVC1
    2  GND                B  @S9S_MB_2U_LIB.S9S_MB_2U(SCH_1):GND

Q_RES  I15  R1329  [Q_RES_0402LF-2K,1%,1/16W,CHIP,A]
    1  PWRGD_DRAMPWRGD_CPU1_AB_R_LVC1      A  @S9S_MB_2U_LIB.S9S_MB_2U(SCH_1):PWRGD_DRAMPWRGD_CPU1_AB_R_LVC1
    2  GND                B  @S9S_MB_2U_LIB.S9S_MB_2U(SCH_1):GND

Q_RES  I16  R1330  [Q_RES_0402LF-2K,1%,1/16W,CHIP,A]
    1  PWRGD_DRAMPWRGD_CPU1_CD_R_LVC1      A  @S9S_MB_2U_LIB.S9S_MB_2U(SCH_1):PWRGD_DRAMPWRGD_CPU1_CD_R_LVC1
    2  GND                B  @S9S_MB_2U_LIB.S9S_MB_2U(SCH_1):GND

Q_RES  I95  R1331  [Q_RES_0402LF-4.7K,5%,1/16W,CHIA]
    2  SMB_SENSOR_3V3AUX_SCL      B  @S9S_MB_2U_LIB.S9S_MB_2U(SCH_1):SMB_SENSOR_3V3AUX_SCL
    1  P3V3_AUX           A  @S9S_MB_2U_LIB.S9S_MB_2U(SCH_1):P3V3_AUX

Q_RES  I93  R1332  [Q_RES_0402LF-4.7K,5%,1/16W,CHIA]
    2  SMB_SENSOR_3V3AUX_SDA      B  @S9S_MB_2U_LIB.S9S_MB_2U(SCH_1):SMB_SENSOR_3V3AUX_SDA
    1  P3V3_AUX           A  @S9S_MB_2U_LIB.S9S_MB_2U(SCH_1):P3V3_AUX

Q_RES  I49  R1333  [Q_RES_0402LF-1K,1%,1/16W,CHIP,A]
    2  PD_RST_RTCRST_N      B  @S9S_MB_2U_LIB.S9S_MB_2U(SCH_1):PD_RST_RTCRST_N
    1  GND                A  @S9S_MB_2U_LIB.S9S_MB_2U(SCH_1):GND

Q_RES  I54  R1334  [Q_RES_0402LF-1K,1%,1/16W,CHIP,A]
    2  PD_ME_RCVR_N       B  @S9S_MB_2U_LIB.S9S_MB_2U(SCH_1):PD_ME_RCVR_N
    1  GND                A  @S9S_MB_2U_LIB.S9S_MB_2U(SCH_1):GND

Q_RES  I50  R1335  [Q_RES_0402LF-1K,1%,1/16W,CHIP,A]
    2  PD_PASSWORD_CLEAR      B  @S9S_MB_2U_LIB.S9S_MB_2U(SCH_1):PD_PASSWORD_CLEAR
    1  GND                A  @S9S_MB_2U_LIB.S9S_MB_2U(SCH_1):GND

Q_RES  I177  R1336  [Q_RES_0402LF-2.2K ,5%,1/16W,CHA]
    1  SMB_SENSOR_3V3AUX_SCL      A  @S9S_MB_2U_LIB.S9S_MB_2U(SCH_1):SMB_SENSOR_3V3AUX_SCL
    2  P3V3_AUX           B  @S9S_MB_2U_LIB.S9S_MB_2U(SCH_1):P3V3_AUX

Q_RES  I77  R1337  [Q_RES_0402LF-10K,1%,1/16W,CHIPA]
    2  GND                B  @S9S_MB_2U_LIB.S9S_MB_2U(SCH_1):GND
    1  FM_FLASH_SECURITY_STRAP      A  @S9S_MB_2U_LIB.S9S_MB_2U(SCH_1):FM_FLASH_SECURITY_STRAP

Q_RES  I29  R1338  [Q_RES_0402LF-10K,1%,1/16W,CHIPA]
    2  GND                B  @S9S_MB_2U_LIB.S9S_MB_2U(SCH_1):GND
    1  FM_PCH_BIOS_RCVR_MODE      A  @S9S_MB_2U_LIB.S9S_MB_2U(SCH_1):FM_PCH_BIOS_RCVR_MODE

Q_RES  I81  R1339  [Q_RES_0402LF-10K,1%,1/16W,CHIPA]
    1  P3V3_AUX           A  @S9S_MB_2U_LIB.S9S_MB_2U(SCH_1):P3V3_AUX
    2  FM_BIOS_IMAGE_SWAP_N      B  @S9S_MB_2U_LIB.S9S_MB_2U(SCH_1):FM_BIOS_IMAGE_SWAP_N

Q_RES  I57  R1340  [Q_RES_0402LF-20K,5%,1/16W,CHIPA]
    2  RST_RTCRST_N       B  @S9S_MB_2U_LIB.S9S_MB_2U(SCH_1):RST_RTCRST_N
    1  P3V3_RTC_AUX       A  @S9S_MB_2U_LIB.S9S_MB_2U(SCH_1):P3V3_RTC_AUX

Q_RES  I69  R1341  [Q_RES_0402LF-10K,1%,1/16W,CHIPA]
    2  GND                B  @S9S_MB_2U_LIB.S9S_MB_2U(SCH_1):GND
    1  FM_ADR_COMPLETE      A  @S9S_MB_2U_LIB.S9S_MB_2U(SCH_1):FM_ADR_COMPLETE

Q_RES  I45  R1342  [Q_RES_0402LF-10K,1%,1/16W,CHIPA]
    1  P1V05_PCH_AUX      A  @S9S_MB_2U_LIB.S9S_MB_2U(SCH_1):P1V05_PCH_AUX
    2  FM_ME_RCVR_N       B  @S9S_MB_2U_LIB.S9S_MB_2U(SCH_1):FM_ME_RCVR_N

Q_RES  I44  R1343  [Q_RES_0402LF-10K,1%,1/16W,CHIPA]
    1  P1V05_PCH_AUX      A  @S9S_MB_2U_LIB.S9S_MB_2U(SCH_1):P1V05_PCH_AUX
    2  FM_PASSWORD_CLEAR_N      B  @S9S_MB_2U_LIB.S9S_MB_2U(SCH_1):FM_PASSWORD_CLEAR_N

Q_RES  I13  R1345  [Q_RES_0402LF-0,5%,1/16W,CHIP,CA]
    1  JTAG_BMC_DBP_TDI_R      A  @S9S_MB_2U_LIB.S9S_MB_2U(SCH_1):JTAG_BMC_DBP_TDI_R
    2  JTAG_BMC_DBP_TDI      B  @S9S_MB_2U_LIB.S9S_MB_2U(SCH_1):JTAG_BMC_DBP_TDI

Q_RES  I34  R1346  [Q_RES_0402LF-1K,1%,1/16W,CHIP,A]
    1  PD_GTL2014_BMC_JTAG_VREF_2      A  @S9S_MB_2U_LIB.S9S_MB_2U(SCH_1):PD_GTL2014_BMC_JTAG_VREF_2
    2  GND                B  @S9S_MB_2U_LIB.S9S_MB_2U(SCH_1):GND

Q_RES  I10  R1347  [Q_RES_0402LF-1K,1%,1/16W,CHIP,A]
    1  PD_GTL2014_BMC_JTAG_VREF_1      A  @S9S_MB_2U_LIB.S9S_MB_2U(SCH_1):PD_GTL2014_BMC_JTAG_VREF_1
    2  GND                B  @S9S_MB_2U_LIB.S9S_MB_2U(SCH_1):GND

Q_RES  I88  R1348  [Q_RES_0402LF-0,5%,1/16W,CHIP,CA]
    1  JTAG_DBP_CPU_GTL_TCK_R1      A  @S9S_MB_2U_LIB.S9S_MB_2U(SCH_1):JTAG_DBP_CPU_GTL_TCK_R1
    2  JTAG_DBP_CPU_GTL_TCK      B  @S9S_MB_2U_LIB.S9S_MB_2U(SCH_1):JTAG_DBP_CPU_GTL_TCK

Q_RES  I87  R1349  [Q_RES_0402LF-0,5%,1/16W,CHIP,CA]
    1  JTAG_DBP_TCK_PCH_R      A  @S9S_MB_2U_LIB.S9S_MB_2U(SCH_1):JTAG_DBP_TCK_PCH_R
    2  JTAG_DBP_TCK_PCH      B  @S9S_MB_2U_LIB.S9S_MB_2U(SCH_1):JTAG_DBP_TCK_PCH

Q_RES  I82  R1350  [Q_RES_0402LF-100K,1%,1/16W,CHIA]
    1  RMII_OCP_BMC_CRSDV      A  @S9S_MB_2U_LIB.S9S_MB_2U(SCH_1):RMII_OCP_BMC_CRSDV
    2  GND                B  @S9S_MB_2U_LIB.S9S_MB_2U(SCH_1):GND

Q_RES  I86  R1351  [Q_RES_0402LF-100K,1%,1/16W,CHIA]
    1  RMII_OCP_BMC_RXD_0      A  @S9S_MB_2U_LIB.S9S_MB_2U(SCH_1):RMII_OCP_BMC_RXD_0
    2  GND                B  @S9S_MB_2U_LIB.S9S_MB_2U(SCH_1):GND

Q_RES  I87  R1352  [Q_RES_0402LF-100K,1%,1/16W,CHIA]
    1  RMII_OCP_BMC_RXD_1      A  @S9S_MB_2U_LIB.S9S_MB_2U(SCH_1):RMII_OCP_BMC_RXD_1
    2  GND                B  @S9S_MB_2U_LIB.S9S_MB_2U(SCH_1):GND

Q_RES  I92  R1353  [Q_RES_0402LF-100K,1%,1/16W,CHIA]
    1  RMII_BMC_OCP_TX_EN      A  @S9S_MB_2U_LIB.S9S_MB_2U(SCH_1):RMII_BMC_OCP_TX_EN
    2  GND                B  @S9S_MB_2U_LIB.S9S_MB_2U(SCH_1):GND

Q_RES  I91  R1354  [Q_RES_0402LF-100K,1%,1/16W,CHIA]
    1  RMII_BMC_OCP_TXD_0      A  @S9S_MB_2U_LIB.S9S_MB_2U(SCH_1):RMII_BMC_OCP_TXD_0
    2  GND                B  @S9S_MB_2U_LIB.S9S_MB_2U(SCH_1):GND

Q_RES  I93  R1355  [Q_RES_0402LF-100K,1%,1/16W,CHIA]
    1  RMII_BMC_OCP_TXD_1      A  @S9S_MB_2U_LIB.S9S_MB_2U(SCH_1):RMII_BMC_OCP_TXD_1
    2  GND                B  @S9S_MB_2U_LIB.S9S_MB_2U(SCH_1):GND

Q_RES  I96  R1356  [Q_RES_0402LF-1K,1%,1/16W,CHIP,A]
    1  RMII_BMC_OCP_RX_ER      A  @S9S_MB_2U_LIB.S9S_MB_2U(SCH_1):RMII_BMC_OCP_RX_ER
    2  GND                B  @S9S_MB_2U_LIB.S9S_MB_2U(SCH_1):GND

Q_RES  I188  R1361  [Q_RES_0402LF-0,5%,1/16W,CHIP,CA]
    1  CLK_100M_EDSFF2A_R_DP      A  @S9S_MB_2U_LIB.S9S_MB_2U(SCH_1):CLK_100M_EDSFF2A_R_DP
    2  CLK_100M_EDSFF2A_DP      B  @S9S_MB_2U_LIB.S9S_MB_2U(SCH_1):CLK_100M_EDSFF2A_DP

Q_RES  I187  R1362  [Q_RES_0402LF-0,5%,1/16W,CHIP,CA]
    1  CLK_100M_EDSFF2A_R_DN      A  @S9S_MB_2U_LIB.S9S_MB_2U(SCH_1):CLK_100M_EDSFF2A_R_DN
    2  CLK_100M_EDSFF2A_DN      B  @S9S_MB_2U_LIB.S9S_MB_2U(SCH_1):CLK_100M_EDSFF2A_DN

Q_RES  I206  R1363  [Q_RES_0402LF-0,5%,1/16W,CHIP,CA]
    1  CLK_100M_EDSFF2B_R_DP      A  @S9S_MB_2U_LIB.S9S_MB_2U(SCH_1):CLK_100M_EDSFF2B_R_DP
    2  CLK_100M_EDSFF2B_DP      B  @S9S_MB_2U_LIB.S9S_MB_2U(SCH_1):CLK_100M_EDSFF2B_DP

Q_RES  I205  R1364  [Q_RES_0402LF-0,5%,1/16W,CHIP,CA]
    1  CLK_100M_EDSFF2B_R_DN      A  @S9S_MB_2U_LIB.S9S_MB_2U(SCH_1):CLK_100M_EDSFF2B_R_DN
    2  CLK_100M_EDSFF2B_DN      B  @S9S_MB_2U_LIB.S9S_MB_2U(SCH_1):CLK_100M_EDSFF2B_DN

Q_RES  I116  R1365  [Q_RES_0402LF-1K,1%,1/16W,CHIP,A]
    2  GND                B  @S9S_MB_2U_LIB.S9S_MB_2U(SCH_1):GND
    1  FM_JTAG_TCK_MUX_SEL      A  @S9S_MB_2U_LIB.S9S_MB_2U(SCH_1):FM_JTAG_TCK_MUX_SEL

Q_RES  I64  R1366  [Q_RES_0402LF-100,1%,1/16W,CHIPB]
    1  JTAG_DBP_TDO       A  @S9S_MB_2U_LIB.S9S_MB_2U(SCH_1):JTAG_DBP_TDO
    2  JTAG_DBP_FB_TDO      B  @S9S_MB_2U_LIB.S9S_MB_2U(SCH_1):JTAG_DBP_FB_TDO

Q_RES  I65  R1367  [Q_RES_0402LF-100,1%,1/16W,CHIPB]
    2  JTAG_DBP_PRDY_R_N      B  @S9S_MB_2U_LIB.S9S_MB_2U(SCH_1):JTAG_DBP_PRDY_R_N
    1  JTAG_DBP_PRDY_N      A  @S9S_MB_2U_LIB.S9S_MB_2U(SCH_1):JTAG_DBP_PRDY_N

Q_RES  I48  R1368  [Q_RES_0402LF-1K,1%,1/16W,CHIP,A]
    1  PD_JTAG_DBP_B2      A  @S9S_MB_2U_LIB.S9S_MB_2U(SCH_1):PD_JTAG_DBP_B2
    2  GND                B  @S9S_MB_2U_LIB.S9S_MB_2U(SCH_1):GND

Q_RES  I47  R1369  [Q_RES_0402LF-1K,1%,1/16W,CHIP,A]
    1  PD_JTAG_DBP_B0      A  @S9S_MB_2U_LIB.S9S_MB_2U(SCH_1):PD_JTAG_DBP_B0
    2  GND                B  @S9S_MB_2U_LIB.S9S_MB_2U(SCH_1):GND

Q_RES  I98  R1370  [Q_RES_0402LF-100,1%,1/16W,EMPTA]
    1  P3V3_AUX           A  @S9S_MB_2U_LIB.S9S_MB_2U(SCH_1):P3V3_AUX
    2  FM_REMOTE_DEBUG_DET_R      B  @S9S_MB_2U_LIB.S9S_MB_2U(SCH_1):FM_REMOTE_DEBUG_DET_R

Q_RES  I106  R1371  [Q_RES_0402LF-1K,1%,1/16W,CHIP,A]
    1  JTAG_BMC_PCH_TCK      A  @S9S_MB_2U_LIB.S9S_MB_2U(SCH_1):JTAG_BMC_PCH_TCK
    2  GND                B  @S9S_MB_2U_LIB.S9S_MB_2U(SCH_1):GND

Q_RES  I102  R1372  [Q_RES_0402LF-1K,1%,1/16W,CHIP,A]
    2  GND                B  @S9S_MB_2U_LIB.S9S_MB_2U(SCH_1):GND
    1  FM_REMOTE_DEBUG_DET_R      A  @S9S_MB_2U_LIB.S9S_MB_2U(SCH_1):FM_REMOTE_DEBUG_DET_R

Q_RES  I105  R1373  [Q_RES_0402LF-1K,1%,1/16W,CHIP,A]
    1  JTAG_BMC_CPU_TCK      A  @S9S_MB_2U_LIB.S9S_MB_2U(SCH_1):JTAG_BMC_CPU_TCK
    2  GND                B  @S9S_MB_2U_LIB.S9S_MB_2U(SCH_1):GND

Q_RES  I103  R1374  [Q_RES_0402LF-1K,1%,1/16W,CHIP,A]
    1  PD_JTAG_BMC_NTRST_N      A  @S9S_MB_2U_LIB.S9S_MB_2U(SCH_1):PD_JTAG_BMC_NTRST_N
    2  GND                B  @S9S_MB_2U_LIB.S9S_MB_2U(SCH_1):GND

Q_RES  I97  R1375  [Q_RES_0402LF-10K,1%,1/16W,CHIPA]
    2  GND                B  @S9S_MB_2U_LIB.S9S_MB_2U(SCH_1):GND
    1  FM_BMC_EN_DET      A  @S9S_MB_2U_LIB.S9S_MB_2U(SCH_1):FM_BMC_EN_DET

Q_RES  I35  R1376  [Q_RES_0402LF-1K,1%,1/16W,CHIP,A]
    2  PU_GTL2014_BMC_JTAG_DIR_2      B  @S9S_MB_2U_LIB.S9S_MB_2U(SCH_1):PU_GTL2014_BMC_JTAG_DIR_2
    1  P3V3_AUX           A  @S9S_MB_2U_LIB.S9S_MB_2U(SCH_1):P3V3_AUX

Q_RES  I11  R1377  [Q_RES_0402LF-1K,1%,1/16W,CHIP,A]
    2  PU_GTL2014_BMC_JTAG_DIR_1      B  @S9S_MB_2U_LIB.S9S_MB_2U(SCH_1):PU_GTL2014_BMC_JTAG_DIR_1
    1  P3V3_AUX           A  @S9S_MB_2U_LIB.S9S_MB_2U(SCH_1):P3V3_AUX

Q_RES  I36  R1378  [Q_RES_0402LF-33.2,1%,1/16W,CHIA]
    1  JTAG_DBP_BMC_PRDY_R1_N      A  @S9S_MB_2U_LIB.S9S_MB_2U(SCH_1):JTAG_DBP_BMC_PRDY_R1_N
    2  JTAG_DBP_BMC_PRDY_N      B  @S9S_MB_2U_LIB.S9S_MB_2U(SCH_1):JTAG_DBP_BMC_PRDY_N

Q_RES  I12  R1379  [Q_RES_0402LF-33.2,1%,1/16W,CHIA]
    1  JTAG_DBP_BMC_PREQ_R1_N      A  @S9S_MB_2U_LIB.S9S_MB_2U(SCH_1):JTAG_DBP_BMC_PREQ_R1_N
    2  JTAG_BMC_DBP_PREQ_N      B  @S9S_MB_2U_LIB.S9S_MB_2U(SCH_1):JTAG_BMC_DBP_PREQ_N

Q_RES  I31  R1380  [Q_RES_0402LF-1K,1%,1/16W,CHIP,A]
    1  P3V3_AUX           A  @S9S_MB_2U_LIB.S9S_MB_2U(SCH_1):P3V3_AUX
    2  JTAG_BMC_DBP_TDO      B  @S9S_MB_2U_LIB.S9S_MB_2U(SCH_1):JTAG_BMC_DBP_TDO

Q_RES  I7   R1381  [Q_RES_0402LF-1K,1%,1/16W,CHIP,A]
    1  P3V3_AUX           A  @S9S_MB_2U_LIB.S9S_MB_2U(SCH_1):P3V3_AUX
    2  FM_BMC_CPU_FBRK_OUT_N      B  @S9S_MB_2U_LIB.S9S_MB_2U(SCH_1):FM_BMC_CPU_FBRK_OUT_N

Q_RES  I20  R1382  [Q_RES_0402LF-1K,1%,1/16W,CHIP,A]
    1  P3V3_AUX           A  @S9S_MB_2U_LIB.S9S_MB_2U(SCH_1):P3V3_AUX
    2  JTAG_DBP_BMC_PRDY_N      B  @S9S_MB_2U_LIB.S9S_MB_2U(SCH_1):JTAG_DBP_BMC_PRDY_N

Q_RES  I1   R1383  [Q_RES_0402LF-1K,1%,1/16W,CHIP,A]
    1  P3V3_AUX           A  @S9S_MB_2U_LIB.S9S_MB_2U(SCH_1):P3V3_AUX
    2  JTAG_BMC_DBP_PREQ_N      B  @S9S_MB_2U_LIB.S9S_MB_2U(SCH_1):JTAG_BMC_DBP_PREQ_N

Q_RES  I4   R1384  [Q_RES_0402LF-2K,1%,1/16W,CHIP,A]
    1  SMB_SML0_3V3AUX_SCL      A  @S9S_MB_2U_LIB.S9S_MB_2U(SCH_1):SMB_SML0_3V3AUX_SCL
    2  P3V3_AUX           B  @S9S_MB_2U_LIB.S9S_MB_2U(SCH_1):P3V3_AUX

Q_RES  I5   R1385  [Q_RES_0402LF-2K,1%,1/16W,CHIP,A]
    1  SMB_SML0_3V3AUX_SDA      A  @S9S_MB_2U_LIB.S9S_MB_2U(SCH_1):SMB_SML0_3V3AUX_SDA
    2  P3V3_AUX           B  @S9S_MB_2U_LIB.S9S_MB_2U(SCH_1):P3V3_AUX

Q_RES  I6   R1386  [Q_RES_0402LF-2K,1%,1/16W,CHIP,A]
    1  SMB_SML1_PMBUS_3V3AUX_PCH_SCL      A  @S9S_MB_2U_LIB.S9S_MB_2U(SCH_1):SMB_SML1_PMBUS_3V3AUX_PCH_SCL
    2  P3V3_AUX           B  @S9S_MB_2U_LIB.S9S_MB_2U(SCH_1):P3V3_AUX

Q_RES  I7   R1387  [Q_RES_0402LF-2K,1%,1/16W,CHIP,A]
    1  SMB_SML1_PMBUS_3V3AUX_PCH_SDA      A  @S9S_MB_2U_LIB.S9S_MB_2U(SCH_1):SMB_SML1_PMBUS_3V3AUX_PCH_SDA
    2  P3V3_AUX           B  @S9S_MB_2U_LIB.S9S_MB_2U(SCH_1):P3V3_AUX

Q_RES  I17  R1388  [Q_RES_0402LF-2K,1%,1/16W,CHIP,A]
    1  PWRGD_DRAMPWRGD_CPU1_EF_R_LVC1      A  @S9S_MB_2U_LIB.S9S_MB_2U(SCH_1):PWRGD_DRAMPWRGD_CPU1_EF_R_LVC1
    2  GND                B  @S9S_MB_2U_LIB.S9S_MB_2U(SCH_1):GND

Q_RES  I19  R1389  [Q_RES_0402LF-2K,1%,1/16W,CHIP,A]
    1  PWRGD_DRAMPWRGD_CPU1_GH_R_LVC1      A  @S9S_MB_2U_LIB.S9S_MB_2U(SCH_1):PWRGD_DRAMPWRGD_CPU1_GH_R_LVC1
    2  GND                B  @S9S_MB_2U_LIB.S9S_MB_2U(SCH_1):GND

Q_RES  I275  R1390  [Q_RES_0402LF-1K,1%,1/16W,EMPTYA]
    2  GND                B  @S9S_MB_2U_LIB.S9S_MB_2U(SCH_1):GND
    1  FM_PLD_CLKS_DEV_EN      A  @S9S_MB_2U_LIB.S9S_MB_2U(SCH_1):FM_PLD_CLKS_DEV_EN

Q_RES  I61  R1391  [Q_RES_0402LF-240,1%,1/16W,EMPTA]
    1  GND                A  @S9S_MB_2U_LIB.S9S_MB_2U(SCH_1):GND
    2  FM_S3M_CPU0_LVC1_GPIO_2      B  @S9S_MB_2U_LIB.S9S_MB_2U(SCH_1):FM_S3M_CPU0_LVC1_GPIO_2

Q_RES  I62  R1392  [Q_RES_0402LF-240,1%,1/16W,EMPTA]
    1  GND                A  @S9S_MB_2U_LIB.S9S_MB_2U(SCH_1):GND
    2  FM_S3M_CPU0_LVC1_GPIO_3      B  @S9S_MB_2U_LIB.S9S_MB_2U(SCH_1):FM_S3M_CPU0_LVC1_GPIO_3

Q_RES  I66  R1393  [Q_RES_0402LF-240,1%,1/16W,EMPTA]
    1  GND                A  @S9S_MB_2U_LIB.S9S_MB_2U(SCH_1):GND
    2  FM_S3M_CPU1_LVC1_GPIO_2      B  @S9S_MB_2U_LIB.S9S_MB_2U(SCH_1):FM_S3M_CPU1_LVC1_GPIO_2

Q_RES  I67  R1394  [Q_RES_0402LF-240,1%,1/16W,EMPTA]
    1  GND                A  @S9S_MB_2U_LIB.S9S_MB_2U(SCH_1):GND
    2  FM_S3M_CPU1_LVC1_GPIO_3      B  @S9S_MB_2U_LIB.S9S_MB_2U(SCH_1):FM_S3M_CPU1_LVC1_GPIO_3

Q_RES  I102  R1395  [Q_RES_0402LF-33.2,1%,1/16W,CHIA]
    2  SPI_TPM_CS_N       B  @S9S_MB_2U_LIB.S9S_MB_2U(SCH_1):SPI_TPM_CS_N
    1  SPI_PCH_TPM_CS_N      A  @S9S_MB_2U_LIB.S9S_MB_2U(SCH_1):SPI_PCH_TPM_CS_N

Q_RES  I167  R1396  [Q_RES_0402LF-10K,1%,1/16W,CHIPA]
    2  P3V3_AUX           B  @S9S_MB_2U_LIB.S9S_MB_2U(SCH_1):P3V3_AUX
    1  FM_M2_SSD_1_PEDET      A  @S9S_MB_2U_LIB.S9S_MB_2U(SCH_1):FM_M2_SSD_1_PEDET

Q_RES  I22  R1398  [Q_RES_0402LF-2K,1%,1/16W,CHIP,A]
    1  PWRGD_CPU1_LVC1_R      A  @S9S_MB_2U_LIB.S9S_MB_2U(SCH_1):PWRGD_CPU1_LVC1_R
    2  GND                B  @S9S_MB_2U_LIB.S9S_MB_2U(SCH_1):GND

Q_RES  I269  R1399  [Q_RES_0402LF-10K,1%,1/16W,CHIPA]
    2  P3V3_AUX           B  @S9S_MB_2U_LIB.S9S_MB_2U(SCH_1):P3V3_AUX
    1  FM_PFR_DSW_PWROK_N      A  @S9S_MB_2U_LIB.S9S_MB_2U(SCH_1):FM_PFR_DSW_PWROK_N

Q_RES  I277  R1401  [Q_RES_0402LF-10K,1%,1/16W,CHIPA]
    1  PU_MAIN_FPGA_CONFIG_DONE      A  @S9S_MB_2U_LIB.S9S_MB_2U(SCH_1):PU_MAIN_FPGA_CONFIG_DONE
    2  P3V3_AUX           B  @S9S_MB_2U_LIB.S9S_MB_2U(SCH_1):P3V3_AUX

Q_RES  I23  R1402  [Q_RES_0402LF-2K,1%,1/16W,CHIP,A]
    1  PWRGD_SYS_PWROK      A  @S9S_MB_2U_LIB.S9S_MB_2U(SCH_1):PWRGD_SYS_PWROK
    2  GND                B  @S9S_MB_2U_LIB.S9S_MB_2U(SCH_1):GND

Q_RES  I24  R1403  [Q_RES_0402LF-2K,1%,1/16W,CHIP,A]
    1  PWRGD_PCH_PWROK      A  @S9S_MB_2U_LIB.S9S_MB_2U(SCH_1):PWRGD_PCH_PWROK
    2  GND                B  @S9S_MB_2U_LIB.S9S_MB_2U(SCH_1):GND

Q_RES  I25  R1404  [Q_RES_0402LF-2K,1%,1/16W,CHIP,A]
    2  GND                B  @S9S_MB_2U_LIB.S9S_MB_2U(SCH_1):GND
    1  FM_PCH_P1V8_AUX_EN      A  @S9S_MB_2U_LIB.S9S_MB_2U(SCH_1):FM_PCH_P1V8_AUX_EN

Q_RES  I26  R1405  [Q_RES_0402LF-2K,1%,1/16W,CHIP,A]
    2  GND                B  @S9S_MB_2U_LIB.S9S_MB_2U(SCH_1):GND
    1  FM_PVCCIN_CPU0_R_EN      A  @S9S_MB_2U_LIB.S9S_MB_2U(SCH_1):FM_PVCCIN_CPU0_R_EN

Q_RES  I51  R1406  [Q_RES_0402LF-2K,1%,1/16W,CHIP,A]
    2  GND                B  @S9S_MB_2U_LIB.S9S_MB_2U(SCH_1):GND
    1  FM_PVCCIN_CPU1_R_EN      A  @S9S_MB_2U_LIB.S9S_MB_2U(SCH_1):FM_PVCCIN_CPU1_R_EN

Q_RES  I52  R1407  [Q_RES_0402LF-2K,1%,1/16W,CHIP,A]
    2  GND                B  @S9S_MB_2U_LIB.S9S_MB_2U(SCH_1):GND
    1  FM_PVCCINFAON_CPU0_R_EN      A  @S9S_MB_2U_LIB.S9S_MB_2U(SCH_1):FM_PVCCINFAON_CPU0_R_EN

Q_RES  I53  R1408  [Q_RES_0402LF-2K,1%,1/16W,CHIP,A]
    2  GND                B  @S9S_MB_2U_LIB.S9S_MB_2U(SCH_1):GND
    1  FM_PVCCINFAON_CPU1_R_EN      A  @S9S_MB_2U_LIB.S9S_MB_2U(SCH_1):FM_PVCCINFAON_CPU1_R_EN

Q_RES  I55  R1409  [Q_RES_0402LF-2K,1%,1/16W,CHIP,A]
    2  GND                B  @S9S_MB_2U_LIB.S9S_MB_2U(SCH_1):GND
    1  FM_PVCCFA_EHV_CPU0_R_EN      A  @S9S_MB_2U_LIB.S9S_MB_2U(SCH_1):FM_PVCCFA_EHV_CPU0_R_EN

Q_RES  I54  R1410  [Q_RES_0402LF-2K,1%,1/16W,CHIP,A]
    2  GND                B  @S9S_MB_2U_LIB.S9S_MB_2U(SCH_1):GND
    1  FM_PVCCFA_EHV_CPU1_R_EN      A  @S9S_MB_2U_LIB.S9S_MB_2U(SCH_1):FM_PVCCFA_EHV_CPU1_R_EN

Q_RES  I56  R1411  [Q_RES_0402LF-2K,1%,1/16W,CHIP,A]
    2  GND                B  @S9S_MB_2U_LIB.S9S_MB_2U(SCH_1):GND
    1  FM_PVCCFA_EHV_FIVRA_CPU0_R_EN      A  @S9S_MB_2U_LIB.S9S_MB_2U(SCH_1):FM_PVCCFA_EHV_FIVRA_CPU0_R_EN

Q_RES  I57  R1412  [Q_RES_0402LF-2K,1%,1/16W,CHIP,A]
    2  GND                B  @S9S_MB_2U_LIB.S9S_MB_2U(SCH_1):GND
    1  FM_PVCCFA_EHV_FIVRA_CPU1_R_EN      A  @S9S_MB_2U_LIB.S9S_MB_2U(SCH_1):FM_PVCCFA_EHV_FIVRA_CPU1_R_EN

Q_RES  I59  R1413  [Q_RES_0402LF-2K,1%,1/16W,CHIP,A]
    2  GND                B  @S9S_MB_2U_LIB.S9S_MB_2U(SCH_1):GND
    1  FM_PVCCD_HV_CPU0_EN      A  @S9S_MB_2U_LIB.S9S_MB_2U(SCH_1):FM_PVCCD_HV_CPU0_EN

Q_RES  I58  R1414  [Q_RES_0402LF-2K,1%,1/16W,CHIP,A]
    2  GND                B  @S9S_MB_2U_LIB.S9S_MB_2U(SCH_1):GND
    1  FM_PVCCD_HV_CPU1_EN      A  @S9S_MB_2U_LIB.S9S_MB_2U(SCH_1):FM_PVCCD_HV_CPU1_EN

Q_RES  I4   R1415  [Q_RES_0402LF-2K,1%,1/16W,CHIP,A]
    1  RST_CPU0_LVC1_R_N      A  @S9S_MB_2U_LIB.S9S_MB_2U(SCH_1):RST_CPU0_LVC1_R_N
    2  GND                B  @S9S_MB_2U_LIB.S9S_MB_2U(SCH_1):GND

Q_RES  I5   R1416  [Q_RES_0402LF-2K,1%,1/16W,CHIP,A]
    1  RST_CPU1_LVC1_R_N      A  @S9S_MB_2U_LIB.S9S_MB_2U(SCH_1):RST_CPU1_LVC1_R_N
    2  GND                B  @S9S_MB_2U_LIB.S9S_MB_2U(SCH_1):GND

Q_RES  I7   R1417  [Q_RES_0402LF-2K,1%,1/16W,CHIP,A]
    1  RST_PCIE_CPU0_DEV_PERST_N      A  @S9S_MB_2U_LIB.S9S_MB_2U(SCH_1):RST_PCIE_CPU0_DEV_PERST_N
    2  GND                B  @S9S_MB_2U_LIB.S9S_MB_2U(SCH_1):GND

Q_RES  I6   R1418  [Q_RES_0402LF-2K,1%,1/16W,CHIP,A]
    1  RST_PCIE_CPU1_DEV_PERST_N      A  @S9S_MB_2U_LIB.S9S_MB_2U(SCH_1):RST_PCIE_CPU1_DEV_PERST_N
    2  GND                B  @S9S_MB_2U_LIB.S9S_MB_2U(SCH_1):GND

Q_RES  I8   R1419  [Q_RES_0402LF-2K,1%,1/16W,CHIP,A]
    1  RST_PCIE_PCH_DEV_PERST_N      A  @S9S_MB_2U_LIB.S9S_MB_2U(SCH_1):RST_PCIE_PCH_DEV_PERST_N
    2  GND                B  @S9S_MB_2U_LIB.S9S_MB_2U(SCH_1):GND

Q_RES  I9   R1420  [Q_RES_0402LF-2K,1%,1/16W,CHIP,A]
    1  RST_PLTRST_PLD_B_N      A  @S9S_MB_2U_LIB.S9S_MB_2U(SCH_1):RST_PLTRST_PLD_B_N
    2  GND                B  @S9S_MB_2U_LIB.S9S_MB_2U(SCH_1):GND

Q_RES  I10  R1421  [Q_RES_0402LF-2K,1%,1/16W,CHIP,A]
    1  RST_RSMRST_PLD_R_N      A  @S9S_MB_2U_LIB.S9S_MB_2U(SCH_1):RST_RSMRST_PLD_R_N
    2  GND                B  @S9S_MB_2U_LIB.S9S_MB_2U(SCH_1):GND

Q_RES  I44  R1423  [Q_RES_0402LF-33.2,1%,1/16W,CHIA]
    1  PWRGD_SYS_PWROK_R      A  @S9S_MB_2U_LIB.S9S_MB_2U(SCH_1):PWRGD_SYS_PWROK_R
    2  PWRGD_SYS_PWROK      B  @S9S_MB_2U_LIB.S9S_MB_2U(SCH_1):PWRGD_SYS_PWROK

Q_RES  I197  R1425  [Q_RES_0402LF-100,1%,1/16W,CHIPA]
    2  PVCCIO_PLDIO5      B  @S9S_MB_2U_LIB.S9S_MB_2U(SCH_1):PVCCIO_PLDIO5
    1  H_CPU0_MEMHOT_OUT_LVC1_N      A  @S9S_MB_2U_LIB.S9S_MB_2U(SCH_1):H_CPU0_MEMHOT_OUT_LVC1_N

Q_RES  I198  R1426  [Q_RES_0402LF-100,1%,1/16W,CHIPA]
    2  PVCCIO_PLDIO5      B  @S9S_MB_2U_LIB.S9S_MB_2U(SCH_1):PVCCIO_PLDIO5
    1  H_CPU1_MEMHOT_OUT_LVC1_N      A  @S9S_MB_2U_LIB.S9S_MB_2U(SCH_1):H_CPU1_MEMHOT_OUT_LVC1_N

Q_RES  I199  R1427  [Q_RES_0402LF-100,1%,1/16W,CHIPA]
    2  PVCCIO_PLDIO5      B  @S9S_MB_2U_LIB.S9S_MB_2U(SCH_1):PVCCIO_PLDIO5
    1  H_CPU0_THERMTRIP_LVC1_N      A  @S9S_MB_2U_LIB.S9S_MB_2U(SCH_1):H_CPU0_THERMTRIP_LVC1_N

Q_RES  I202  R1428  [Q_RES_0402LF-100,1%,1/16W,CHIPA]
    2  PVCCIO_PLDIO5      B  @S9S_MB_2U_LIB.S9S_MB_2U(SCH_1):PVCCIO_PLDIO5
    1  H_CPU1_THERMTRIP_LVC1_N      A  @S9S_MB_2U_LIB.S9S_MB_2U(SCH_1):H_CPU1_THERMTRIP_LVC1_N

Q_RES  I205  R1429  [Q_RES_0402LF-100,1%,1/16W,CHIPA]
    2  PVCCIO_PLDIO5      B  @S9S_MB_2U_LIB.S9S_MB_2U(SCH_1):PVCCIO_PLDIO5
    1  H_CPU0_MEMTRIP_LVC1_N      A  @S9S_MB_2U_LIB.S9S_MB_2U(SCH_1):H_CPU0_MEMTRIP_LVC1_N

Q_RES  I203  R1430  [Q_RES_0402LF-100,1%,1/16W,CHIPA]
    2  PVCCIO_PLDIO5      B  @S9S_MB_2U_LIB.S9S_MB_2U(SCH_1):PVCCIO_PLDIO5
    1  H_CPU1_MEMTRIP_LVC1_N      A  @S9S_MB_2U_LIB.S9S_MB_2U(SCH_1):H_CPU1_MEMTRIP_LVC1_N

Q_RES  I213  R1431  [Q_RES_0402LF-150,1%,1/16W,CHIPA]
    2  PVCCIO_PLDIO5      B  @S9S_MB_2U_LIB.S9S_MB_2U(SCH_1):PVCCIO_PLDIO5
    1  H_CPU_ERR0_LVC1_N      A  @S9S_MB_2U_LIB.S9S_MB_2U(SCH_1):H_CPU_ERR0_LVC1_N

Q_RES  I214  R1432  [Q_RES_0402LF-150,1%,1/16W,CHIPA]
    2  PVCCIO_PLDIO5      B  @S9S_MB_2U_LIB.S9S_MB_2U(SCH_1):PVCCIO_PLDIO5
    1  H_CPU_ERR1_LVC1_N      A  @S9S_MB_2U_LIB.S9S_MB_2U(SCH_1):H_CPU_ERR1_LVC1_N

Q_RES  I215  R1433  [Q_RES_0402LF-150,1%,1/16W,CHIPA]
    2  PVCCIO_PLDIO5      B  @S9S_MB_2U_LIB.S9S_MB_2U(SCH_1):PVCCIO_PLDIO5
    1  H_CPU_ERR2_LVC1_N      A  @S9S_MB_2U_LIB.S9S_MB_2U(SCH_1):H_CPU_ERR2_LVC1_N

Q_RES  I216  R1434  [Q_RES_0402LF-10K,1%,1/16W,CHIPA]
    2  P3V3_AUX           B  @S9S_MB_2U_LIB.S9S_MB_2U(SCH_1):P3V3_AUX
    1  FM_SYS_THROTTLE_R_N      A  @S9S_MB_2U_LIB.S9S_MB_2U(SCH_1):FM_SYS_THROTTLE_R_N

Q_RES  I221  R1435  [Q_RES_0402LF-10K,1%,1/16W,CHIPA]
    2  P3V3_AUX           B  @S9S_MB_2U_LIB.S9S_MB_2U(SCH_1):P3V3_AUX
    1  FM_ADR_TRIGGER_N      A  @S9S_MB_2U_LIB.S9S_MB_2U(SCH_1):FM_ADR_TRIGGER_N

Q_RES  I278  R1436  [Q_RES_0402LF-10K,1%,1/16W,CHIPA]
    1  PU_MAIN_FPGA_STATUS_N      A  @S9S_MB_2U_LIB.S9S_MB_2U(SCH_1):PU_MAIN_FPGA_STATUS_N
    2  P3V3_AUX           B  @S9S_MB_2U_LIB.S9S_MB_2U(SCH_1):P3V3_AUX

Q_RES  I224  R1437  [Q_RES_0402LF-10K,1%,1/16W,CHIPA]
    2  P3V3_AUX           B  @S9S_MB_2U_LIB.S9S_MB_2U(SCH_1):P3V3_AUX
    1  FM_PLD_HEARTBEAT_LVC3      A  @S9S_MB_2U_LIB.S9S_MB_2U(SCH_1):FM_PLD_HEARTBEAT_LVC3

Q_RES  I226  R1438  [Q_RES_0402LF-10K,1%,1/16W,CHIPA]
    2  P3V3_AUX           B  @S9S_MB_2U_LIB.S9S_MB_2U(SCH_1):P3V3_AUX
    1  JTAG_PLD_TDI_R      A  @S9S_MB_2U_LIB.S9S_MB_2U(SCH_1):JTAG_PLD_TDI_R

Q_RES  I229  R1439  [Q_RES_0402LF-10K,1%,1/16W,CHIPA]
    2  P3V3_AUX           B  @S9S_MB_2U_LIB.S9S_MB_2U(SCH_1):P3V3_AUX
    1  JTAG_PLD_TMS_R      A  @S9S_MB_2U_LIB.S9S_MB_2U(SCH_1):JTAG_PLD_TMS_R

Q_RES  I231  R1440  [Q_RES_0402LF-10K,1%,1/16W,EMPTA]
    2  P3V3_AUX           B  @S9S_MB_2U_LIB.S9S_MB_2U(SCH_1):P3V3_AUX
    1  JTAG_PLD_TDO_R      A  @S9S_MB_2U_LIB.S9S_MB_2U(SCH_1):JTAG_PLD_TDO_R

Q_RES  I235  R1441  [Q_RES_0402LF-1K,1%,1/16W,CHIP,A]
    1  JTAG_PLD_TCK_R      A  @S9S_MB_2U_LIB.S9S_MB_2U(SCH_1):JTAG_PLD_TCK_R
    2  GND                B  @S9S_MB_2U_LIB.S9S_MB_2U(SCH_1):GND

Q_RES  I48  R1442  [Q_RES_0402LF-33.2,1%,1/16W,CHIA]
    1  PWRGD_PCH_PWROK_R      A  @S9S_MB_2U_LIB.S9S_MB_2U(SCH_1):PWRGD_PCH_PWROK_R
    2  PWRGD_PCH_PWROK      B  @S9S_MB_2U_LIB.S9S_MB_2U(SCH_1):PWRGD_PCH_PWROK

Q_RES  I49  R1443  [Q_RES_0402LF-33.2,1%,1/16W,CHIA]
    2  PWRGD_CPUPWRGD_LVC1_R      B  @S9S_MB_2U_LIB.S9S_MB_2U(SCH_1):PWRGD_CPUPWRGD_LVC1_R
    1  PWRGD_CPUPWRGD_LVC1      A  @S9S_MB_2U_LIB.S9S_MB_2U(SCH_1):PWRGD_CPUPWRGD_LVC1

Q_RES  I54  R1444  [Q_RES_0402LF-33.2,1%,1/16W,CHIA]
    2  PWRGD_P1V8_PCH_AUX_PLD      B  @S9S_MB_2U_LIB.S9S_MB_2U(SCH_1):PWRGD_P1V8_PCH_AUX_PLD
    1  PWRGD_P1V8_PCH_AUX      A  @S9S_MB_2U_LIB.S9S_MB_2U(SCH_1):PWRGD_P1V8_PCH_AUX

Q_RES  I155  R1445  [Q_RES_0402LF-2K,1%,1/16W,CHIP,A]
    2  GND                B  @S9S_MB_2U_LIB.S9S_MB_2U(SCH_1):GND
    1  FM_PVNN_MAIN_CPU0_EN      A  @S9S_MB_2U_LIB.S9S_MB_2U(SCH_1):FM_PVNN_MAIN_CPU0_EN

Q_RES  I61  R1446  [Q_RES_0402LF-33.2,1%,1/16W,CHIA]
    2  PWRGD_PS_PWROK_PLD_R      B  @S9S_MB_2U_LIB.S9S_MB_2U(SCH_1):PWRGD_PS_PWROK_PLD_R
    1  PWRGD_PS_PWROK_PLD      A  @S9S_MB_2U_LIB.S9S_MB_2U(SCH_1):PWRGD_PS_PWROK_PLD

Q_RES  I68  R1447  [Q_RES_0402LF-33.2,1%,1/16W,CHIA]
    2  FM_CPU0_SKTOCC_LVT3_PLD_N      B  @S9S_MB_2U_LIB.S9S_MB_2U(SCH_1):FM_CPU0_SKTOCC_LVT3_PLD_N
    1  FM_CPU0_SKTOCC_LVT3_N      A  @S9S_MB_2U_LIB.S9S_MB_2U(SCH_1):FM_CPU0_SKTOCC_LVT3_N

Q_RES  I62  R1448  [Q_RES_0402LF-33.2,1%,1/16W,CHIA]
    2  FM_CPU1_SKTOCC_LVT3_PLD_N      B  @S9S_MB_2U_LIB.S9S_MB_2U(SCH_1):FM_CPU1_SKTOCC_LVT3_PLD_N
    1  FM_CPU1_SKTOCC_LVT3_N      A  @S9S_MB_2U_LIB.S9S_MB_2U(SCH_1):FM_CPU1_SKTOCC_LVT3_N

Q_RES  I41  R1449  [Q_RES_0402LF-10K,1%,1/16W,CHIPA]
    1  P3V3_AUX           A  @S9S_MB_2U_LIB.S9S_MB_2U(SCH_1):P3V3_AUX
    2  FM_BIOS_POST_CMPLT_N      B  @S9S_MB_2U_LIB.S9S_MB_2U(SCH_1):FM_BIOS_POST_CMPLT_N

Q_RES  I42  R1450  [Q_RES_0402LF-10K,1%,1/16W,CHIPA]
    1  P3V3_AUX           A  @S9S_MB_2U_LIB.S9S_MB_2U(SCH_1):P3V3_AUX
    2  FM_THROTTLE_N      B  @S9S_MB_2U_LIB.S9S_MB_2U(SCH_1):FM_THROTTLE_N

Q_RES  I109  R1451  [Q_RES_0402LF-2K,1%,1/16W,CHIP,A]
    1  PU_SMB_SML3_3V3AUX_PCH_SCL      A  @S9S_MB_2U_LIB.S9S_MB_2U(SCH_1):PU_SMB_SML3_3V3AUX_PCH_SCL
    2  P3V3_AUX           B  @S9S_MB_2U_LIB.S9S_MB_2U(SCH_1):P3V3_AUX

Q_RES  I112  R1452  [Q_RES_0402LF-2K,1%,1/16W,CHIP,A]
    1  PU_SMB_SML3_3V3AUX_PCH_SDA      A  @S9S_MB_2U_LIB.S9S_MB_2U(SCH_1):PU_SMB_SML3_3V3AUX_PCH_SDA
    2  P3V3_AUX           B  @S9S_MB_2U_LIB.S9S_MB_2U(SCH_1):P3V3_AUX

Q_RES  I120  R1453  [Q_RES_0402LF-2K,1%,1/16W,CHIP,A]
    1  PU_SMB_SML4_3V3AUX_PCH_SCL      A  @S9S_MB_2U_LIB.S9S_MB_2U(SCH_1):PU_SMB_SML4_3V3AUX_PCH_SCL
    2  P3V3_AUX           B  @S9S_MB_2U_LIB.S9S_MB_2U(SCH_1):P3V3_AUX

Q_RES  I121  R1454  [Q_RES_0402LF-2K,1%,1/16W,CHIP,A]
    1  PU_SMB_SML4_3V3AUX_PCH_SDA      A  @S9S_MB_2U_LIB.S9S_MB_2U(SCH_1):PU_SMB_SML4_3V3AUX_PCH_SDA
    2  P3V3_AUX           B  @S9S_MB_2U_LIB.S9S_MB_2U(SCH_1):P3V3_AUX

Q_RES  I27  R1455  [Q_RES_0402LF-49.9     ,1%  ,1/A]
    1  FM_ADR_MODE0_R      A  @S9S_MB_2U_LIB.S9S_MB_2U(SCH_1):FM_ADR_MODE0_R
    2  FM_ADR_MODE0       B  @S9S_MB_2U_LIB.S9S_MB_2U(SCH_1):FM_ADR_MODE0

Q_RES  I28  R1456  [Q_RES_0402LF-49.9     ,1%  ,1/A]
    2  FM_CPU_RMCA_CATERR_DLY_N      B  @S9S_MB_2U_LIB.S9S_MB_2U(SCH_1):FM_CPU_RMCA_CATERR_DLY_N
    1  FM_CPU_RMCA_CATERR_DLY_LVT3_R_N      A  @S9S_MB_2U_LIB.S9S_MB_2U(SCH_1):FM_CPU_RMCA_CATERR_DLY_LVT3_R_N

Q_RES  I36  R1457  [Q_RES_0402LF-10K,1%,1/16W,CHIPA]
    2  GND                B  @S9S_MB_2U_LIB.S9S_MB_2U(SCH_1):GND
    1  FM_XTAL_INPUT_FREQUENCY_1_MGPIO      A  @S9S_MB_2U_LIB.S9S_MB_2U(SCH_1):FM_XTAL_INPUT_FREQUENCY_1_MGPIO_TEST5

Q_RES  I50  R1458  [Q_RES_0402LF-10K,1%,1/16W,CHIPA]
    1  P3V3_AUX           A  @S9S_MB_2U_LIB.S9S_MB_2U(SCH_1):P3V3_AUX
    2  IRQ_SMI_ACTIVE_N      B  @S9S_MB_2U_LIB.S9S_MB_2U(SCH_1):IRQ_SMI_ACTIVE_N

Q_RES  I51  R1459  [Q_RES_0402LF-10K,1%,1/16W,CHIPA]
    1  P3V3_AUX           A  @S9S_MB_2U_LIB.S9S_MB_2U(SCH_1):P3V3_AUX
    2  IRQ_PCH_CPU_NMI_EVENT_R_N      B  @S9S_MB_2U_LIB.S9S_MB_2U(SCH_1):IRQ_PCH_CPU_NMI_EVENT_R_N

Q_RES  I176  R1460  [Q_RES_0402LF-2.2K ,5%,1/16W,CHA]
    1  SMB_SENSOR_3V3AUX_SDA      A  @S9S_MB_2U_LIB.S9S_MB_2U(SCH_1):SMB_SENSOR_3V3AUX_SDA
    2  P3V3_AUX           B  @S9S_MB_2U_LIB.S9S_MB_2U(SCH_1):P3V3_AUX

Q_RES  I80  R1461  [Q_RES_0402LF-0,5%,1/16W,CHIP,CA]
    2  FM_SUSACK_N        B  @S9S_MB_2U_LIB.S9S_MB_2U(SCH_1):FM_SUSACK_N
    1  FM_EUP_LOT6_N      A  @S9S_MB_2U_LIB.S9S_MB_2U(SCH_1):FM_EUP_LOT6_N

Q_RES  I274  R1462  [Q_RES_0402LF-1K,1%,1/16W,CHIP,A]
    1  PD_CK440_SBI_CLK      A  @S9S_MB_2U_LIB.S9S_MB_2U(SCH_1):PD_CK440_SBI_CLK
    2  GND                B  @S9S_MB_2U_LIB.S9S_MB_2U(SCH_1):GND

Q_RES  I129  R1463  [Q_RES_0402LF-0,5%,1/16W,CHIP,CA]
    2  P1V05_PCH_PLL_AUX      B  @S9S_MB_2U_LIB.S9S_MB_2U(SCH_1):P1V05_PCH_PLL_AUX
    1  P1V05_PCH_AUX      A  @S9S_MB_2U_LIB.S9S_MB_2U(SCH_1):P1V05_PCH_AUX

Q_RES  I144  R1464  [Q_RES_0402LF-0,5%,1/16W,CHIP,CA]
    2  P1V8_PCH_PLL_AUX      B  @S9S_MB_2U_LIB.S9S_MB_2U(SCH_1):P1V8_PCH_PLL_AUX
    1  P1V8_PCH_AUX       A  @S9S_MB_2U_LIB.S9S_MB_2U(SCH_1):P1V8_PCH_AUX

Q_RES  I226  R1465  [Q_RES_0402LF-10K,1%,1/16W,EMPTA]
    1  P3V3_AUX           A  @S9S_MB_2U_LIB.S9S_MB_2U(SCH_1):P3V3_AUX
    2  IRQ_BMC_CPU_NMI_R1      B  @S9S_MB_2U_LIB.S9S_MB_2U(SCH_1):IRQ_BMC_CPU_NMI_R1

Q_RES  I232  R1467  [Q_RES_0402LF-4.7K,1%,1/16W,CHIA]
    2  SMB_PLD_3V3AUX_SDA_R      B  @S9S_MB_2U_LIB.S9S_MB_2U(SCH_1):SMB_PLD_3V3AUX_SDA_R
    1  P3V3_AUX           A  @S9S_MB_2U_LIB.S9S_MB_2U(SCH_1):P3V3_AUX

Q_RES  I55  R1469  [Q_RES_0402LF-33.2,1%,1/16W,CHIA]
    1  RST_PLTRST_PLD_B_N      A  @S9S_MB_2U_LIB.S9S_MB_2U(SCH_1):RST_PLTRST_PLD_B_N
    2  RST_PLTRST_B_N      B  @S9S_MB_2U_LIB.S9S_MB_2U(SCH_1):RST_PLTRST_B_N

Q_RES  I56  R1470  [Q_RES_0402LF-33.2,1%,1/16W,CHIA]
    1  RST_PLTRST_PLD_B_N      A  @S9S_MB_2U_LIB.S9S_MB_2U(SCH_1):RST_PLTRST_PLD_B_N
    2  RST_PLTRST_B_MUX_N      B  @S9S_MB_2U_LIB.S9S_MB_2U(SCH_1):RST_PLTRST_B_MUX_N

Q_RES  I267  R1471  [Q_RES_0402LF-4.75K,1%,1/16W,CHA]
    1  P3V3_AUX           A  @S9S_MB_2U_LIB.S9S_MB_2U(SCH_1):P3V3_AUX
    2  FM_CLK_CK440_SS_EN      B  @S9S_MB_2U_LIB.S9S_MB_2U(SCH_1):FM_CLK_CK440_SS_EN

Q_RES  I144  R1472  [Q_RES_0402LF-33.2,1%,1/16W,CHIA]
    1  JTAG_DBP_PRESENT_R_N      A  @S9S_MB_2U_LIB.S9S_MB_2U(SCH_1):JTAG_DBP_PRESENT_R_N
    2  FM_BMC_DBP_PRESENT_R_N      B  @S9S_MB_2U_LIB.S9S_MB_2U(SCH_1):FM_BMC_DBP_PRESENT_R_N

Q_RES  I261  R1473  [Q_RES_0402LF-1K,1%,1/16W,CHIP,A]
    2  P3V3_AUX           B  @S9S_MB_2U_LIB.S9S_MB_2U(SCH_1):P3V3_AUX
    1  FM_RST_PERST_BIT1      A  @S9S_MB_2U_LIB.S9S_MB_2U(SCH_1):FM_RST_PERST_BIT1

Q_RES  I262  R1474  [Q_RES_0402LF-1K,1%,1/16W,CHIP,A]
    2  P3V3_AUX           B  @S9S_MB_2U_LIB.S9S_MB_2U(SCH_1):P3V3_AUX
    1  FM_RST_PERST_BIT2      A  @S9S_MB_2U_LIB.S9S_MB_2U(SCH_1):FM_RST_PERST_BIT2

Q_RES  I44  R1475  [Q_RES_0402LF-1K,1%,1/16W,EMPTYA]
    1  P3V3_AUX           A  @S9S_MB_2U_LIB.S9S_MB_2U(SCH_1):P3V3_AUX
    2  FM_PCH_RING_OSC_BYPASS_MGPIO_TE      B  @S9S_MB_2U_LIB.S9S_MB_2U(SCH_1):FM_PCH_RING_OSC_BYPASS_MGPIO_TEST2

Q_RES  I43  R1476  [Q_RES_0402LF-1K,1%,1/16W,CHIP,A]
    2  GND                B  @S9S_MB_2U_LIB.S9S_MB_2U(SCH_1):GND
    1  FM_PCH_RING_OSC_BYPASS_MGPIO_TE      A  @S9S_MB_2U_LIB.S9S_MB_2U(SCH_1):FM_PCH_RING_OSC_BYPASS_MGPIO_TEST2

Q_RES  I47  R1477  [Q_RES_0402LF-1K,1%,1/16W,EMPTYA]
    1  P3V3_AUX           A  @S9S_MB_2U_LIB.S9S_MB_2U(SCH_1):P3V3_AUX
    2  FM_PCH_XTAL_INPUT_MODE_MGPIO_TE      B  @S9S_MB_2U_LIB.S9S_MB_2U(SCH_1):FM_PCH_XTAL_INPUT_MODE_MGPIO_TEST3

Q_RES  I50  R1478  [Q_RES_0402LF-10K,1%,1/16W,CHIPA]
    2  GND                B  @S9S_MB_2U_LIB.S9S_MB_2U(SCH_1):GND
    1  FM_PCH_XTAL_INPUT_MODE_MGPIO_TE      A  @S9S_MB_2U_LIB.S9S_MB_2U(SCH_1):FM_PCH_XTAL_INPUT_MODE_MGPIO_TEST3

Q_RES  I52  R1479  [Q_RES_0402LF-33.2,1%,1/16W,CHIA]
    1  ESPI_LFRAME_N_BMC_CS0_N      A  @S9S_MB_2U_LIB.S9S_MB_2U(SCH_1):ESPI_LFRAME_N_BMC_CS0_N
    2  ESPI_HOST_LPC_BMC_LFRAME_N      B  @S9S_MB_2U_LIB.S9S_MB_2U(SCH_1):ESPI_HOST_LPC_BMC_LFRAME_N

Q_RES  I293  R1481  [Q_RES_0402LF-33.2,1%,1/16W,CHIA]
    2  IRQ_LVC3_WAKE_R2_N      B  @S9S_MB_2U_LIB.S9S_MB_2U(SCH_1):IRQ_LVC3_WAKE_R2_N
    1  IRQ_LVC3_WAKE_N      A  @S9S_MB_2U_LIB.S9S_MB_2U(SCH_1):IRQ_LVC3_WAKE_N

Q_RES  I428  R1482  [Q_RES_0402LF-33.2,1%,1/16W,CHIA]
    1  IRQ_LVC3_WAKE_R3_N      A  @S9S_MB_2U_LIB.S9S_MB_2U(SCH_1):IRQ_LVC3_WAKE_R3_N
    2  IRQ_LVC3_WAKE_N      B  @S9S_MB_2U_LIB.S9S_MB_2U(SCH_1):IRQ_LVC3_WAKE_N

Q_RES  I265  R1483  [Q_RES_0402LF-10K,1%,1/16W,EMPTA]
    1  P3V3_AUX           A  @S9S_MB_2U_LIB.S9S_MB_2U(SCH_1):P3V3_AUX
    2  FM_CK440Q_DEV_25M_EN      B  @S9S_MB_2U_LIB.S9S_MB_2U(SCH_1):FM_CK440Q_DEV_25M_EN

Q_RES  I268  R1484  [Q_RES_0402LF-1K,1%,1/16W,EMPTYA]
    2  GND                B  @S9S_MB_2U_LIB.S9S_MB_2U(SCH_1):GND
    1  FM_CK440Q_DEV_25M_EN      A  @S9S_MB_2U_LIB.S9S_MB_2U(SCH_1):FM_CK440Q_DEV_25M_EN

Q_RES  I75  R1485  [Q_RES_0402LF-200,1%,1/16W,EMPTA]
    1  PVNN_TERM_CPU0      A  @S9S_MB_2U_LIB.S9S_MB_2U(SCH_1):PVNN_TERM_CPU0
    2  FM_PCH_TRIGGER0_R_N      B  @S9S_MB_2U_LIB.S9S_MB_2U(SCH_1):FM_PCH_TRIGGER0_R_N

Q_RES  I74  R1486  [Q_RES_0402LF-200,1%,1/16W,EMPTA]
    1  PVNN_TERM_CPU0      A  @S9S_MB_2U_LIB.S9S_MB_2U(SCH_1):PVNN_TERM_CPU0
    2  FM_PCH_TRIGGER1_R_N      B  @S9S_MB_2U_LIB.S9S_MB_2U(SCH_1):FM_PCH_TRIGGER1_R_N

Q_RES  I125  R1487  [Q_RES_0402LF-100,1%,1/16W,CHIPA]
    2  GND                B  @S9S_MB_2U_LIB.S9S_MB_2U(SCH_1):GND
    1  FM_PCH_SATA_RAID_KEY      A  @S9S_MB_2U_LIB.S9S_MB_2U(SCH_1):FM_PCH_SATA_RAID_KEY

Q_RES  I279  R1488  [Q_RES_0402LF-10K,1%,1/16W,CHIPA]
    1  PU_MAIN_FPGA_CONFIG_N      A  @S9S_MB_2U_LIB.S9S_MB_2U(SCH_1):PU_MAIN_FPGA_CONFIG_N
    2  P3V3_AUX           B  @S9S_MB_2U_LIB.S9S_MB_2U(SCH_1):P3V3_AUX

Q_RES  I282  R1491  [Q_RES_0402LF-1K,1%,1/16W,CHIP,A]
    1  PD_MAIN_FPGA_CONFIG_SEL      A  @S9S_MB_2U_LIB.S9S_MB_2U(SCH_1):PD_MAIN_FPGA_CONFIG_SEL
    2  GND                B  @S9S_MB_2U_LIB.S9S_MB_2U(SCH_1):GND

Q_RES  I272  R1492  [Q_RES_0402LF-10K,1%,1/16W,EMPTA]
    2  P3V3_AUX           B  @S9S_MB_2U_LIB.S9S_MB_2U(SCH_1):P3V3_AUX
    1  FM_DIS_PS_PWROK_DLY      A  @S9S_MB_2U_LIB.S9S_MB_2U(SCH_1):FM_DIS_PS_PWROK_DLY

Q_RES  I287  R1493  [Q_RES_0402LF-1K,1%,1/16W,EMPTYA]
    2  P3V3_AUX           B  @S9S_MB_2U_LIB.S9S_MB_2U(SCH_1):P3V3_AUX
    1  FM_FORCE_PWRON_LVC3      A  @S9S_MB_2U_LIB.S9S_MB_2U(SCH_1):FM_FORCE_PWRON_LVC3

Q_RES  I275  R1494  [Q_RES_0402LF-1K,1%,1/16W,CHIP,A]
    2  GND                B  @S9S_MB_2U_LIB.S9S_MB_2U(SCH_1):GND
    1  FM_DIS_PS_PWROK_DLY      A  @S9S_MB_2U_LIB.S9S_MB_2U(SCH_1):FM_DIS_PS_PWROK_DLY

Q_RES  I286  R1495  [Q_RES_0402LF-10K,1%,1/16W,CHIPA]
    2  GND                B  @S9S_MB_2U_LIB.S9S_MB_2U(SCH_1):GND
    1  FM_FORCE_PWRON_LVC3      A  @S9S_MB_2U_LIB.S9S_MB_2U(SCH_1):FM_FORCE_PWRON_LVC3

Q_RES  I71  R1496  [Q_RES_0402LF-10K,1%,1/16W,CHIPA]
    1  P3V3_AUX           A  @S9S_MB_2U_LIB.S9S_MB_2U(SCH_1):P3V3_AUX
    2  FM_PCH_DFXTESTMODE      B  @S9S_MB_2U_LIB.S9S_MB_2U(SCH_1):FM_PCH_DFXTESTMODE

Q_RES  I70  R1497  [Q_RES_0402LF-12K,1%,1/16W,EMPTA]
    2  GND                B  @S9S_MB_2U_LIB.S9S_MB_2U(SCH_1):GND
    1  FM_PCH_DFXTESTMODE      A  @S9S_MB_2U_LIB.S9S_MB_2U(SCH_1):FM_PCH_DFXTESTMODE

Q_RES  I76  R1498  [Q_RES_0402LF-1K,1%,1/16W,EMPTYA]
    1  P3V3_AUX           A  @S9S_MB_2U_LIB.S9S_MB_2U(SCH_1):P3V3_AUX
    2  FM_BIOS_ADV_FUNCTIONS      B  @S9S_MB_2U_LIB.S9S_MB_2U(SCH_1):FM_BIOS_ADV_FUNCTIONS

Q_RES  I77  R1499  [Q_RES_0402LF-1K,1%,1/16W,CHIP,A]
    2  GND                B  @S9S_MB_2U_LIB.S9S_MB_2U(SCH_1):GND
    1  FM_BIOS_ADV_FUNCTIONS      A  @S9S_MB_2U_LIB.S9S_MB_2U(SCH_1):FM_BIOS_ADV_FUNCTIONS

Q_RES  I271  R1500  [Q_RES_0402LF-4.75K,1%,1/16W,CHA]
    1  PD_CK440_SBI_DATA_IN      A  @S9S_MB_2U_LIB.S9S_MB_2U(SCH_1):PD_CK440_SBI_DATA_IN
    2  GND                B  @S9S_MB_2U_LIB.S9S_MB_2U(SCH_1):GND

Q_RES  I270  R1502  [Q_RES_0402LF-4.75K,1%,1/16W,CHA]
    2  GND                B  @S9S_MB_2U_LIB.S9S_MB_2U(SCH_1):GND
    1  FM_CLK_CK440_SS_EN      A  @S9S_MB_2U_LIB.S9S_MB_2U(SCH_1):FM_CLK_CK440_SS_EN

Q_RES  I10  R1504  [Q_RES_0402LF-33.2,1%,1/16W,CHIA]
    2  RST_PERST2_OCP_SFF_N      B  @S9S_MB_2U_LIB.S9S_MB_2U(SCH_1):RST_PERST2_OCP_SFF_N
    1  RST_OCP_V3_1_BUF_N      A  @S9S_MB_2U_LIB.S9S_MB_2U(SCH_1):RST_OCP_V3_1_BUF_N

Q_RES  I13  R1505  [Q_RES_0402LF-33.2,1%,1/16W,CHIA]
    2  RST_PERST3_OCP_SFF_N      B  @S9S_MB_2U_LIB.S9S_MB_2U(SCH_1):RST_PERST3_OCP_SFF_N
    1  RST_OCP_V3_1_BUF_N      A  @S9S_MB_2U_LIB.S9S_MB_2U(SCH_1):RST_OCP_V3_1_BUF_N

Q_RES  I108  R1512  [Q_RES_0402LF-33.2,1%,1/16W,CHIA]
    2  RST_PCIE_EDSFF2A_PERST_N      B  @S9S_MB_2U_LIB.S9S_MB_2U(SCH_1):RST_PCIE_EDSFF2A_PERST_N
    1  RST_PCIE_CPU0_DEV_PERST_N      A  @S9S_MB_2U_LIB.S9S_MB_2U(SCH_1):RST_PCIE_CPU0_DEV_PERST_N

Q_RES  I104  R1513  [Q_RES_0402LF-33.2,1%,1/16W,CHIA]
    2  RST_PCIE_RISER2_N      B  @S9S_MB_2U_LIB.S9S_MB_2U(SCH_1):RST_PCIE_RISER2_N
    1  RST_PCIE_CPU0_DEV_PERST_N      A  @S9S_MB_2U_LIB.S9S_MB_2U(SCH_1):RST_PCIE_CPU0_DEV_PERST_N

Q_RES  I105  R1514  [Q_RES_0402LF-33.2,1%,1/16W,CHIA]
    1  RST_PCIE_CPU0_DEV_PERST_N      A  @S9S_MB_2U_LIB.S9S_MB_2U(SCH_1):RST_PCIE_CPU0_DEV_PERST_N
    2  RST_OCP_V3_1_N      B  @S9S_MB_2U_LIB.S9S_MB_2U(SCH_1):RST_OCP_V3_1_N

Q_RES  I106  R1515  [Q_RES_0402LF-33.2,1%,1/16W,CHIA]
    2  RST_PCIE_EDSFF1A_PERST_N      B  @S9S_MB_2U_LIB.S9S_MB_2U(SCH_1):RST_PCIE_EDSFF1A_PERST_N
    1  RST_PCIE_CPU0_DEV_PERST_N      A  @S9S_MB_2U_LIB.S9S_MB_2U(SCH_1):RST_PCIE_CPU0_DEV_PERST_N

Q_RES  I107  R1516  [Q_RES_0402LF-33.2,1%,1/16W,CHIA]
    2  RST_PCIE_EDSFF1B_PERST_N      B  @S9S_MB_2U_LIB.S9S_MB_2U(SCH_1):RST_PCIE_EDSFF1B_PERST_N
    1  RST_PCIE_CPU0_DEV_PERST_N      A  @S9S_MB_2U_LIB.S9S_MB_2U(SCH_1):RST_PCIE_CPU0_DEV_PERST_N

Q_RES  I70  R1518  [Q_RES_0402LF-33.2,1%,1/16W,CHIA]
    2  RST_PCIE_RISER3_N      B  @S9S_MB_2U_LIB.S9S_MB_2U(SCH_1):RST_PCIE_RISER3_N
    1  RST_PCIE_CPU1_DEV_PERST_N      A  @S9S_MB_2U_LIB.S9S_MB_2U(SCH_1):RST_PCIE_CPU1_DEV_PERST_N

Q_RES  I115  R1519  [Q_RES_0402LF-33.2,1%,1/16W,CHIA]
    2  RST_PCIE_EDSFF4B_PERST_N      B  @S9S_MB_2U_LIB.S9S_MB_2U(SCH_1):RST_PCIE_EDSFF4B_PERST_N
    1  RST_PCIE_CPU1_DEV_PERST_N      A  @S9S_MB_2U_LIB.S9S_MB_2U(SCH_1):RST_PCIE_CPU1_DEV_PERST_N

Q_RES  I113  R1520  [Q_RES_0402LF-33.2,1%,1/16W,CHIA]
    2  RST_PCIE_EDSFF3_PERST_N      B  @S9S_MB_2U_LIB.S9S_MB_2U(SCH_1):RST_PCIE_EDSFF3_PERST_N
    1  RST_PCIE_CPU1_DEV_PERST_N      A  @S9S_MB_2U_LIB.S9S_MB_2U(SCH_1):RST_PCIE_CPU1_DEV_PERST_N

Q_RES  I114  R1521  [Q_RES_0402LF-33.2,1%,1/16W,CHIA]
    2  RST_PCIE_EDSFF4A_PERST_N      B  @S9S_MB_2U_LIB.S9S_MB_2U(SCH_1):RST_PCIE_EDSFF4A_PERST_N
    1  RST_PCIE_CPU1_DEV_PERST_N      A  @S9S_MB_2U_LIB.S9S_MB_2U(SCH_1):RST_PCIE_CPU1_DEV_PERST_N

Q_RES  I97  R1522  [Q_RES_0402LF-10K,1%,1/16W,CHIPA]
    2  PU_RST_SMB_EDSFF_N      B  @S9S_MB_2U_LIB.S9S_MB_2U(SCH_1):PU_RST_SMB_EDSFF_N
    1  P3V3_AUX           A  @S9S_MB_2U_LIB.S9S_MB_2U(SCH_1):P3V3_AUX

Q_RES  I40  R1525  [Q_RES_0402LF-0,5%,1/16W,CHIP,CA]
    2  SMB_HOST_CLK_3V3AUX_SCL      B  @S9S_MB_2U_LIB.S9S_MB_2U(SCH_1):SMB_HOST_CLK_3V3AUX_SCL
    1  SMB_HOST_3V3AUX_SCL_R      A  @S9S_MB_2U_LIB.S9S_MB_2U(SCH_1):SMB_HOST_3V3AUX_SCL_R

Q_RES  I41  R1526  [Q_RES_0402LF-33.2,1%,1/16W,CHIA]
    2  SMB_HOST_CLK_3V3AUX_SDA      B  @S9S_MB_2U_LIB.S9S_MB_2U(SCH_1):SMB_HOST_CLK_3V3AUX_SDA
    1  SMB_HOST_3V3AUX_SDA_R      A  @S9S_MB_2U_LIB.S9S_MB_2U(SCH_1):SMB_HOST_3V3AUX_SDA_R

Q_RES  I269  R1527  [Q_RES_0402LF-1K,1%,1/16W,CHIP,A]
    2  GND                B  @S9S_MB_2U_LIB.S9S_MB_2U(SCH_1):GND
    1  FM_CLK_GEN1_OE0_N      A  @S9S_MB_2U_LIB.S9S_MB_2U(SCH_1):FM_CLK_GEN1_OE0_N

Q_RES  I163  R1528  [Q_RES_0402LF-4.7K,5%,1/16W,EMPA]
    2  P3V3_AUX           B  @S9S_MB_2U_LIB.S9S_MB_2U(SCH_1):P3V3_AUX
    1  JTAG_RISER2_TDO      A  @S9S_MB_2U_LIB.S9S_MB_2U(SCH_1):JTAG_RISER2_TDO

Q_RES  I162  R1529  [Q_RES_0402LF-4.7K,5%,1/16W,EMPA]
    2  P3V3_AUX           B  @S9S_MB_2U_LIB.S9S_MB_2U(SCH_1):P3V3_AUX
    1  JTAG_RISER2_TMS      A  @S9S_MB_2U_LIB.S9S_MB_2U(SCH_1):JTAG_RISER2_TMS

Q_RES  I161  R1530  [Q_RES_0402LF-4.7K,5%,1/16W,EMPA]
    1  JTAG_RISER2_TCK      A  @S9S_MB_2U_LIB.S9S_MB_2U(SCH_1):JTAG_RISER2_TCK
    2  GND                B  @S9S_MB_2U_LIB.S9S_MB_2U(SCH_1):GND

Q_RES  I160  R1531  [Q_RES_0402LF-4.7K,5%,1/16W,EMPA]
    1  JTAG_RISER2_TRST_N      A  @S9S_MB_2U_LIB.S9S_MB_2U(SCH_1):JTAG_RISER2_TRST_N
    2  GND                B  @S9S_MB_2U_LIB.S9S_MB_2U(SCH_1):GND

Q_RES  I370  R1532  [Q_RES_0402LF-4.7K,5%,1/16W,EMPA]
    2  P3V3_AUX           B  @S9S_MB_2U_LIB.S9S_MB_2U(SCH_1):P3V3_AUX
    1  JTAG_RISER3_TDI      A  @S9S_MB_2U_LIB.S9S_MB_2U(SCH_1):JTAG_RISER3_TDI

Q_RES  I369  R1533  [Q_RES_0402LF-4.7K,5%,1/16W,EMPA]
    2  P3V3_AUX           B  @S9S_MB_2U_LIB.S9S_MB_2U(SCH_1):P3V3_AUX
    1  JTAG_RISER3_TDO      A  @S9S_MB_2U_LIB.S9S_MB_2U(SCH_1):JTAG_RISER3_TDO

Q_RES  I373  R1534  [Q_RES_0402LF-4.7K,5%,1/16W,EMPA]
    2  P3V3_AUX           B  @S9S_MB_2U_LIB.S9S_MB_2U(SCH_1):P3V3_AUX
    1  JTAG_RISER3_TMS      A  @S9S_MB_2U_LIB.S9S_MB_2U(SCH_1):JTAG_RISER3_TMS

Q_RES  I371  R1535  [Q_RES_0402LF-4.7K,5%,1/16W,EMPA]
    1  JTAG_RISER3_TCK      A  @S9S_MB_2U_LIB.S9S_MB_2U(SCH_1):JTAG_RISER3_TCK
    2  GND                B  @S9S_MB_2U_LIB.S9S_MB_2U(SCH_1):GND

Q_RES  I372  R1536  [Q_RES_0402LF-4.7K,5%,1/16W,EMPA]
    1  JTAG_RISER3_TRST_N      A  @S9S_MB_2U_LIB.S9S_MB_2U(SCH_1):JTAG_RISER3_TRST_N
    2  GND                B  @S9S_MB_2U_LIB.S9S_MB_2U(SCH_1):GND

Q_RES  I71  R1537  [Q_RES_0402LF-33.2,1%,1/16W,CHIA]
    1  SMB_SML1_PMBUS_3V3AUX_PCH_SCL      A  @S9S_MB_2U_LIB.S9S_MB_2U(SCH_1):SMB_SML1_PMBUS_3V3AUX_PCH_SCL
    2  SMB_PMBUS_PSU1_SCL      B  @S9S_MB_2U_LIB.S9S_MB_2U(SCH_1):SMB_PMBUS_PSU1_SCL

Q_RES  I72  R1538  [Q_RES_0402LF-33.2,1%,1/16W,CHIA]
    1  SMB_SML1_PMBUS_3V3AUX_PCH_SDA      A  @S9S_MB_2U_LIB.S9S_MB_2U(SCH_1):SMB_SML1_PMBUS_3V3AUX_PCH_SDA
    2  SMB_PMBUS_PSU1_SDA      B  @S9S_MB_2U_LIB.S9S_MB_2U(SCH_1):SMB_PMBUS_PSU1_SDA

Q_RES  I37  R1539  [Q_RES_0402LF-10K,1%,1/16W,CHIPA]
    2  GND                B  @S9S_MB_2U_LIB.S9S_MB_2U(SCH_1):GND
    1  FM_PSU_THROTTLE_L      A  @S9S_MB_2U_LIB.S9S_MB_2U(SCH_1):FM_PSU_THROTTLE_L

Q_RES  I33  R1540  [Q_RES_0402LF-100K,1%,1/16W,EMPB]
    1  P3V3_AUX           A  @S9S_MB_2U_LIB.S9S_MB_2U(SCH_1):P3V3_AUX
    2  FM_PSU_THROTTLE_N      B  @S9S_MB_2U_LIB.S9S_MB_2U(SCH_1):FM_PSU_THROTTLE_N

Q_RES  I92  R1541  [Q_RES_0402LF-100K,1%,1/16W,CHIA]
    2  RST_PLTRST_N       B  @S9S_MB_2U_LIB.S9S_MB_2U(SCH_1):RST_PLTRST_N
    1  GND                A  @S9S_MB_2U_LIB.S9S_MB_2U(SCH_1):GND

Q_RES  I418  R1542  [Q_RES_0402LF-10K,1%,1/16W,CHIPA]
    1  P3V3               A  @S9S_MB_2U_LIB.S9S_MB_2U(SCH_1):P3V3
    2  EDSFF1A_PERST1_CLKREQ_N      B  @S9S_MB_2U_LIB.S9S_MB_2U(SCH_1):EDSFF1A_PERST1_CLKREQ_N

Q_RES  I411  R1543  [Q_RES_0402LF-0,5%,1/16W,CHIP,CA]
    1  HP_LVC3_OCP_V3_1_PRSNT2_N      A  @S9S_MB_2U_LIB.S9S_MB_2U(SCH_1):HP_LVC3_OCP_V3_1_PRSNT2_N
    2  FM_DB2000_8_OE_N      B  @S9S_MB_2U_LIB.S9S_MB_2U(SCH_1):FM_DB2000_8_OE_N

Q_RES  I416  R1544  [Q_RES_0402LF-0,5%,1/16W,CHIP,CA]
    2  FM_DB2000_12_OE_N      B  @S9S_MB_2U_LIB.S9S_MB_2U(SCH_1):FM_DB2000_12_OE_N
    1  EDSFF1A_PERST1_CLKREQ_N      A  @S9S_MB_2U_LIB.S9S_MB_2U(SCH_1):EDSFF1A_PERST1_CLKREQ_N

Q_RES  I137  R1545  [Q_RES_0402LF-2K,1%,1/16W,CHIP,A]
    1  SMB_SML0B_3V3AUX_SCL      A  @S9S_MB_2U_LIB.S9S_MB_2U(SCH_1):SMB_SML0B_3V3AUX_SCL
    2  P3V3_AUX           B  @S9S_MB_2U_LIB.S9S_MB_2U(SCH_1):P3V3_AUX

Q_RES  I138  R1546  [Q_RES_0402LF-2K,1%,1/16W,CHIP,A]
    1  SMB_SML0B_3V3AUX_SDA      A  @S9S_MB_2U_LIB.S9S_MB_2U(SCH_1):SMB_SML0B_3V3AUX_SDA
    2  P3V3_AUX           B  @S9S_MB_2U_LIB.S9S_MB_2U(SCH_1):P3V3_AUX

Q_RES  I251  R1547  [Q_RES_0402LF-0,5%,1/16W,CHIP,CA]
    1  FM_TPM_PRSNT_R_N      A  @S9S_MB_2U_LIB.S9S_MB_2U(SCH_1):FM_TPM_PRSNT_R_N
    2  FM_TPM_PRSNT_N      B  @S9S_MB_2U_LIB.S9S_MB_2U(SCH_1):FM_TPM_PRSNT_N

Q_RES  I393  R1549  [Q_RES_0402LF-4.7K,1%,1/16W,CHIA]
    2  SMB_PCIE_3V3AUX_SDA      B  @S9S_MB_2U_LIB.S9S_MB_2U(SCH_1):SMB_PCIE_3V3AUX_SDA
    1  P3V3_AUX           A  @S9S_MB_2U_LIB.S9S_MB_2U(SCH_1):P3V3_AUX

Q_RES  I392  R1550  [Q_RES_0402LF-4.7K,1%,1/16W,CHIA]
    2  SMB_PCIE_3V3AUX_SCL      B  @S9S_MB_2U_LIB.S9S_MB_2U(SCH_1):SMB_PCIE_3V3AUX_SCL
    1  P3V3_AUX           A  @S9S_MB_2U_LIB.S9S_MB_2U(SCH_1):P3V3_AUX

Q_RES  I234  R1551  [Q_RES_0402LF-4.7K,1%,1/16W,CHIA]
    2  SMB_PLD_3V3AUX_SCL_R      B  @S9S_MB_2U_LIB.S9S_MB_2U(SCH_1):SMB_PLD_3V3AUX_SCL_R
    1  P3V3_AUX           A  @S9S_MB_2U_LIB.S9S_MB_2U(SCH_1):P3V3_AUX

Q_RES  I62  R1554  [Q_RES_0402LF-10K,1%,1/16W,CHIPA]
    1  P3V3_AUX           A  @S9S_MB_2U_LIB.S9S_MB_2U(SCH_1):P3V3_AUX
    2  FM_ME_AUTHN_FAIL      B  @S9S_MB_2U_LIB.S9S_MB_2U(SCH_1):FM_ME_AUTHN_FAIL

Q_RES  I318  R1558  [Q_RES_0402LF-10K,1%,1/16W,CHIPA]
    2  P3V3_AUX           B  @S9S_MB_2U_LIB.S9S_MB_2U(SCH_1):P3V3_AUX
    1  FM_CPU_RMCA_CATERR_LVT3_R_N      A  @S9S_MB_2U_LIB.S9S_MB_2U(SCH_1):FM_CPU_RMCA_CATERR_LVT3_R_N

Q_RES  I394  R1559  [Q_RES_0402LF-0,5%,1/16W,EMPTY,A]
    2  SMB_PCIE_3V3AUX_SDA      B  @S9S_MB_2U_LIB.S9S_MB_2U(SCH_1):SMB_PCIE_3V3AUX_SDA
    1  SMB_PCIE_3V3AUX_B_SDA      A  @S9S_MB_2U_LIB.S9S_MB_2U(SCH_1):SMB_PCIE_3V3AUX_B_SDA

Q_RES  I395  R1560  [Q_RES_0402LF-0,5%,1/16W,EMPTY,A]
    2  SMB_PCIE_3V3AUX_SCL      B  @S9S_MB_2U_LIB.S9S_MB_2U(SCH_1):SMB_PCIE_3V3AUX_SCL
    1  SMB_PCIE_3V3AUX_B_SCL      A  @S9S_MB_2U_LIB.S9S_MB_2U(SCH_1):SMB_PCIE_3V3AUX_B_SCL

Q_RES  I306  R1573  [Q_RES_0402LF-0,5%,1/16W,CHIP,CA]
    1  FM_SYS_THROTTLE_R_N      A  @S9S_MB_2U_LIB.S9S_MB_2U(SCH_1):FM_SYS_THROTTLE_R_N
    2  FM_RISER2_PWRBRK_N      B  @S9S_MB_2U_LIB.S9S_MB_2U(SCH_1):FM_RISER2_PWRBRK_N

Q_RES  I262  R1574  [Q_RES_0402LF-100,1%,1/16W,CHIPA]
    1  PD_RISER2_PRSNT1      A  @S9S_MB_2U_LIB.S9S_MB_2U(SCH_1):PD_RISER2_PRSNT1
    2  GND                B  @S9S_MB_2U_LIB.S9S_MB_2U(SCH_1):GND

Q_RES  I308  R1575  [Q_RES_0402LF-10K,5%,1/16W,CHIPA]
    2  RISER2_CLK3_EN_N      B  @S9S_MB_2U_LIB.S9S_MB_2U(SCH_1):RISER2_CLK3_EN_N
    1  P3V3_AUX           A  @S9S_MB_2U_LIB.S9S_MB_2U(SCH_1):P3V3_AUX

Q_RES  I304  R1576  [Q_RES_0402LF-10K,5%,1/16W,CHIPA]
    2  RISER2_CLK2_EN_N      B  @S9S_MB_2U_LIB.S9S_MB_2U(SCH_1):RISER2_CLK2_EN_N
    1  P3V3_AUX           A  @S9S_MB_2U_LIB.S9S_MB_2U(SCH_1):P3V3_AUX

Q_RES  I239  R1577  [Q_RES_0402LF-0,5%,1/16W,CHIP,CA]
    1  FM_SYS_THROTTLE_R_N      A  @S9S_MB_2U_LIB.S9S_MB_2U(SCH_1):FM_SYS_THROTTLE_R_N
    2  FM_RISER3_PWRBRK_N      B  @S9S_MB_2U_LIB.S9S_MB_2U(SCH_1):FM_RISER3_PWRBRK_N

Q_RES  I345  R1578  [Q_RES_0402LF-100,1%,1/16W,CHIPA]
    1  PD_RISER3_PRSNT1      A  @S9S_MB_2U_LIB.S9S_MB_2U(SCH_1):PD_RISER3_PRSNT1
    2  GND                B  @S9S_MB_2U_LIB.S9S_MB_2U(SCH_1):GND

Q_RES  I343  R1579  [Q_RES_0402LF-10K,5%,1/16W,CHIPA]
    2  RISER3_CLK4_EN_N      B  @S9S_MB_2U_LIB.S9S_MB_2U(SCH_1):RISER3_CLK4_EN_N
    1  P3V3_AUX           A  @S9S_MB_2U_LIB.S9S_MB_2U(SCH_1):P3V3_AUX

Q_RES  I341  R1580  [Q_RES_0402LF-10K,5%,1/16W,CHIPA]
    2  RISER3_CLK5_EN_N      B  @S9S_MB_2U_LIB.S9S_MB_2U(SCH_1):RISER3_CLK5_EN_N
    1  P3V3_AUX           A  @S9S_MB_2U_LIB.S9S_MB_2U(SCH_1):P3V3_AUX

Q_RES  I142  R1581  [Q_RES_0402LF-2K,1%,1/16W,CHIP,A]
    1  PU_SMB_PCH_PLD_3V3AUX_SCL      A  @S9S_MB_2U_LIB.S9S_MB_2U(SCH_1):PU_SMB_PCH_PLD_3V3AUX_SCL
    2  P3V3_AUX           B  @S9S_MB_2U_LIB.S9S_MB_2U(SCH_1):P3V3_AUX

Q_RES  I141  R1582  [Q_RES_0402LF-2K,1%,1/16W,CHIP,A]
    1  PU_SMB_PCH_PLD_3V3AUX_SDA      A  @S9S_MB_2U_LIB.S9S_MB_2U(SCH_1):PU_SMB_PCH_PLD_3V3AUX_SDA
    2  P3V3_AUX           B  @S9S_MB_2U_LIB.S9S_MB_2U(SCH_1):P3V3_AUX

Q_RES  I144  R1583  [Q_RES_0402LF-10K,1%,1/16W,CHIPA]
    1  PU_PCH_PLD_3V3AUX_ALERT_N      A  @S9S_MB_2U_LIB.S9S_MB_2U(SCH_1):PU_PCH_PLD_3V3AUX_ALERT_N
    2  P3V3_AUX           B  @S9S_MB_2U_LIB.S9S_MB_2U(SCH_1):P3V3_AUX

Q_RES  I114  R1584  [Q_RES_0402LF-10K,5%,1/16W,EMPTA]
    1  P3V3_AUX           A  @S9S_MB_2U_LIB.S9S_MB_2U(SCH_1):P3V3_AUX
    2  FM_SYS_THROTTLE_R_N      B  @S9S_MB_2U_LIB.S9S_MB_2U(SCH_1):FM_SYS_THROTTLE_R_N

Q_RES  I112  R1585  [Q_RES_0402LF-0,5%,1/16W,CHIP,CA]
    1  FM_SYS_THROTTLE_R_N      A  @S9S_MB_2U_LIB.S9S_MB_2U(SCH_1):FM_SYS_THROTTLE_R_N
    2  FM_EDSFF2A_PWRBRK_N      B  @S9S_MB_2U_LIB.S9S_MB_2U(SCH_1):FM_EDSFF2A_PWRBRK_N

Q_RES  I100  R1586  [Q_RES_0402LF-10K,5%,1/16W,EMPTA]
    1  P3V3_AUX           A  @S9S_MB_2U_LIB.S9S_MB_2U(SCH_1):P3V3_AUX
    2  FM_SYS_THROTTLE_R_N      B  @S9S_MB_2U_LIB.S9S_MB_2U(SCH_1):FM_SYS_THROTTLE_R_N

Q_RES  I98  R1587  [Q_RES_0402LF-0,5%,1/16W,CHIP,CA]
    1  FM_SYS_THROTTLE_R_N      A  @S9S_MB_2U_LIB.S9S_MB_2U(SCH_1):FM_SYS_THROTTLE_R_N
    2  FM_EDSFF2B_PWRBRK_N      B  @S9S_MB_2U_LIB.S9S_MB_2U(SCH_1):FM_EDSFF2B_PWRBRK_N

Q_RES  I455  R1588  [Q_RES_0402LF-10K,5%,1/16W,EMPTA]
    1  P3V3_AUX           A  @S9S_MB_2U_LIB.S9S_MB_2U(SCH_1):P3V3_AUX
    2  FM_SYS_THROTTLE_R_N      B  @S9S_MB_2U_LIB.S9S_MB_2U(SCH_1):FM_SYS_THROTTLE_R_N

Q_RES  I453  R1589  [Q_RES_0402LF-0,5%,1/16W,CHIP,CA]
    1  FM_SYS_THROTTLE_R_N      A  @S9S_MB_2U_LIB.S9S_MB_2U(SCH_1):FM_SYS_THROTTLE_R_N
    2  FM_EDSFF3_PWRBRK_N      B  @S9S_MB_2U_LIB.S9S_MB_2U(SCH_1):FM_EDSFF3_PWRBRK_N

Q_RES  I37  R1592  [Q_RES_0402LF-10K,1%,1/16W,CHIPA]
    2  PU_OCP_SFF_WAKE_OE      B  @S9S_MB_2U_LIB.S9S_MB_2U(SCH_1):PU_OCP_SFF_WAKE_OE
    1  P3V3_OCP_SFF       A  @S9S_MB_2U_LIB.S9S_MB_2U(SCH_1):P3V3_OCP_SFF

Q_RES  I42  R1593  [Q_RES_0402LF-4.7K,1%,1/16W,EMPA]
    1  P3V3_AUX           A  @S9S_MB_2U_LIB.S9S_MB_2U(SCH_1):P3V3_AUX
    2  OCP_SFF_PWRBRK_BUFF_N      B  @S9S_MB_2U_LIB.S9S_MB_2U(SCH_1):OCP_SFF_PWRBRK_BUFF_N

Q_RES  I26  R1594  [Q_RES_0402LF-33.2,1%,1/16W,CHIA]
    1  OCP_SFF_WAKE_BUFF_N      A  @S9S_MB_2U_LIB.S9S_MB_2U(SCH_1):OCP_SFF_WAKE_BUFF_N
    2  IRQ_LVC3_WAKE_N      B  @S9S_MB_2U_LIB.S9S_MB_2U(SCH_1):IRQ_LVC3_WAKE_N

Q_RES  I40  R1595  [Q_RES_0402LF-33.2,1%,1/16W,CHIA]
    2  OCP_SFF_PWRBRK_N      B  @S9S_MB_2U_LIB.S9S_MB_2U(SCH_1):OCP_SFF_PWRBRK_N
    1  OCP_SFF_PWRBRK_BUFF_N      A  @S9S_MB_2U_LIB.S9S_MB_2U(SCH_1):OCP_SFF_PWRBRK_BUFF_N

Q_RES  I148  R1600  [Q_RES_0402LF-33,5%,1/16W,CHIP,A]
    2  IRQ_SML0_ALERT_R_N      B  @S9S_MB_2U_LIB.S9S_MB_2U(SCH_1):IRQ_SML0_ALERT_R_N
    1  IRQ_SML0_ALERT_N      A  @S9S_MB_2U_LIB.S9S_MB_2U(SCH_1):IRQ_SML0_ALERT_N

Q_RES  I151  R1601  [Q_RES_0402LF-10K,1%,1/16W,CHIPA]
    2  P3V3_AUX           B  @S9S_MB_2U_LIB.S9S_MB_2U(SCH_1):P3V3_AUX
    1  IRQ_SML0_ALERT_N      A  @S9S_MB_2U_LIB.S9S_MB_2U(SCH_1):IRQ_SML0_ALERT_N

Q_RES  I105  R1605  [Q_RES_0402LF-1K,1%,1/16W,CHIP,A]
    1  PD_M2_1_DEVSLP      A  @S9S_MB_2U_LIB.S9S_MB_2U(SCH_1):PD_M2_1_DEVSLP
    2  GND                B  @S9S_MB_2U_LIB.S9S_MB_2U(SCH_1):GND

Q_RES  I183  R1606  [Q_RES_0402LF-0,5%,1/16W,CHIP,CA]
    2  FM_OCP_SFF_PWR_GOOD_R      B  @S9S_MB_2U_LIB.S9S_MB_2U(SCH_1):FM_OCP_SFF_PWR_GOOD_R
    1  FM_OCP_SFF_PWR_GOOD      A  @S9S_MB_2U_LIB.S9S_MB_2U(SCH_1):FM_OCP_SFF_PWR_GOOD

Q_RES  I85  R1607  [Q_RES_0402LF-0,5%,1/16W,CHIP,CA]
    2  VR_P5V_EN          B  @S9S_MB_2U_LIB.S9S_MB_2U(SCH_1):VR_P5V_EN
    1  FM_PS_EN_PLD_R      A  @S9S_MB_2U_LIB.S9S_MB_2U(SCH_1):FM_PS_EN_PLD_R

Q_RES  I203  R1608  [Q_RES_0402LF-4.7K,1%,1/16W,EMPA]
    1  P3V3_AUX           A  @S9S_MB_2U_LIB.S9S_MB_2U(SCH_1):P3V3_AUX
    2  IRQ_PSU_ALERT_N      B  @S9S_MB_2U_LIB.S9S_MB_2U(SCH_1):IRQ_PSU_ALERT_N

Q_RES  I88  R1609  [Q_RES_0402LF-10K,1%,1/16W,CHIPA]
    1  P3V3_AUX           A  @S9S_MB_2U_LIB.S9S_MB_2U(SCH_1):P3V3_AUX
    2  FM_EDSFF2A_TYPE_ID      B  @S9S_MB_2U_LIB.S9S_MB_2U(SCH_1):FM_EDSFF2A_TYPE_ID

Q_RES  I85  R1610  [Q_RES_0402LF-10K,1%,1/16W,CHIPA]
    1  P3V3_AUX           A  @S9S_MB_2U_LIB.S9S_MB_2U(SCH_1):P3V3_AUX
    2  FM_EDSFF2B_TYPE_ID      B  @S9S_MB_2U_LIB.S9S_MB_2U(SCH_1):FM_EDSFF2B_TYPE_ID

Q_RES  I97  R1613  [Q_RES_0402LF-4.7K,5%,1/16W,CHIA]
    1  RST_SMB_EDSFF2A_N      A  @S9S_MB_2U_LIB.S9S_MB_2U(SCH_1):RST_SMB_EDSFF2A_N
    2  P3V3_AUX           B  @S9S_MB_2U_LIB.S9S_MB_2U(SCH_1):P3V3_AUX

Q_RES  I98  R1614  [Q_RES_0402LF-100,1%,1/16W,CHIPA]
    1  PD_PCIE_EDSFF2A_PRSNT_0_N      A  @S9S_MB_2U_LIB.S9S_MB_2U(SCH_1):PD_PCIE_EDSFF2A_PRSNT_0_N
    2  GND                B  @S9S_MB_2U_LIB.S9S_MB_2U(SCH_1):GND

Q_RES  I95  R1615  [Q_RES_0402LF-4.7K,5%,1/16W,CHIA]
    1  RST_SMB_EDSFF2B_N      A  @S9S_MB_2U_LIB.S9S_MB_2U(SCH_1):RST_SMB_EDSFF2B_N
    2  P3V3_AUX           B  @S9S_MB_2U_LIB.S9S_MB_2U(SCH_1):P3V3_AUX

Q_RES  I93  R1616  [Q_RES_0402LF-100,1%,1/16W,CHIPA]
    1  PD_PCIE_EDSFF2B_PRSNT_0_N      A  @S9S_MB_2U_LIB.S9S_MB_2U(SCH_1):PD_PCIE_EDSFF2B_PRSNT_0_N
    2  GND                B  @S9S_MB_2U_LIB.S9S_MB_2U(SCH_1):GND

Q_RES  I203  R1617  [Q_RES_0402LF-4.7K,5%,1/16W,CHIA]
    1  NC                 A  NC
    2  P3V3_AUX           B  @S9S_MB_2U_LIB.S9S_MB_2U(SCH_1):P3V3_AUX

Q_RES  I446  R1618  [Q_RES_0402LF-100,1%,1/16W,CHIPA]
    2  GND                B  @S9S_MB_2U_LIB.S9S_MB_2U(SCH_1):GND
    1  EDSFF3_PRSNT_0_N      A  @S9S_MB_2U_LIB.S9S_MB_2U(SCH_1):EDSFF3_PRSNT_0_N

Q_RES  I84  R1640  [Q_RES_0402LF-0,5%,1/16W,EMPTY,A]
    2  VR_P5V_EN          B  @S9S_MB_2U_LIB.S9S_MB_2U(SCH_1):VR_P5V_EN
    1  FM_P5V_EN          A  @S9S_MB_2U_LIB.S9S_MB_2U(SCH_1):FM_P5V_EN

Q_RES  I74  R1641  [Q_RES_0402LF-100,1%,1/16W,CHIPA]
    1  VR_P5V_EN          A  @S9S_MB_2U_LIB.S9S_MB_2U(SCH_1):VR_P5V_EN
    2  GND                B  @S9S_MB_2U_LIB.S9S_MB_2U(SCH_1):GND

Q_RES  I87  R1642  [Q_RES_0402LF-10K,5%,1/16W,CHIPA]
    2  VR_P5V_EN_D_R      B  @S9S_MB_2U_LIB.S9S_MB_2U(SCH_1):VR_P5V_EN_D_R
    1  P12V_AUX           A  @S9S_MB_2U_LIB.S9S_MB_2U(SCH_1):P12V_AUX

Q_RES  I86  R1643  [Q_RES_0402LF-100K,5%,1/16W,CHIA]
    2  VR_P5V_EN_N        B  @S9S_MB_2U_LIB.S9S_MB_2U(SCH_1):VR_P5V_EN_N
    1  P12V_AUX           A  @S9S_MB_2U_LIB.S9S_MB_2U(SCH_1):P12V_AUX

Q_RES  I20  R1645  [Q_RES_0402LF-4.7K,5%,1/16W,EMPA]
    1  P3V3_AUX           A  @S9S_MB_2U_LIB.S9S_MB_2U(SCH_1):P3V3_AUX
    2  FM_FAN_ID          B  @S9S_MB_2U_LIB.S9S_MB_2U(SCH_1):FM_FAN_ID

Q_RES  I27  R1646  [Q_RES_0402LF-4.7K,5%,1/16W,CHIA]
    2  GND                B  @S9S_MB_2U_LIB.S9S_MB_2U(SCH_1):GND
    1  FM_FAN_ID          A  @S9S_MB_2U_LIB.S9S_MB_2U(SCH_1):FM_FAN_ID

Q_RES  I3   R1648  [Q_RES_0402LF-0,5%,1/16W,EMPTY,A]
    2  SMB_S3M_CPU1_3V3AUX_SDA      B  @S9S_MB_2U_LIB.S9S_MB_2U(SCH_1):SMB_S3M_CPU1_3V3AUX_SDA
    1  SMB_S3M_CPU0_3V3AUX_SDA      A  @S9S_MB_2U_LIB.S9S_MB_2U(SCH_1):SMB_S3M_CPU0_3V3AUX_SDA

Q_RES  I31  R1649  [Q_RES_0402LF-2K,1%,1/16W,CHIP,A]
    2  GND                B  @S9S_MB_2U_LIB.S9S_MB_2U(SCH_1):GND
    1  FM_P1V05_PCH_AUX_R_EN      A  @S9S_MB_2U_LIB.S9S_MB_2U(SCH_1):FM_P1V05_PCH_AUX_R_EN

Q_RES  I173  R1652  [Q_RES_0402LF-0,5%,1/16W,CHIP,CA]
    1  PWRGD_PVNN_MAIN_CPU0_R      A  @S9S_MB_2U_LIB.S9S_MB_2U(SCH_1):PWRGD_PVNN_MAIN_CPU0_R
    2  PWRGD_PVNN_MAIN_CPU0      B  @S9S_MB_2U_LIB.S9S_MB_2U(SCH_1):PWRGD_PVNN_MAIN_CPU0

Q_RES  I77  R1654  [Q_RES_0402LF-1K,5%,1/16W,CHIP,A]
    2  VR_P5V_EN_D_R1      B  @S9S_MB_2U_LIB.S9S_MB_2U(SCH_1):VR_P5V_EN_D_R1
    1  VR_P5V_EN_D_R      A  @S9S_MB_2U_LIB.S9S_MB_2U(SCH_1):VR_P5V_EN_D_R

Q_RES  I71  R1655  [Q_RES_0402LF-10K,5%,1/16W,CHIPA]
    2  PWRGD_P5V          B  @S9S_MB_2U_LIB.S9S_MB_2U(SCH_1):PWRGD_P5V
    1  P5V                A  @S9S_MB_2U_LIB.S9S_MB_2U(SCH_1):P5V

Q_RES  I178  R1656  [Q_RES_0402LF-33,5%,1/16W,CHIP,A]
    2  IRQ_SML1_PMBUS_PLD_ALERT_N      B  @S9S_MB_2U_LIB.S9S_MB_2U(SCH_1):IRQ_SML1_PMBUS_PLD_ALERT_N
    1  IRQ_SML1_PMBUS_ALERT_N      A  @S9S_MB_2U_LIB.S9S_MB_2U(SCH_1):IRQ_SML1_PMBUS_ALERT_N

Q_RES  I180  R1657  [Q_RES_0402LF-33,5%,1/16W,CHIP,A]
    2  IRQ_SML1_PMBUS_BMC_ALERT_N      B  @S9S_MB_2U_LIB.S9S_MB_2U(SCH_1):IRQ_SML1_PMBUS_BMC_ALERT_N
    1  IRQ_SML1_PMBUS_ALERT_N      A  @S9S_MB_2U_LIB.S9S_MB_2U(SCH_1):IRQ_SML1_PMBUS_ALERT_N

Q_RES  I174  R1658  [Q_RES_0402LF-10K,1%,1/16W,CHIPA]
    2  P3V3_AUX           B  @S9S_MB_2U_LIB.S9S_MB_2U(SCH_1):P3V3_AUX
    1  IRQ_SML1_PMBUS_ALERT_N      A  @S9S_MB_2U_LIB.S9S_MB_2U(SCH_1):IRQ_SML1_PMBUS_ALERT_N

Q_RES  I181  R1659  [Q_RES_0402LF-10K,1%,1/16W,CHIPA]
    2  P3V3_AUX           B  @S9S_MB_2U_LIB.S9S_MB_2U(SCH_1):P3V3_AUX
    1  FM_PMBUS_ALERT_B_EN      A  @S9S_MB_2U_LIB.S9S_MB_2U(SCH_1):FM_PMBUS_ALERT_B_EN

Q_RES  I328  R1660  [Q_RES_0402LF-10K,1%,1/16W,EMPTA]
    2  P3V3_AUX           B  @S9S_MB_2U_LIB.S9S_MB_2U(SCH_1):P3V3_AUX
    1  FM_SLP_SUS_RSM_RST_N      A  @S9S_MB_2U_LIB.S9S_MB_2U(SCH_1):FM_SLP_SUS_RSM_RST_N

Q_RES  I89  R1661  [Q_RES_0402LF-33,5%,1/16W,CHIP,A]
    2  SMB_VR_3V3AUX_SCL_R      B  @S9S_MB_2U_LIB.S9S_MB_2U(SCH_1):SMB_VR_3V3AUX_SCL_R
    1  SMB_VR_3V3AUX_SCL      A  @S9S_MB_2U_LIB.S9S_MB_2U(SCH_1):SMB_VR_3V3AUX_SCL

Q_RES  I90  R1662  [Q_RES_0402LF-33,5%,1/16W,CHIP,A]
    2  SMB_VR_3V3AUX_SDA_R      B  @S9S_MB_2U_LIB.S9S_MB_2U(SCH_1):SMB_VR_3V3AUX_SDA_R
    1  SMB_VR_3V3AUX_SDA      A  @S9S_MB_2U_LIB.S9S_MB_2U(SCH_1):SMB_VR_3V3AUX_SDA

Q_RES  I183  R1667  [Q_RES_0402LF-10K,1%,1/16W,CHIPA]
    2  PU_RST_SMB_PCIE3_N      B  @S9S_MB_2U_LIB.S9S_MB_2U(SCH_1):PU_RST_SMB_PCIE3_N
    1  P3V3_AUX           A  @S9S_MB_2U_LIB.S9S_MB_2U(SCH_1):P3V3_AUX

Q_RES  I340  R1671  [Q_RES_0402LF-0,5%,1/16W,CHIP,CA]
    2  OCP_SFF_AUX_PWR_EN_R      B  @S9S_MB_2U_LIB.S9S_MB_2U(SCH_1):OCP_SFF_AUX_PWR_EN_R
    1  OCP_SFF_AUX_PWR_EN      A  @S9S_MB_2U_LIB.S9S_MB_2U(SCH_1):OCP_SFF_AUX_PWR_EN

Q_RES  I34  R1673  [Q_RES_0402LF-10K,1%,1/16W,EMPTA]
    2  RST_SMB_E1S_0_N      B  @S9S_MB_2U_LIB.S9S_MB_2U(SCH_1):RST_SMB_E1S_0_N
    1  P3V3_E1S_0         A  @S9S_MB_2U_LIB.S9S_MB_2U(SCH_1):P3V3_E1S_0

Q_RES  I82  R1675  [Q_RES_0402LF-2.49K,1%,1/16W,CHA]
    2  P3V3_AUX           B  @S9S_MB_2U_LIB.S9S_MB_2U(SCH_1):P3V3_AUX
    1  FM_PCIE_EV_BIF_EN      A  @S9S_MB_2U_LIB.S9S_MB_2U(SCH_1):FM_PCIE_EV_BIF_EN

Q_RES  I94  R1676  [Q_RES_0402LF-1K,1%,1/16W,EMPTYA]
    2  GND                B  @S9S_MB_2U_LIB.S9S_MB_2U(SCH_1):GND
    1  FM_PCIE_EV_BIF_EN      A  @S9S_MB_2U_LIB.S9S_MB_2U(SCH_1):FM_PCIE_EV_BIF_EN

Q_RES  I252  R1680  [Q_RES_0402LF-0,5%,1/16W,CHIP,CA]
    1  FM_PLD_CLK_25M_EN      A  @S9S_MB_2U_LIB.S9S_MB_2U(SCH_1):FM_PLD_CLK_25M_EN
    2  FM_CK440Q_DEV_25M_EN      B  @S9S_MB_2U_LIB.S9S_MB_2U(SCH_1):FM_CK440Q_DEV_25M_EN

Q_RES  I296  R1681  [Q_RES_0402LF-10K,1%,1/16W,CHIPA]
    2  PU_RST_DEDI_BUSY_PLD_N      B  @S9S_MB_2U_LIB.S9S_MB_2U(SCH_1):PU_RST_DEDI_BUSY_PLD_N
    1  P3V3_AUX           A  @S9S_MB_2U_LIB.S9S_MB_2U(SCH_1):P3V3_AUX

Q_RES  I88  R1682  [Q_RES_0402LF-10K,5%,1/16W,CHIPA]
    1  PWRGD_P3V3_R       A  @S9S_MB_2U_LIB.S9S_MB_2U(SCH_1):PWRGD_P3V3_R
    2  PWRGD_P3V3         B  @S9S_MB_2U_LIB.S9S_MB_2U(SCH_1):PWRGD_P3V3

Q_RES  I4   R1688  [Q_RES_0402LF-100K,1%,1/16W,CHIA]
    1  P12V_AUX           A  @S9S_MB_2U_LIB.S9S_MB_2U(SCH_1):P12V_AUX
    2  FM_COMP_P3V3_AUX_VIN      B  @S9S_MB_2U_LIB.S9S_MB_2U(SCH_1):FM_COMP_P3V3_AUX_VIN

Q_RES  I6   R1689  [Q_RES_0402LF-6.19K,1%,1/16W,CHA]
    2  GND                B  @S9S_MB_2U_LIB.S9S_MB_2U(SCH_1):GND
    1  FM_COMP_P3V3_AUX_VIN      A  @S9S_MB_2U_LIB.S9S_MB_2U(SCH_1):FM_COMP_P3V3_AUX_VIN

Q_RES  I2   R1690  [Q_RES_0402LF-10K,1%,1/16W,CHIPA]
    1  P3V3_AUX           A  @S9S_MB_2U_LIB.S9S_MB_2U(SCH_1):P3V3_AUX
    2  FM_COMP_P3V3_AUX_ENIN      B  @S9S_MB_2U_LIB.S9S_MB_2U(SCH_1):FM_COMP_P3V3_AUX_ENIN

Q_RES  I59  R1691  [Q_RES_0402LF-10K,1%,1/16W,EMPTA]
    2  PWRGD_DSW_PWROK_R1      B  @S9S_MB_2U_LIB.S9S_MB_2U(SCH_1):PWRGD_DSW_PWROK_R1
    1  P3V3_AUX           A  @S9S_MB_2U_LIB.S9S_MB_2U(SCH_1):P3V3_AUX

Q_RES  I56  R1692  [Q_RES_0402LF-100K,1%,1/16W,CHIA]
    1  PWRGD_DSW_PWROK_R1      A  @S9S_MB_2U_LIB.S9S_MB_2U(SCH_1):PWRGD_DSW_PWROK_R1
    2  GND                B  @S9S_MB_2U_LIB.S9S_MB_2U(SCH_1):GND

Q_RES  I50  R1693  [Q_RES_0402LF-33.2,1%,1/16W,CHIA]
    1  PWRGD_DSW_PWROK_R2      A  @S9S_MB_2U_LIB.S9S_MB_2U(SCH_1):PWRGD_DSW_PWROK_R2
    2  PWRGD_DSW_PWROK      B  @S9S_MB_2U_LIB.S9S_MB_2U(SCH_1):PWRGD_DSW_PWROK

Q_RES  I46  R1694  [Q_RES_0402LF-10K,1%,1/16W,CHIPA]
    2  PWRGD_DSW_PWROK      B  @S9S_MB_2U_LIB.S9S_MB_2U(SCH_1):PWRGD_DSW_PWROK
    1  P3V3_AUX           A  @S9S_MB_2U_LIB.S9S_MB_2U(SCH_1):P3V3_AUX

Q_RES  I45  R1695  [Q_RES_0402LF-0,5%,1/16W,EMPTY,A]
    2  RST_RSMRST_PCH_N      B  @S9S_MB_2U_LIB.S9S_MB_2U(SCH_1):RST_RSMRST_PCH_N
    1  PWRGD_DSW_PWROK      A  @S9S_MB_2U_LIB.S9S_MB_2U(SCH_1):PWRGD_DSW_PWROK

Q_RES  I186  R1697  [Q_RES_0402LF-10K,1%,1/16W,CHIPA]
    1  PGPPA_AUX          A  @S9S_MB_2U_LIB.S9S_MB_2U(SCH_1):PGPPA_AUX
    2  M2_SSD0_CLKREQ_LV_EN_N      B  @S9S_MB_2U_LIB.S9S_MB_2U(SCH_1):M2_SSD0_CLKREQ_LV_EN_N

Q_RES  I89  R1698  [Q_RES_0402LF-20K,5%,1/16W,CHIPA]
    1  PWRGD_P3V3         A  @S9S_MB_2U_LIB.S9S_MB_2U(SCH_1):PWRGD_P3V3
    2  GND                B  @S9S_MB_2U_LIB.S9S_MB_2U(SCH_1):GND

Q_RES  I48  R1700  [Q_RES_0402LF-4.7K,5%,1/16W,CHIA]
    2  SMB_PCIE_M2_EN      B  @S9S_MB_2U_LIB.S9S_MB_2U(SCH_1):SMB_PCIE_M2_EN
    1  P1V8_PCH_AUX       A  @S9S_MB_2U_LIB.S9S_MB_2U(SCH_1):P1V8_PCH_AUX

Q_RES  I49  R1701  [Q_RES_0402LF-100K,1%,1/16W,EMPB]
    1  SMB_PCIE_M2_EN      A  @S9S_MB_2U_LIB.S9S_MB_2U(SCH_1):SMB_PCIE_M2_EN
    2  GND                B  @S9S_MB_2U_LIB.S9S_MB_2U(SCH_1):GND

Q_RES  I43  R1702  [Q_RES_0402LF-4.7K,5%,1/16W,CHIA]
    2  SMB_M2_P0_1V8AUX_SDA      B  @S9S_MB_2U_LIB.S9S_MB_2U(SCH_1):SMB_M2_P0_1V8AUX_SDA
    1  P1V8_PCH_AUX       A  @S9S_MB_2U_LIB.S9S_MB_2U(SCH_1):P1V8_PCH_AUX

Q_RES  I45  R1703  [Q_RES_0402LF-4.7K,5%,1/16W,CHIA]
    2  SMB_M2_P0_1V8AUX_SCL      B  @S9S_MB_2U_LIB.S9S_MB_2U(SCH_1):SMB_M2_P0_1V8AUX_SCL
    1  P1V8_PCH_AUX       A  @S9S_MB_2U_LIB.S9S_MB_2U(SCH_1):P1V8_PCH_AUX

Q_RES  I68  R1706  [Q_RES_0402LF-4.7K,5%,1/16W,EMPA]
    2  PWRGD_P3V3         B  @S9S_MB_2U_LIB.S9S_MB_2U(SCH_1):PWRGD_P3V3
    1  P3V3               A  @S9S_MB_2U_LIB.S9S_MB_2U(SCH_1):P3V3

Q_RES  I414  R1710  [Q_RES_0402LF-49.9     ,1%  ,1/A]
    1  FM_PLD_REV_R_N      A  @S9S_MB_2U_LIB.S9S_MB_2U(SCH_1):FM_PLD_REV_R_N
    2  FM_PLD_REV_N       B  @S9S_MB_2U_LIB.S9S_MB_2U(SCH_1):FM_PLD_REV_N

Q_RES  I129  R1712  [Q_RES_0402LF-1K,1%,1/16W,CHIP,A]
    1  SMB_VR_3V3AUX_SDA_R      A  @S9S_MB_2U_LIB.S9S_MB_2U(SCH_1):SMB_VR_3V3AUX_SDA_R
    2  P3V3_AUX           B  @S9S_MB_2U_LIB.S9S_MB_2U(SCH_1):P3V3_AUX

Q_RES  I130  R1713  [Q_RES_0402LF-1K,1%,1/16W,CHIP,A]
    1  SMB_VR_3V3AUX_SCL_R      A  @S9S_MB_2U_LIB.S9S_MB_2U(SCH_1):SMB_VR_3V3AUX_SCL_R
    2  P3V3_AUX           B  @S9S_MB_2U_LIB.S9S_MB_2U(SCH_1):P3V3_AUX

Q_RES  I26  R1717  [Q_RES_0402LF-49.9     ,1%  ,1/A]
    2  SVID_CLK1_CPU0_R      B  @S9S_MB_2U_LIB.S9S_MB_2U(SCH_1):SVID_CLK1_CPU0_R
    1  PVNN_TERM_CPU0      A  @S9S_MB_2U_LIB.S9S_MB_2U(SCH_1):PVNN_TERM_CPU0

Q_RES  I119  R1719  [Q_RES_0402LF-33.2,1%,1/16W,CHIA]
    2  OCP_SFF_AUX_PWR_EN_R1      B  @S9S_MB_2U_LIB.S9S_MB_2U(SCH_1):OCP_SFF_AUX_PWR_EN_R1
    1  OCP_SFF_AUX_PWR_EN      A  @S9S_MB_2U_LIB.S9S_MB_2U(SCH_1):OCP_SFF_AUX_PWR_EN

Q_RES  I103  R1720  [Q_RES_0402LF-0,5%,1/16W,EMPTY,A]
    1  XTAL_PCH_25M_IN_R      A  @S9S_MB_2U_LIB.S9S_MB_2U(SCH_1):XTAL_PCH_25M_IN_R
    2  XTAL_PCH_25M_IN      B  @S9S_MB_2U_LIB.S9S_MB_2U(SCH_1):XTAL_PCH_25M_IN

Q_RES  I104  R1721  [Q_RES_0402LF-0,5%,1/16W,CHIP,CA]
    1  XTAL_PCH_RTC2_R      A  @S9S_MB_2U_LIB.S9S_MB_2U(SCH_1):XTAL_PCH_RTC2_R
    2  XTAL_PCH_RTC2      B  @S9S_MB_2U_LIB.S9S_MB_2U(SCH_1):XTAL_PCH_RTC2

Q_RES  I287  R1724  [Q_RES_0402LF-0,5%,1/16W,CHIP,CA]
    1  XTAL_CLK_GEN1_25M_X1_R      A  @S9S_MB_2U_LIB.S9S_MB_2U(SCH_1):XTAL_CLK_GEN1_25M_X1_R
    2  XTAL_CLK_GEN1_25M_X1      B  @S9S_MB_2U_LIB.S9S_MB_2U(SCH_1):XTAL_CLK_GEN1_25M_X1

Q_RES  I125  R1731  [Q_RES_0402LF-2K,1%,1/16W,CHIP,A]
    1  SMB_VR_3V3AUX_SCL      A  @S9S_MB_2U_LIB.S9S_MB_2U(SCH_1):SMB_VR_3V3AUX_SCL
    2  P3V3_AUX           B  @S9S_MB_2U_LIB.S9S_MB_2U(SCH_1):P3V3_AUX

Q_RES  I124  R1732  [Q_RES_0402LF-2K,1%,1/16W,CHIP,A]
    1  SMB_VR_3V3AUX_SDA      A  @S9S_MB_2U_LIB.S9S_MB_2U(SCH_1):SMB_VR_3V3AUX_SDA
    2  P3V3_AUX           B  @S9S_MB_2U_LIB.S9S_MB_2U(SCH_1):P3V3_AUX

Q_RES  I25  R1735  [Q_RES_0402LF-100,1%,1/16W,CHIPA]
    2  SVID_DIO1_CPU0_R      B  @S9S_MB_2U_LIB.S9S_MB_2U(SCH_1):SVID_DIO1_CPU0_R
    1  PVNN_TERM_CPU0      A  @S9S_MB_2U_LIB.S9S_MB_2U(SCH_1):PVNN_TERM_CPU0

Q_RES  I89  R1736  [Q_RES_0402LF-0,5%,1/16W,CHIP,CA]
    2  FM_SLP_SUS_RSM_RST_N      B  @S9S_MB_2U_LIB.S9S_MB_2U(SCH_1):FM_SLP_SUS_RSM_RST_N
    1  FM_PCH_SLP_SUS_N      A  @S9S_MB_2U_LIB.S9S_MB_2U(SCH_1):FM_PCH_SLP_SUS_N

Q_RES  I201  R1738  [Q_RES_0402LF-100,1%,1/16W,CHIPA]
    1  PD_MAIN_FPGA_N13      A  @S9S_MB_2U_LIB.S9S_MB_2U(SCH_1):PD_MAIN_FPGA_N13
    2  GND                B  @S9S_MB_2U_LIB.S9S_MB_2U(SCH_1):GND

Q_RES  I202  R1739  [Q_RES_0402LF-100,1%,1/16W,CHIPA]
    1  PD_MAIN_FPGA_F7      A  @S9S_MB_2U_LIB.S9S_MB_2U(SCH_1):PD_MAIN_FPGA_F7
    2  GND                B  @S9S_MB_2U_LIB.S9S_MB_2U(SCH_1):GND

Q_RES  I330  R1741  [Q_RES_0402LF-1K,1%,1/16W,CHIP,A]
    2  P3V3_AUX           B  @S9S_MB_2U_LIB.S9S_MB_2U(SCH_1):P3V3_AUX
    1  FM_RST_PERST_BIT0      A  @S9S_MB_2U_LIB.S9S_MB_2U(SCH_1):FM_RST_PERST_BIT0

Q_RES  I329  R1742  [Q_RES_0402LF-10K,1%,1/16W,EMPTA]
    2  GND                B  @S9S_MB_2U_LIB.S9S_MB_2U(SCH_1):GND
    1  FM_RST_PERST_BIT0      A  @S9S_MB_2U_LIB.S9S_MB_2U(SCH_1):FM_RST_PERST_BIT0

Q_RES  I94  R1744  [Q_RES_0402LF-0,5%,1/16W,CHIP,CA]
    1  FM_BMC_PWRBTN_OUT_N      A  @S9S_MB_2U_LIB.S9S_MB_2U(SCH_1):FM_BMC_PWRBTN_OUT_N
    2  FM_BMC_PWRBTN_N      B  @S9S_MB_2U_LIB.S9S_MB_2U(SCH_1):FM_BMC_PWRBTN_N

Q_RES  I33  R1745  [Q_RES_0402LF-0,5%,1/16W,EMPTY,A]
    2  FM_PFR_DSW_PWROK_N      B  @S9S_MB_2U_LIB.S9S_MB_2U(SCH_1):FM_PFR_DSW_PWROK_N
    1  FM_COMP_P3V3_AUX_ENIN      A  @S9S_MB_2U_LIB.S9S_MB_2U(SCH_1):FM_COMP_P3V3_AUX_ENIN

Q_RES  I2   R1747  [Q_RES_0805LF-0,5%,1/8W,CHIP,CSA]
    2  PGPPA_AUX          B  @S9S_MB_2U_LIB.S9S_MB_2U(SCH_1):PGPPA_AUX
    1  P1V8_PCH_AUX       A  @S9S_MB_2U_LIB.S9S_MB_2U(SCH_1):P1V8_PCH_AUX

Q_RES  I54  R1748  [Q_RES_0402LF-0,5%,1/16W,CHIP,CA]
    2  FM_ESPI_PLD_R_EN      B  @S9S_MB_2U_LIB.S9S_MB_2U(SCH_1):FM_ESPI_PLD_R_EN
    1  FM_ESPI_PLD_EN      A  @S9S_MB_2U_LIB.S9S_MB_2U(SCH_1):FM_ESPI_PLD_EN

Q_RES  I75  R1749  [Q_RES_0402LF-10K,1%,1/16W,EMPTA]
    2  GND                B  @S9S_MB_2U_LIB.S9S_MB_2U(SCH_1):GND
    1  FM_ESPI_PLD_R_EN      A  @S9S_MB_2U_LIB.S9S_MB_2U(SCH_1):FM_ESPI_PLD_R_EN

Q_RES  I59  R1750  [Q_RES_0402LF-1K,1%,1/16W,CHIP,A]
    1  PGPPA_AUX          A  @S9S_MB_2U_LIB.S9S_MB_2U(SCH_1):PGPPA_AUX
    2  FM_ESPI_PLD_R_EN      B  @S9S_MB_2U_LIB.S9S_MB_2U(SCH_1):FM_ESPI_PLD_R_EN

Q_RES  I81  R1751  [Q_RES_0402LF-33.2,1%,1/16W,CHIA]
    1  SGPIO_DO_0         A  @S9S_MB_2U_LIB.S9S_MB_2U(SCH_1):SGPIO_DO_0
    2  SGPIO_BMC_DOUT      B  @S9S_MB_2U_LIB.S9S_MB_2U(SCH_1):SGPIO_BMC_DOUT

Q_RES  I82  R1752  [Q_RES_0402LF-33.2,1%,1/16W,CHIA]
    1  SGPIO_CLK_0        A  @S9S_MB_2U_LIB.S9S_MB_2U(SCH_1):SGPIO_CLK_0
    2  SGPIO_BMC_CLK      B  @S9S_MB_2U_LIB.S9S_MB_2U(SCH_1):SGPIO_BMC_CLK

Q_RES  I84  R1753  [Q_RES_0402LF-33.2,1%,1/16W,CHIA]
    1  SGPIO_DI_0         A  @S9S_MB_2U_LIB.S9S_MB_2U(SCH_1):SGPIO_DI_0
    2  SGPIO_BMC_DIN_R      B  @S9S_MB_2U_LIB.S9S_MB_2U(SCH_1):SGPIO_BMC_DIN_R

Q_RES  I88  R1754  [Q_RES_0402LF-33.2,1%,1/16W,CHIA]
    1  SGPIO_LD_0         A  @S9S_MB_2U_LIB.S9S_MB_2U(SCH_1):SGPIO_LD_0
    2  SGPIO_BMC_LD_N      B  @S9S_MB_2U_LIB.S9S_MB_2U(SCH_1):SGPIO_BMC_LD_N

Q_RES  I96  R1755  [Q_RES_0402LF-33.2,1%,1/16W,CHIA]
    1  SGPIO_DO_1         A  @S9S_MB_2U_LIB.S9S_MB_2U(SCH_1):SGPIO_DO_1
    2  SGPIO_DEBUG_PLD_DOUT      B  @S9S_MB_2U_LIB.S9S_MB_2U(SCH_1):SGPIO_DEBUG_PLD_DOUT

Q_RES  I98  R1756  [Q_RES_0402LF-33.2,1%,1/16W,CHIA]
    2  SGPIO_DEBUG_PLD_CLK      B  @S9S_MB_2U_LIB.S9S_MB_2U(SCH_1):SGPIO_DEBUG_PLD_CLK
    1  SGPIO_CLK_1        A  @S9S_MB_2U_LIB.S9S_MB_2U(SCH_1):SGPIO_CLK_1

Q_RES  I99  R1757  [Q_RES_0402LF-33.2,1%,1/16W,CHIA]
    1  SGPIO_DI_1         A  @S9S_MB_2U_LIB.S9S_MB_2U(SCH_1):SGPIO_DI_1
    2  SGPIO_DEBUG_PLD_DIN      B  @S9S_MB_2U_LIB.S9S_MB_2U(SCH_1):SGPIO_DEBUG_PLD_DIN

Q_RES  I91  R1758  [Q_RES_0402LF-33.2,1%,1/16W,CHIA]
    1  SGPIO_LD_1         A  @S9S_MB_2U_LIB.S9S_MB_2U(SCH_1):SGPIO_LD_1
    2  SGPIO_DEBUG_PLD_LD_N      B  @S9S_MB_2U_LIB.S9S_MB_2U(SCH_1):SGPIO_DEBUG_PLD_LD_N

Q_RES  I12  R1759  [Q_RES_0402LF-0,5%,1/16W,EMPTY,A]
    2  SMB_S3M_CPU0_LVC1_SCL      B  @S9S_MB_2U_LIB.S9S_MB_2U(SCH_1):SMB_S3M_CPU0_LVC1_SCL
    1  SMB_S3M_CPU0_3V3AUX_SCL      A  @S9S_MB_2U_LIB.S9S_MB_2U(SCH_1):SMB_S3M_CPU0_3V3AUX_SCL

Q_RES  I11  R1760  [Q_RES_0402LF-0,5%,1/16W,EMPTY,A]
    2  SMB_S3M_CPU0_LVC1_SDA      B  @S9S_MB_2U_LIB.S9S_MB_2U(SCH_1):SMB_S3M_CPU0_LVC1_SDA
    1  SMB_S3M_CPU0_3V3AUX_SDA      A  @S9S_MB_2U_LIB.S9S_MB_2U(SCH_1):SMB_S3M_CPU0_3V3AUX_SDA

Q_RES  I160  R1761  [Q_RES_0402LF-33,5%,1/16W,CHIP,A]
    2  SMB_PLD_3V3AUX_SCL_R      B  @S9S_MB_2U_LIB.S9S_MB_2U(SCH_1):SMB_PLD_3V3AUX_SCL_R
    1  SMB_PLD_3V3AUX_SCL      A  @S9S_MB_2U_LIB.S9S_MB_2U(SCH_1):SMB_PLD_3V3AUX_SCL

Q_RES  I161  R1762  [Q_RES_0402LF-33,5%,1/16W,CHIP,A]
    2  SMB_PLD_3V3AUX_SDA_R      B  @S9S_MB_2U_LIB.S9S_MB_2U(SCH_1):SMB_PLD_3V3AUX_SDA_R
    1  SMB_PLD_3V3AUX_SDA      A  @S9S_MB_2U_LIB.S9S_MB_2U(SCH_1):SMB_PLD_3V3AUX_SDA

Q_RES  I7   R1763  [Q_RES_0402LF-10K,1%,1/16W,EMPTA]
    1  PGPPA_AUX          A  @S9S_MB_2U_LIB.S9S_MB_2U(SCH_1):PGPPA_AUX
    2  FM_LPC_ESPI_SEL      B  @S9S_MB_2U_LIB.S9S_MB_2U(SCH_1):FM_LPC_ESPI_SEL

Q_RES  I8   R1764  [Q_RES_0402LF-1K,1%,1/16W,EMPTYA]
    2  GND                B  @S9S_MB_2U_LIB.S9S_MB_2U(SCH_1):GND
    1  FM_LPC_ESPI_SEL      A  @S9S_MB_2U_LIB.S9S_MB_2U(SCH_1):FM_LPC_ESPI_SEL

Q_RES  I13  R1765  [Q_RES_0805LF-0,5%,1/8W,EMPTY,CA]
    1  PGPPA_AUX          A  @S9S_MB_2U_LIB.S9S_MB_2U(SCH_1):PGPPA_AUX
    2  P3V3_AUX           B  @S9S_MB_2U_LIB.S9S_MB_2U(SCH_1):P3V3_AUX

Q_RES  I244  R1778  [Q_RES_0402LF-0,5%,1/16W,EMPTY,A]
    2  M2_SSD0_CLKREQ_LV_EN_N      B  @S9S_MB_2U_LIB.S9S_MB_2U(SCH_1):M2_SSD0_CLKREQ_LV_EN_N
    1  M2_SSD0_CLKREQ_EN_N      A  @S9S_MB_2U_LIB.S9S_MB_2U(SCH_1):M2_SSD0_CLKREQ_EN_N

Q_RES  I14  R1784  [Q_RES_0402LF-4.7K,1%,1/16W,EMPA]
    2  VOL_SEN_ADDR       B  @S9S_MB_2U_LIB.S9S_MB_2U(SCH_1):VOL_SEN_ADDR
    1  P3V3_AUX           A  @S9S_MB_2U_LIB.S9S_MB_2U(SCH_1):P3V3_AUX

Q_RES  I17  R1785  [Q_RES_0402LF-4.7K,1%,1/16W,CHIA]
    1  VOL_SEN_ADDR       A  @S9S_MB_2U_LIB.S9S_MB_2U(SCH_1):VOL_SEN_ADDR
    2  GND                B  @S9S_MB_2U_LIB.S9S_MB_2U(SCH_1):GND

Q_RES  I27  R1786  [Q_RES_0402LF-0,1%,1/16W,CHIP,TA]
    2  P3V3_AUX_SENSE      B  @S9S_MB_2U_LIB.S9S_MB_2U(SCH_1):P3V3_AUX_SENSE
    1  P3V3_AUX           A  @S9S_MB_2U_LIB.S9S_MB_2U(SCH_1):P3V3_AUX

Q_RES  I28  R1787  [Q_RES_0402LF-1K,0.1%,1/16W,CHIA]
    1  P3V3_AUX_SENSE      A  @S9S_MB_2U_LIB.S9S_MB_2U(SCH_1):P3V3_AUX_SENSE
    2  GND                B  @S9S_MB_2U_LIB.S9S_MB_2U(SCH_1):GND

Q_RES  I31  R1788  [Q_RES_0402LF-0,1%,1/16W,CHIP,TA]
    2  P3V3_SENSE         B  @S9S_MB_2U_LIB.S9S_MB_2U(SCH_1):P3V3_SENSE
    1  P3V3               A  @S9S_MB_2U_LIB.S9S_MB_2U(SCH_1):P3V3

Q_RES  I34  R1789  [Q_RES_0402LF-1K,0.1%,1/16W,CHIA]
    1  P3V3_SENSE         A  @S9S_MB_2U_LIB.S9S_MB_2U(SCH_1):P3V3_SENSE
    2  GND                B  @S9S_MB_2U_LIB.S9S_MB_2U(SCH_1):GND

Q_RES  I40  R1790  [Q_RES_0402LF-1K,1%,1/16W,EMPTYA]
    1  P3V_BAT            A  @S9S_MB_2U_LIB.S9S_MB_2U(SCH_1):P3V_BAT
    2  P3V3_RTC_AUX_SENSE      B  @S9S_MB_2U_LIB.S9S_MB_2U(SCH_1):P3V3_RTC_AUX_SENSE

Q_RES  I43  R1791  [Q_RES_0402LF-200K,1%,1/16W,CHIA]
    1  P3V3_RTC_AUX_SENSE      A  @S9S_MB_2U_LIB.S9S_MB_2U(SCH_1):P3V3_RTC_AUX_SENSE
    2  GND                B  @S9S_MB_2U_LIB.S9S_MB_2U(SCH_1):GND

Q_RES  I20  R1792  [Q_RES_0402LF-0,5%,1/16W,CHIP,CA]
    2  SMB_SEN_3V3AUX_SDA      B  @S9S_MB_2U_LIB.S9S_MB_2U(SCH_1):SMB_SEN_3V3AUX_SDA
    1  NC                 A  NC

Q_RES  I19  R1793  [Q_RES_0402LF-0,5%,1/16W,CHIP,CA]
    2  SMB_SEN_3V3AUX_SCL      B  @S9S_MB_2U_LIB.S9S_MB_2U(SCH_1):SMB_SEN_3V3AUX_SCL
    1  NC                 A  NC

Q_RES  I10  R1794  [Q_RES_0402LF-4.7K,1%,1/16W,EMPA]
    2  VOL_SEN_ALERT      B  @S9S_MB_2U_LIB.S9S_MB_2U(SCH_1):VOL_SEN_ALERT
    1  P3V3_AUX           A  @S9S_MB_2U_LIB.S9S_MB_2U(SCH_1):P3V3_AUX

Q_RES  I615  R1798  [Q_RES_0402LF-0,5%,1/16W,CHIP,CA]
    1  ROT_P1_RST_IND_N_R      A  @S9S_MB_2U_LIB.S9S_MB_2U(SCH_1):ROT_P1_RST_IND_N_R
    2  ROT_P1_RST_IND_N      B  @S9S_MB_2U_LIB.S9S_MB_2U(SCH_1):ROT_P1_RST_IND_N

Q_RES  I44  R1799  [Q_RES_0402LF-33K    ,1%  ,1/16A]
    2  P12V_AUX_SENSE      B  @S9S_MB_2U_LIB.S9S_MB_2U(SCH_1):P12V_AUX_SENSE
    1  P12V_AUX           A  @S9S_MB_2U_LIB.S9S_MB_2U(SCH_1):P12V_AUX

Q_RES  I46  R1800  [Q_RES_0402LF-120K,1%,1/16W,CHIA]
    1  P12V_AUX_SENSE      A  @S9S_MB_2U_LIB.S9S_MB_2U(SCH_1):P12V_AUX_SENSE
    2  GND                B  @S9S_MB_2U_LIB.S9S_MB_2U(SCH_1):GND

Q_RES  I398  R1801  [Q_RES_0402LF-0,5%,1/16W,CHIP,CA]
    1  PRSNT0_N           A  @S9S_MB_2U_LIB.S9S_MB_2U(SCH_1):PRSNT0_N
    2  GND                B  @S9S_MB_2U_LIB.S9S_MB_2U(SCH_1):GND

Q_RES  I89  R1809  [Q_RES_0402LF-20K,1%,1/16W,CHIPA]
    1  P3V3_AUX           A  @S9S_MB_2U_LIB.S9S_MB_2U(SCH_1):P3V3_AUX
    2  FM_ADR_MODE0       B  @S9S_MB_2U_LIB.S9S_MB_2U(SCH_1):FM_ADR_MODE0

Q_RES  I88  R1810  [Q_RES_0402LF-1K,5%,1/16W,EMPTYA]
    2  GND                B  @S9S_MB_2U_LIB.S9S_MB_2U(SCH_1):GND
    1  FM_ADR_MODE0       A  @S9S_MB_2U_LIB.S9S_MB_2U(SCH_1):FM_ADR_MODE0

Q_RES  I110  R1811  [Q_RES_0402LF-33.2,1%,1/16W,CHIA]
    2  RST_SGPIO_RESET_N_R      B  @S9S_MB_2U_LIB.S9S_MB_2U(SCH_1):RST_SGPIO_RESET_N_R
    1  RST_SGPIO_RESET_N      A  @S9S_MB_2U_LIB.S9S_MB_2U(SCH_1):RST_SGPIO_RESET_N

Q_RES  I111  R1812  [Q_RES_0402LF-33.2,1%,1/16W,CHIA]
    2  IRQ_SGPIO_INTR_N_R      B  @S9S_MB_2U_LIB.S9S_MB_2U(SCH_1):IRQ_SGPIO_INTR_N_R
    1  IRQ_SGPIO_INTR_N      A  @S9S_MB_2U_LIB.S9S_MB_2U(SCH_1):IRQ_SGPIO_INTR_N

Q_RES  I79  R1813  [Q_RES_0402LF-10K,1%,1/16W,EMPTA]
    1  P3V3_AUX           A  @S9S_MB_2U_LIB.S9S_MB_2U(SCH_1):P3V3_AUX
    2  FM_JTAG_BMC_MUX_SEL      B  @S9S_MB_2U_LIB.S9S_MB_2U(SCH_1):FM_JTAG_BMC_MUX_SEL

Q_RES  I77  R1814  [Q_RES_0402LF-1K,1%,1/16W,CHIP,A]
    2  GND                B  @S9S_MB_2U_LIB.S9S_MB_2U(SCH_1):GND
    1  FM_JTAG_BMC_MUX_SEL      A  @S9S_MB_2U_LIB.S9S_MB_2U(SCH_1):FM_JTAG_BMC_MUX_SEL

Q_RES  I527  R1815  [Q_RES_0402LF-0,5%,1/16W,CHIP,CA]
    2  FM_BMC_PWRBTN_OUT_R_N      B  @S9S_MB_2U_LIB.S9S_MB_2U(SCH_1):FM_BMC_PWRBTN_OUT_R_N
    1  FM_BMC_PWRBTN_OUT_N      A  @S9S_MB_2U_LIB.S9S_MB_2U(SCH_1):FM_BMC_PWRBTN_OUT_N

Q_RES  I605  R1816  [Q_RES_0402LF-0,5%,1/16W,CHIP,CA]
    2  PWRGD_PS_PWROK_R      B  @S9S_MB_2U_LIB.S9S_MB_2U(SCH_1):PWRGD_PS_PWROK_R
    1  PWRGD_PS_PWROK      A  @S9S_MB_2U_LIB.S9S_MB_2U(SCH_1):PWRGD_PS_PWROK

Q_RES  I35  R1820  [Q_RES_0402LF-10K,1%,1/16W,CHIPA]
    1  P3V3_AUX           A  @S9S_MB_2U_LIB.S9S_MB_2U(SCH_1):P3V3_AUX
    2  FM_PLT_BMC_THERMTRIP_R_N      B  @S9S_MB_2U_LIB.S9S_MB_2U(SCH_1):FM_PLT_BMC_THERMTRIP_R_N

Q_RES  I90  R1821  [Q_RES_0402LF-0,5%,1/16W,EMPTY,A]
    1  FM_SPD_REMOTE_EN_R      A  @S9S_MB_2U_LIB.S9S_MB_2U(SCH_1):FM_SPD_REMOTE_EN_R
    2  FM_SPD_REMOTE_EN      B  @S9S_MB_2U_LIB.S9S_MB_2U(SCH_1):FM_SPD_REMOTE_EN

Q_RES  I152  R1822  [Q_RES_0402LF-10K,1%,1/16W,CHIPA]
    2  PU_RST_SMB_PCIE3_N      B  @S9S_MB_2U_LIB.S9S_MB_2U(SCH_1):PU_RST_SMB_PCIE3_N
    1  P3V3_AUX           A  @S9S_MB_2U_LIB.S9S_MB_2U(SCH_1):P3V3_AUX

Q_RES  I152  R1823  [Q_RES_0402LF-1K,1%,1/16W,CHIP,A]
    2  RST_MB_STBY_R_N      B  @S9S_MB_2U_LIB.S9S_MB_2U(SCH_1):RST_MB_STBY_R_N
    1  P3V3_AUX           A  @S9S_MB_2U_LIB.S9S_MB_2U(SCH_1):P3V3_AUX

Q_RES  I62  R1824  [Q_RES_0402LF-10K,1%,1/16W,CHIPA]
    1  P3V3_OCP_SFF       A  @S9S_MB_2U_LIB.S9S_MB_2U(SCH_1):P3V3_OCP_SFF
    2  IRQ_LVC3_OCP_SFF_WAKE_N      B  @S9S_MB_2U_LIB.S9S_MB_2U(SCH_1):IRQ_LVC3_OCP_SFF_WAKE_N

Q_RES  I193  R1827  [Q_RES_0402LF-33,5%,1/16W,CHIP,A]
    1  USB_OC1_REAR_R_N      A  @S9S_MB_2U_LIB.S9S_MB_2U(SCH_1):USB_OC1_REAR_R_N
    2  USB_OC1_REAR_N      B  @S9S_MB_2U_LIB.S9S_MB_2U(SCH_1):USB_OC1_REAR_N

Q_RES  I188  R1828  [Q_RES_0402LF-10K,1%,1/16W,CHIPA]
    1  USB_OC1_REAR_R_N      A  @S9S_MB_2U_LIB.S9S_MB_2U(SCH_1):USB_OC1_REAR_R_N
    2  P3V3_AUX           B  @S9S_MB_2U_LIB.S9S_MB_2U(SCH_1):P3V3_AUX

Q_RES  I20  R1829  [Q_RES_0402LF-0,5%,1/16W,EMPTY,A]
    2  SMB_S3M_CPU1_LVC1_SCL      B  @S9S_MB_2U_LIB.S9S_MB_2U(SCH_1):SMB_S3M_CPU1_LVC1_SCL
    1  SMB_S3M_CPU1_3V3AUX_SCL      A  @S9S_MB_2U_LIB.S9S_MB_2U(SCH_1):SMB_S3M_CPU1_3V3AUX_SCL

Q_RES  I19  R1830  [Q_RES_0402LF-0,5%,1/16W,EMPTY,A]
    2  SMB_S3M_CPU1_LVC1_SDA      B  @S9S_MB_2U_LIB.S9S_MB_2U(SCH_1):SMB_S3M_CPU1_LVC1_SDA
    1  SMB_S3M_CPU1_3V3AUX_SDA      A  @S9S_MB_2U_LIB.S9S_MB_2U(SCH_1):SMB_S3M_CPU1_3V3AUX_SDA

Q_RES  I82  R1831  [Q_RES_0402LF-0,5%,1/16W,EMPTY,A]
    2  JTAG_DBP_BMC_PRDY_R_N      B  @S9S_MB_2U_LIB.S9S_MB_2U(SCH_1):JTAG_DBP_BMC_PRDY_R_N
    1  JTAG_DBP_BMC_PRDY_N      A  @S9S_MB_2U_LIB.S9S_MB_2U(SCH_1):JTAG_DBP_BMC_PRDY_N

Q_RES  I80  R1832  [Q_RES_0402LF-0,5%,1/16W,EMPTY,A]
    2  JTAG_DBP_BMC_PREQ_R_N      B  @S9S_MB_2U_LIB.S9S_MB_2U(SCH_1):JTAG_DBP_BMC_PREQ_R_N
    1  JTAG_BMC_DBP_PREQ_N      A  @S9S_MB_2U_LIB.S9S_MB_2U(SCH_1):JTAG_BMC_DBP_PREQ_N

Q_RES  I611  R1833  [Q_RES_0402LF-0,5%,1/16W,CHIP,CA]
    2  NC                 B  NC
    1  FM_JTAG_BMC_MUX_SEL      A  @S9S_MB_2U_LIB.S9S_MB_2U(SCH_1):FM_JTAG_BMC_MUX_SEL

Q_RES  I176  R1836  [Q_RES_0402LF-0,5%,1/16W,CHIP,CA]
    1  IRQ_PSU_ALERT_N      A  @S9S_MB_2U_LIB.S9S_MB_2U(SCH_1):IRQ_PSU_ALERT_N
    2  IRQ_P12V_HSC_FAULT_N      B  @S9S_MB_2U_LIB.S9S_MB_2U(SCH_1):IRQ_P12V_HSC_FAULT_N

Q_RES_4P_12  I1   R1837  [Q_RES_4P_12-0.001,1%,3W,SMLF,CA]
    4  P12V_S3_AUX_CPU1_NVDIMM_ISENS_1      4  @S9S_MB_2U_LIB.S9S_MB_2U(SCH_1):P12V_S3_AUX_CPU1_NVDIMM_ISENSE_P
    3  P12V_S3_AUX_CPU1_NVDIMM_ISENSE_      3  @S9S_MB_2U_LIB.S9S_MB_2U(SCH_1):P12V_S3_AUX_CPU1_NVDIMM_ISENSE_N
    1  P12V_S3_AUX_CPU1_NVDIMM      1  @S9S_MB_2U_LIB.S9S_MB_2U(SCH_1):P12V_S3_AUX_CPU1_NVDIMM
    2  P12V_AUX           2  @S9S_MB_2U_LIB.S9S_MB_2U(SCH_1):P12V_AUX

Q_RES_4P_12  I5   R1838  [Q_RES_4P_12-0.001,1%,3W,SMLF,CA]
    4  P12V_S3_AUX_CPU0_NVDIMM_ISENS_1      4  @S9S_MB_2U_LIB.S9S_MB_2U(SCH_1):P12V_S3_AUX_CPU0_NVDIMM_ISENSE_P
    3  P12V_S3_AUX_CPU0_NVDIMM_ISENSE_      3  @S9S_MB_2U_LIB.S9S_MB_2U(SCH_1):P12V_S3_AUX_CPU0_NVDIMM_ISENSE_N
    1  P12V_S3_AUX_CPU0_NVDIMM      1  @S9S_MB_2U_LIB.S9S_MB_2U(SCH_1):P12V_S3_AUX_CPU0_NVDIMM
    2  P12V_AUX           2  @S9S_MB_2U_LIB.S9S_MB_2U(SCH_1):P12V_AUX

Q_RES  I85  R1839  [Q_RES_0402LF-0,5%,1/16W,EMPTY,A]
    2  RST_RTCRST_N       B  @S9S_MB_2U_LIB.S9S_MB_2U(SCH_1):RST_RTCRST_N
    1  RST_PFR_OVR_RTC      A  @S9S_MB_2U_LIB.S9S_MB_2U(SCH_1):RST_PFR_OVR_RTC

Q_RES  I89  R1840  [Q_RES_0402LF-0,5%,1/16W,EMPTY,A]
    2  RST_SRTCRST_N      B  @S9S_MB_2U_LIB.S9S_MB_2U(SCH_1):RST_SRTCRST_N
    1  RST_PFR_OVR_SRTC      A  @S9S_MB_2U_LIB.S9S_MB_2U(SCH_1):RST_PFR_OVR_SRTC

Q_RES  I245  R1841  [Q_RES_0402LF-10K,1%,1/16W,EMPTA]
    1  P3V3_AUX           A  @S9S_MB_2U_LIB.S9S_MB_2U(SCH_1):P3V3_AUX
    2  FM_CPU_RMCA_CATERR_LVT3_R_N      B  @S9S_MB_2U_LIB.S9S_MB_2U(SCH_1):FM_CPU_RMCA_CATERR_LVT3_R_N

Q_RES  I115  R1842  [Q_RES_0402LF-33.2,1%,1/16W,CHIA]
    1  FM_JTAG_BMC_PLD_MUX_SEL      A  @S9S_MB_2U_LIB.S9S_MB_2U(SCH_1):FM_JTAG_BMC_PLD_MUX_SEL
    2  FM_JTAG_BMC_MUX_SEL      B  @S9S_MB_2U_LIB.S9S_MB_2U(SCH_1):FM_JTAG_BMC_MUX_SEL

Q_RES  I122  R1843  [Q_RES_0402LF-33.2,1%,1/16W,CHIA]
    1  RST_PFR_OVR_RTC_R      A  @S9S_MB_2U_LIB.S9S_MB_2U(SCH_1):RST_PFR_OVR_RTC_R
    2  RST_PFR_OVR_RTC      B  @S9S_MB_2U_LIB.S9S_MB_2U(SCH_1):RST_PFR_OVR_RTC

Q_RES  I123  R1844  [Q_RES_0402LF-33.2,1%,1/16W,CHIA]
    1  RST_PFR_OVR_SRTC_R      A  @S9S_MB_2U_LIB.S9S_MB_2U(SCH_1):RST_PFR_OVR_SRTC_R
    2  RST_PFR_OVR_SRTC      B  @S9S_MB_2U_LIB.S9S_MB_2U(SCH_1):RST_PFR_OVR_SRTC

Q_RES  I613  R1845  [Q_RES_0402LF-0,5%,1/16W,CHIP,CA]
    2  FM_BMC_CPU_FBRK_OUT_R_N      B  @S9S_MB_2U_LIB.S9S_MB_2U(SCH_1):FM_BMC_CPU_FBRK_OUT_R_N
    1  FM_BMC_CPU_FBRK_OUT_N      A  @S9S_MB_2U_LIB.S9S_MB_2U(SCH_1):FM_BMC_CPU_FBRK_OUT_N

Q_RES  I17  R1850  [Q_RES_0402LF-1K,5%,1/16W,EMPTYA]
    1  GND                A  @S9S_MB_2U_LIB.S9S_MB_2U(SCH_1):GND
    2  FM_PCH_P1V8_AUX_EN_R      B  @S9S_MB_2U_LIB.S9S_MB_2U(SCH_1):FM_PCH_P1V8_AUX_EN_R

Q_RES  I248  R1853  [Q_RES_0402LF-0,5%,1/16W,CHIP,CA]
    1  VIRTUAL_RESEAT_FPGA_R_N      A  @S9S_MB_2U_LIB.S9S_MB_2U(SCH_1):VIRTUAL_RESEAT_FPGA_R_N
    2  VIRTUAL_RESEAT_FPGA_N      B  @S9S_MB_2U_LIB.S9S_MB_2U(SCH_1):VIRTUAL_RESEAT_FPGA_N

Q_RES  I43  R1854  [Q_RES_0402LF-10K,1%,1/16W,CHIPA]
    1  P3V3_AUX           A  @S9S_MB_2U_LIB.S9S_MB_2U(SCH_1):P3V3_AUX
    2  FM_SCM_PRSNT1_N      B  @S9S_MB_2U_LIB.S9S_MB_2U(SCH_1):FM_SCM_PRSNT1_N

Q_RES  I34  R1856  [Q_RES_0402LF-100,1%,1/16W,CHIPA]
    2  FM_SCM_PRSNT1_R_N      B  @S9S_MB_2U_LIB.S9S_MB_2U(SCH_1):FM_SCM_PRSNT1_R_N
    1  FM_SCM_PRSNT1_N      A  @S9S_MB_2U_LIB.S9S_MB_2U(SCH_1):FM_SCM_PRSNT1_N

Q_RES  I29  R1857  [Q_RES_0402LF-10K,1%,1/16W,CHIPA]
    1  P3V3_AUX           A  @S9S_MB_2U_LIB.S9S_MB_2U(SCH_1):P3V3_AUX
    2  P12V_SCM_EN_N      B  @S9S_MB_2U_LIB.S9S_MB_2U(SCH_1):P12V_SCM_EN_N

Q_RES  I61  R1868  [Q_RES_0402LF-0,5%,1/16W,CHIP,CA]
    2  ESPI_LPC_LAD0_IO3      B  @S9S_MB_2U_LIB.S9S_MB_2U(SCH_1):ESPI_LPC_LAD0_IO3
    1  ESPI_LAD0_DATA_IO3      A  @S9S_MB_2U_LIB.S9S_MB_2U(SCH_1):ESPI_LAD0_DATA_IO3

Q_RES  I62  R1869  [Q_RES_0402LF-0,5%,1/16W,CHIP,CA]
    2  ESPI_LPC_LAD0_IO2      B  @S9S_MB_2U_LIB.S9S_MB_2U(SCH_1):ESPI_LPC_LAD0_IO2
    1  ESPI_LAD0_DATA_IO2      A  @S9S_MB_2U_LIB.S9S_MB_2U(SCH_1):ESPI_LAD0_DATA_IO2

Q_RES  I63  R1870  [Q_RES_0402LF-0,5%,1/16W,CHIP,CA]
    2  ESPI_LPC_LAD0_IO1      B  @S9S_MB_2U_LIB.S9S_MB_2U(SCH_1):ESPI_LPC_LAD0_IO1
    1  ESPI_LAD0_DATA_IO1      A  @S9S_MB_2U_LIB.S9S_MB_2U(SCH_1):ESPI_LAD0_DATA_IO1

Q_RES  I64  R1871  [Q_RES_0402LF-0,5%,1/16W,CHIP,CA]
    2  ESPI_LPC_LAD0_IO0      B  @S9S_MB_2U_LIB.S9S_MB_2U(SCH_1):ESPI_LPC_LAD0_IO0
    1  ESPI_LAD0_DATA_IO0      A  @S9S_MB_2U_LIB.S9S_MB_2U(SCH_1):ESPI_LAD0_DATA_IO0

Q_RES  I65  R1872  [Q_RES_0402LF-0,5%,1/16W,CHIP,CA]
    2  ESPI_HOST_LPC_BMC_CLK      B  @S9S_MB_2U_LIB.S9S_MB_2U(SCH_1):ESPI_HOST_LPC_BMC_CLK
    1  CLK_24M_66M_LPC0_ESPI      A  @S9S_MB_2U_LIB.S9S_MB_2U(SCH_1):CLK_24M_66M_LPC0_ESPI

Q_RES  I353  R1895  [Q_RES_0402LF-100,1%,1/16W,CHIPA]
    1  OCP_SFF_PRSNTA_R_N      A  @S9S_MB_2U_LIB.S9S_MB_2U(SCH_1):OCP_SFF_PRSNTA_R_N
    2  GND                B  @S9S_MB_2U_LIB.S9S_MB_2U(SCH_1):GND

Q_RES  I123  R1896  [Q_RES_0402LF-100,1%,1/16W,CHIPA]
    1  OCP_SFF_ISO_BIF0_EN      A  @S9S_MB_2U_LIB.S9S_MB_2U(SCH_1):OCP_SFF_ISO_BIF0_EN
    2  GND                B  @S9S_MB_2U_LIB.S9S_MB_2U(SCH_1):GND

Q_RES  I124  R1897  [Q_RES_0402LF-100,1%,1/16W,CHIPA]
    1  OCP_SFF_ISO_BIF1_EN      A  @S9S_MB_2U_LIB.S9S_MB_2U(SCH_1):OCP_SFF_ISO_BIF1_EN
    2  GND                B  @S9S_MB_2U_LIB.S9S_MB_2U(SCH_1):GND

Q_RES  I122  R1898  [Q_RES_0402LF-100,1%,1/16W,CHIPA]
    1  OCP_SFF_ISO_BIF2_EN      A  @S9S_MB_2U_LIB.S9S_MB_2U(SCH_1):OCP_SFF_ISO_BIF2_EN
    2  GND                B  @S9S_MB_2U_LIB.S9S_MB_2U(SCH_1):GND

Q_RES  I404  R1905  [Q_RES_0402LF-10K,1%,1/16W,CHIPA]
    1  P3V3_AUX           A  @S9S_MB_2U_LIB.S9S_MB_2U(SCH_1):P3V3_AUX
    2  OCP_SFF_PRSNT0_R_N      B  @S9S_MB_2U_LIB.S9S_MB_2U(SCH_1):OCP_SFF_PRSNT0_R_N

Q_RES  I408  R1906  [Q_RES_0402LF-10K,1%,1/16W,CHIPA]
    1  P3V3_AUX           A  @S9S_MB_2U_LIB.S9S_MB_2U(SCH_1):P3V3_AUX
    2  OCP_SFF_PRSNT2_R_N      B  @S9S_MB_2U_LIB.S9S_MB_2U(SCH_1):OCP_SFF_PRSNT2_R_N

Q_RES  I399  R1907  [Q_RES_0402LF-10K,1%,1/16W,CHIPA]
    1  P3V3_AUX           A  @S9S_MB_2U_LIB.S9S_MB_2U(SCH_1):P3V3_AUX
    2  OCP_SFF_PRSNT1_R_N      B  @S9S_MB_2U_LIB.S9S_MB_2U(SCH_1):OCP_SFF_PRSNT1_R_N

Q_RES  I402  R1908  [Q_RES_0402LF-10K,1%,1/16W,CHIPA]
    1  P3V3_AUX           A  @S9S_MB_2U_LIB.S9S_MB_2U(SCH_1):P3V3_AUX
    2  OCP_SFF_PRSNT3_R_N      B  @S9S_MB_2U_LIB.S9S_MB_2U(SCH_1):OCP_SFF_PRSNT3_R_N

Q_RES  I127  R1919  [Q_RES_0402LF-33.2,1%,1/16W,CHIA]
    2  PWRGD_P3V3_AUX_PLD      B  @S9S_MB_2U_LIB.S9S_MB_2U(SCH_1):PWRGD_P3V3_AUX_PLD
    1  PWRGD_P3V3_AUX      A  @S9S_MB_2U_LIB.S9S_MB_2U(SCH_1):PWRGD_P3V3_AUX

Q_RES  I132  R1921  [Q_RES_0402LF-33,5%,1/16W,CHIP,A]
    2  FM_SMB_PEHPCPU0_PCIE_ALERT_N      B  @S9S_MB_2U_LIB.S9S_MB_2U(SCH_1):FM_SMB_PEHPCPU0_PCIE_ALERT_N
    1  FM_SMB_CPU0_ALERT      A  @S9S_MB_2U_LIB.S9S_MB_2U(SCH_1):FM_SMB_CPU0_ALERT

Q_RES  I524  R1925  [Q_RES_0402LF-0,5%,1/16W,CHIP,CA]
    1  IRQ0_A57_R         A  @S9S_MB_2U_LIB.S9S_MB_2U(SCH_1):IRQ0_A57_R
    2  IRQ0_A57           B  @S9S_MB_2U_LIB.S9S_MB_2U(SCH_1):IRQ0_A57

Q_RES  I360  R1929  [Q_RES_0402LF-10K,5%,1/16W,CHIPA]
    2  OCP_SFF_AUX_PWR_EN      B  @S9S_MB_2U_LIB.S9S_MB_2U(SCH_1):OCP_SFF_AUX_PWR_EN
    1  GND                A  @S9S_MB_2U_LIB.S9S_MB_2U(SCH_1):GND

Q_RES  I359  R1930  [Q_RES_0402LF-10K,5%,1/16W,CHIPA]
    2  OCP_SFF_MAIN_PWR_EN      B  @S9S_MB_2U_LIB.S9S_MB_2U(SCH_1):OCP_SFF_MAIN_PWR_EN
    1  GND                A  @S9S_MB_2U_LIB.S9S_MB_2U(SCH_1):GND

Q_RES  I109  R1932  [Q_RES_0402LF-33.2,1%,1/16W,CHIA]
    1  SMB_CPU_PIROM_3V3AUX_SCL      A  @S9S_MB_2U_LIB.S9S_MB_2U(SCH_1):SMB_CPU_PIROM_3V3AUX_SCL
    2  SMB_CPU0_PIROM_3V3AUX_SCL_R      B  @S9S_MB_2U_LIB.S9S_MB_2U(SCH_1):SMB_CPU0_PIROM_3V3AUX_SCL_R

Q_RES  I110  R1933  [Q_RES_0402LF-33.2,1%,1/16W,CHIA]
    1  SMB_CPU_PIROM_3V3AUX_SDA      A  @S9S_MB_2U_LIB.S9S_MB_2U(SCH_1):SMB_CPU_PIROM_3V3AUX_SDA
    2  SMB_CPU0_PIROM_3V3AUX_SDA_R      B  @S9S_MB_2U_LIB.S9S_MB_2U(SCH_1):SMB_CPU0_PIROM_3V3AUX_SDA_R

Q_RES  I81  R1934  [Q_RES_0402LF-33.2,1%,1/16W,CHIA]
    1  SMB_CPU_PIROM_3V3AUX_SCL      A  @S9S_MB_2U_LIB.S9S_MB_2U(SCH_1):SMB_CPU_PIROM_3V3AUX_SCL
    2  SMB_CPU1_PIROM_3V3AUX_SCL_R      B  @S9S_MB_2U_LIB.S9S_MB_2U(SCH_1):SMB_CPU1_PIROM_3V3AUX_SCL_R

Q_RES  I82  R1935  [Q_RES_0402LF-33.2,1%,1/16W,CHIA]
    1  SMB_CPU_PIROM_3V3AUX_SDA      A  @S9S_MB_2U_LIB.S9S_MB_2U(SCH_1):SMB_CPU_PIROM_3V3AUX_SDA
    2  SMB_CPU1_PIROM_3V3AUX_SDA_R      B  @S9S_MB_2U_LIB.S9S_MB_2U(SCH_1):SMB_CPU1_PIROM_3V3AUX_SDA_R

Q_RES  I161  R1940  [Q_RES_0402LF-33.2,1%,1/16W,CHIA]
    1  SMB_PMBUS_PSU1_SCL_R2      A  @S9S_MB_2U_LIB.S9S_MB_2U(SCH_1):SMB_PMBUS_PSU1_SCL_R2
    2  SMB_PMBUS_PSU1_SCL      B  @S9S_MB_2U_LIB.S9S_MB_2U(SCH_1):SMB_PMBUS_PSU1_SCL

Q_RES  I163  R1941  [Q_RES_0402LF-33.2,1%,1/16W,CHIA]
    1  SMB_PMBUS_PSU1_SDA_R2      A  @S9S_MB_2U_LIB.S9S_MB_2U(SCH_1):SMB_PMBUS_PSU1_SDA_R2
    2  SMB_PMBUS_PSU1_SDA      B  @S9S_MB_2U_LIB.S9S_MB_2U(SCH_1):SMB_PMBUS_PSU1_SDA

Q_RES  I384  R1944  [Q_RES_0402LF-0,5%,1/16W,CHIP,CA]
    1  IRQ_PCH_SCI_WHEA_R_N      A  @S9S_MB_2U_LIB.S9S_MB_2U(SCH_1):IRQ_PCH_SCI_WHEA_R_N
    2  IRQ_PCH_SCI_WHEA_N      B  @S9S_MB_2U_LIB.S9S_MB_2U(SCH_1):IRQ_PCH_SCI_WHEA_N

Q_RES  I35  R1950  [Q_RES_0402LF-0,5%,1/16W,CHIP,CA]
    2  PWRGD_P3V3_AUX      B  @S9S_MB_2U_LIB.S9S_MB_2U(SCH_1):PWRGD_P3V3_AUX
    1  FM_COMP_P3V3_AUX_VIN      A  @S9S_MB_2U_LIB.S9S_MB_2U(SCH_1):FM_COMP_P3V3_AUX_VIN

Q_RES  I72  R1955  [Q_RES_0402LF-10K,1%,1/16W,CHIPA]
    1  P3V3_AUX           A  @S9S_MB_2U_LIB.S9S_MB_2U(SCH_1):P3V3_AUX
    2  FM_PCHHOT_N        B  @S9S_MB_2U_LIB.S9S_MB_2U(SCH_1):FM_PCHHOT_N

Q_RES  I146  R1956  [Q_RES_0402LF-100,1%,1/16W,CHIPA]
    2  PVNN_TERM_CPU0      B  @S9S_MB_2U_LIB.S9S_MB_2U(SCH_1):PVNN_TERM_CPU0
    1  H_CPU0_MON_FAIL_LVC1_R_N      A  @S9S_MB_2U_LIB.S9S_MB_2U(SCH_1):H_CPU0_MON_FAIL_LVC1_R_N

Q_RES  I148  R1957  [Q_RES_0402LF-100,1%,1/16W,CHIPA]
    2  PVNN_TERM_CPU1      B  @S9S_MB_2U_LIB.S9S_MB_2U(SCH_1):PVNN_TERM_CPU1
    1  H_CPU1_MON_FAIL_LVC1_R_N      A  @S9S_MB_2U_LIB.S9S_MB_2U(SCH_1):H_CPU1_MON_FAIL_LVC1_R_N

Q_RES  I303  R1958  [Q_RES_0402LF-10K,1%,1/16W,CHIPA]
    2  PU_CLK_PFT_LOST_N      B  @S9S_MB_2U_LIB.S9S_MB_2U(SCH_1):PU_CLK_PFT_LOST_N
    1  P3V3_AUX           A  @S9S_MB_2U_LIB.S9S_MB_2U(SCH_1):P3V3_AUX

Q_RES  I115  R1959  [Q_RES_0402LF-0,5%,1/16W,CHIP,CA]
    1  H_CPU0_PMDOWN_PCH_R2      A  @S9S_MB_2U_LIB.S9S_MB_2U(SCH_1):H_CPU0_PMDOWN_PCH_R2
    2  H_CPU0_PMDOWN_PCH_R      B  @S9S_MB_2U_LIB.S9S_MB_2U(SCH_1):H_CPU0_PMDOWN_PCH_R

Q_RES  I117  R1960  [Q_RES_0402LF-0,5%,1/16W,CHIP,CA]
    1  H_CPU0_PMSYNC_PCH_R2      A  @S9S_MB_2U_LIB.S9S_MB_2U(SCH_1):H_CPU0_PMSYNC_PCH_R2
    2  H_CPU0_PMSYNC_PCH_R      B  @S9S_MB_2U_LIB.S9S_MB_2U(SCH_1):H_CPU0_PMSYNC_PCH_R

Q_RES  I70  R1961  [Q_RES_0402LF-10K,1%,1/16W,CHIPA]
    1  PGPPA_AUX          A  @S9S_MB_2U_LIB.S9S_MB_2U(SCH_1):PGPPA_AUX
    2  ESPI_LFRAME_N_BMC_CS0_N      B  @S9S_MB_2U_LIB.S9S_MB_2U(SCH_1):ESPI_LFRAME_N_BMC_CS0_N

Q_RES  I90  R1962  [Q_RES_0402LF-20K,5%,1/16W,CHIPA]
    2  GND                B  @S9S_MB_2U_LIB.S9S_MB_2U(SCH_1):GND
    1  FM_PCH_CONSENT_STRAP_N      A  @S9S_MB_2U_LIB.S9S_MB_2U(SCH_1):FM_PCH_CONSENT_STRAP_N

Q_RES  I83  R1963  [Q_RES_0402LF-10K,1%,1/16W,CHIPA]
    1  P3V3_AUX           A  @S9S_MB_2U_LIB.S9S_MB_2U(SCH_1):P3V3_AUX
    2  FM_EDSFF1A_TYPE_ID      B  @S9S_MB_2U_LIB.S9S_MB_2U(SCH_1):FM_EDSFF1A_TYPE_ID

Q_RES  I80  R1964  [Q_RES_0402LF-10K,5%,1/16W,EMPTA]
    1  P3V3_AUX           A  @S9S_MB_2U_LIB.S9S_MB_2U(SCH_1):P3V3_AUX
    2  FM_SYS_THROTTLE_R_N      B  @S9S_MB_2U_LIB.S9S_MB_2U(SCH_1):FM_SYS_THROTTLE_R_N

Q_RES  I61  R1965  [Q_RES_0402LF-0,5%,1/16W,CHIP,CA]
    1  FM_SYS_THROTTLE_R_N      A  @S9S_MB_2U_LIB.S9S_MB_2U(SCH_1):FM_SYS_THROTTLE_R_N
    2  FM_EDSFF1A_PWRBRK_N      B  @S9S_MB_2U_LIB.S9S_MB_2U(SCH_1):FM_EDSFF1A_PWRBRK_N

Q_RES  I62  R1966  [Q_RES_0402LF-33.2,1%,1/16W,CHIA]
    1  SMB_PEHPCPU0_LVC3_SDA      A  @S9S_MB_2U_LIB.S9S_MB_2U(SCH_1):SMB_PEHPCPU0_LVC3_SDA
    2  SMB_PEHPCPU0_EDSFF1ALVC3_R_SDA      B  @S9S_MB_2U_LIB.S9S_MB_2U(SCH_1):SMB_PEHPCPU0_EDSFF1ALVC3_R_SDA

Q_RES  I76  R1967  [Q_RES_0402LF-4.7K,5%,1/16W,CHIA]
    1  RST_SMB_EDSFF1A_N      A  @S9S_MB_2U_LIB.S9S_MB_2U(SCH_1):RST_SMB_EDSFF1A_N
    2  P3V3_AUX           B  @S9S_MB_2U_LIB.S9S_MB_2U(SCH_1):P3V3_AUX

Q_RES  I86  R1968  [Q_RES_0402LF-4.7K,5%,1/16W,CHIA]
    2  P3V3_AUX           B  @S9S_MB_2U_LIB.S9S_MB_2U(SCH_1):P3V3_AUX
    1  FM_PCIE_EDSFF1A_PRSNT_1_N      A  @S9S_MB_2U_LIB.S9S_MB_2U(SCH_1):FM_PCIE_EDSFF1A_PRSNT_1_N

Q_RES  I87  R1969  [Q_RES_0402LF-10K,1%,1/16W,EMPTA]
    2  GND                B  @S9S_MB_2U_LIB.S9S_MB_2U(SCH_1):GND
    1  EDSFF1A_PERST1_CLKREQ_N      A  @S9S_MB_2U_LIB.S9S_MB_2U(SCH_1):EDSFF1A_PERST1_CLKREQ_N

Q_RES  I88  R1970  [Q_RES_0402LF-10K,1%,1/16W,CHIPA]
    1  PD_EDSFF1A_PWRDIS      A  @S9S_MB_2U_LIB.S9S_MB_2U(SCH_1):PD_EDSFF1A_PWRDIS
    2  GND                B  @S9S_MB_2U_LIB.S9S_MB_2U(SCH_1):GND

Q_RES  I6   R1971  [Q_RES_0402LF-33.2,1%,1/16W,CHIA]
    2  SMB_PEHPCPU0_LVC3_SCL      B  @S9S_MB_2U_LIB.S9S_MB_2U(SCH_1):SMB_PEHPCPU0_LVC3_SCL
    1  SMB_PEHPCPU0_EDSFF1A_LVC3_R_SCL      A  @S9S_MB_2U_LIB.S9S_MB_2U(SCH_1):SMB_PEHPCPU0_EDSFF1A_LVC3_R_SCL

Q_RES  I2   R1972  [Q_RES_0402LF-100,1%,1/16W,CHIPA]
    1  PD_PCIE_EDSFF1A_PRSNT_0_N      A  @S9S_MB_2U_LIB.S9S_MB_2U(SCH_1):PD_PCIE_EDSFF1A_PRSNT_0_N
    2  GND                B  @S9S_MB_2U_LIB.S9S_MB_2U(SCH_1):GND

Q_RES  I85  R1973  [Q_RES_0402LF-10K,1%,1/16W,CHIPA]
    1  P3V3_AUX           A  @S9S_MB_2U_LIB.S9S_MB_2U(SCH_1):P3V3_AUX
    2  FM_EDSFF1B_TYPE_ID      B  @S9S_MB_2U_LIB.S9S_MB_2U(SCH_1):FM_EDSFF1B_TYPE_ID

Q_RES  I78  R1974  [Q_RES_0402LF-10K,5%,1/16W,EMPTA]
    1  P3V3_AUX           A  @S9S_MB_2U_LIB.S9S_MB_2U(SCH_1):P3V3_AUX
    2  FM_SYS_THROTTLE_R_N      B  @S9S_MB_2U_LIB.S9S_MB_2U(SCH_1):FM_SYS_THROTTLE_R_N

Q_RES  I74  R1975  [Q_RES_0402LF-0,5%,1/16W,CHIP,CA]
    1  FM_SYS_THROTTLE_R_N      A  @S9S_MB_2U_LIB.S9S_MB_2U(SCH_1):FM_SYS_THROTTLE_R_N
    2  FM_EDSFF1B_PWRBRK_N      B  @S9S_MB_2U_LIB.S9S_MB_2U(SCH_1):FM_EDSFF1B_PWRBRK_N

Q_RES  I75  R1976  [Q_RES_0402LF-33.2,1%,1/16W,CHIA]
    1  SMB_PEHPCPU0_LVC3_SDA      A  @S9S_MB_2U_LIB.S9S_MB_2U(SCH_1):SMB_PEHPCPU0_LVC3_SDA
    2  SMB_PEHPCPU0_EDSFF1B_LVC3_R_SDA      B  @S9S_MB_2U_LIB.S9S_MB_2U(SCH_1):SMB_PEHPCPU0_EDSFF1B_LVC3_R_SDA

Q_RES  I80  R1977  [Q_RES_0402LF-4.7K,5%,1/16W,CHIA]
    1  RST_SMB_EDSFF1B_N      A  @S9S_MB_2U_LIB.S9S_MB_2U(SCH_1):RST_SMB_EDSFF1B_N
    2  P3V3_AUX           B  @S9S_MB_2U_LIB.S9S_MB_2U(SCH_1):P3V3_AUX

Q_RES  I88  R1978  [Q_RES_0402LF-4.7K,5%,1/16W,CHIA]
    2  P3V3_AUX           B  @S9S_MB_2U_LIB.S9S_MB_2U(SCH_1):P3V3_AUX
    1  FM_PCIE_EDSFF1B_PRSNT_1_N      A  @S9S_MB_2U_LIB.S9S_MB_2U(SCH_1):FM_PCIE_EDSFF1B_PRSNT_1_N

Q_RES  I87  R1979  [Q_RES_0402LF-10K,1%,1/16W,CHIPA]
    1  PU_EDSFF1B_PERST1_CLKREQ_N      A  @S9S_MB_2U_LIB.S9S_MB_2U(SCH_1):PU_EDSFF1B_PERST1_CLKREQ_N
    2  P3V3_AUX           B  @S9S_MB_2U_LIB.S9S_MB_2U(SCH_1):P3V3_AUX

Q_RES  I89  R1980  [Q_RES_0402LF-10K,1%,1/16W,CHIPA]
    1  PD_EDSFF1B_PWRDIS      A  @S9S_MB_2U_LIB.S9S_MB_2U(SCH_1):PD_EDSFF1B_PWRDIS
    2  GND                B  @S9S_MB_2U_LIB.S9S_MB_2U(SCH_1):GND

Q_RES  I2   R1981  [Q_RES_0402LF-33.2,1%,1/16W,CHIA]
    2  SMB_PEHPCPU0_LVC3_SCL      B  @S9S_MB_2U_LIB.S9S_MB_2U(SCH_1):SMB_PEHPCPU0_LVC3_SCL
    1  SMB_PEHPCPU0_EDSFF1B_LVC3_R_SCL      A  @S9S_MB_2U_LIB.S9S_MB_2U(SCH_1):SMB_PEHPCPU0_EDSFF1B_LVC3_R_SCL

Q_RES  I3   R1982  [Q_RES_0402LF-100,1%,1/16W,CHIPA]
    1  PD_PCIE_EDSFF1B_PRSNT_0_N      A  @S9S_MB_2U_LIB.S9S_MB_2U(SCH_1):PD_PCIE_EDSFF1B_PRSNT_0_N
    2  GND                B  @S9S_MB_2U_LIB.S9S_MB_2U(SCH_1):GND

Q_RES  I5   R1983  [Q_RES_0402LF-10K,1%,1/16W,CHIPA]
    1  P3V3_AUX           A  @S9S_MB_2U_LIB.S9S_MB_2U(SCH_1):P3V3_AUX
    2  FM_EDSFF4A_TYPE_ID      B  @S9S_MB_2U_LIB.S9S_MB_2U(SCH_1):FM_EDSFF4A_TYPE_ID

Q_RES  I27  R1984  [Q_RES_0402LF-10K,5%,1/16W,EMPTA]
    1  P3V3_AUX           A  @S9S_MB_2U_LIB.S9S_MB_2U(SCH_1):P3V3_AUX
    2  FM_SYS_THROTTLE_R_N      B  @S9S_MB_2U_LIB.S9S_MB_2U(SCH_1):FM_SYS_THROTTLE_R_N

Q_RES  I31  R1985  [Q_RES_0402LF-0,5%,1/16W,CHIP,CA]
    1  FM_SYS_THROTTLE_R_N      A  @S9S_MB_2U_LIB.S9S_MB_2U(SCH_1):FM_SYS_THROTTLE_R_N
    2  FM_EDSFF4A_PWRBRK_N      B  @S9S_MB_2U_LIB.S9S_MB_2U(SCH_1):FM_EDSFF4A_PWRBRK_N

Q_RES  I30  R1986  [Q_RES_0402LF-33.2,1%,1/16W,CHIA]
    1  SMB_PEHPCPU1_LVC3_SDA      A  @S9S_MB_2U_LIB.S9S_MB_2U(SCH_1):SMB_PEHPCPU1_LVC3_SDA
    2  SMB_PEHPCPU1_EDSFF4A_LVC3_R_SDA      B  @S9S_MB_2U_LIB.S9S_MB_2U(SCH_1):SMB_PEHPCPU1_EDSFF4A_LVC3_R_SDA

Q_RES  I12  R1987  [Q_RES_0402LF-4.7K,5%,1/16W,CHIA]
    1  RST_SMB_EDSFF4A_N      A  @S9S_MB_2U_LIB.S9S_MB_2U(SCH_1):RST_SMB_EDSFF4A_N
    2  P3V3_AUX           B  @S9S_MB_2U_LIB.S9S_MB_2U(SCH_1):P3V3_AUX

Q_RES  I11  R1988  [Q_RES_0402LF-4.7K,5%,1/16W,CHIA]
    2  P3V3_AUX           B  @S9S_MB_2U_LIB.S9S_MB_2U(SCH_1):P3V3_AUX
    1  FM_PCIE_EDSFF4A_PRSNT_1_N      A  @S9S_MB_2U_LIB.S9S_MB_2U(SCH_1):FM_PCIE_EDSFF4A_PRSNT_1_N

Q_RES  I10  R1989  [Q_RES_0402LF-10K,1%,1/16W,CHIPA]
    2  P3V3_AUX           B  @S9S_MB_2U_LIB.S9S_MB_2U(SCH_1):P3V3_AUX
    1  EDSFF4A_PERST1_CLKREQ_N      A  @S9S_MB_2U_LIB.S9S_MB_2U(SCH_1):EDSFF4A_PERST1_CLKREQ_N

Q_RES  I9   R1990  [Q_RES_0402LF-10K,1%,1/16W,CHIPA]
    1  PD_EDSFF4A_PWRDIS      A  @S9S_MB_2U_LIB.S9S_MB_2U(SCH_1):PD_EDSFF4A_PWRDIS
    2  GND                B  @S9S_MB_2U_LIB.S9S_MB_2U(SCH_1):GND

Q_RES  I87  R1991  [Q_RES_0402LF-33.2,1%,1/16W,CHIA]
    2  SMB_PEHPCPU1_LVC3_SCL      B  @S9S_MB_2U_LIB.S9S_MB_2U(SCH_1):SMB_PEHPCPU1_LVC3_SCL
    1  SMB_PEHPCPU1_EDSFF4A_LVC3_R_SCL      A  @S9S_MB_2U_LIB.S9S_MB_2U(SCH_1):SMB_PEHPCPU1_EDSFF4A_LVC3_R_SCL

Q_RES  I85  R1992  [Q_RES_0402LF-100,1%,1/16W,CHIPA]
    1  PD_PCIE_EDSFF4A_PRSNT_0_N      A  @S9S_MB_2U_LIB.S9S_MB_2U(SCH_1):PD_PCIE_EDSFF4A_PRSNT_0_N
    2  GND                B  @S9S_MB_2U_LIB.S9S_MB_2U(SCH_1):GND

Q_RES  I3   R1993  [Q_RES_0402LF-10K,1%,1/16W,CHIPA]
    1  P3V3_AUX           A  @S9S_MB_2U_LIB.S9S_MB_2U(SCH_1):P3V3_AUX
    2  FM_EDSFF4B_TYPE_ID      B  @S9S_MB_2U_LIB.S9S_MB_2U(SCH_1):FM_EDSFF4B_TYPE_ID

Q_RES  I86  R1995  [Q_RES_0402LF-33,5%,1/16W,CHIP,A]
    2  FM_SLPS3_PLD_N      B  @S9S_MB_2U_LIB.S9S_MB_2U(SCH_1):FM_SLPS3_PLD_N
    1  FM_PCH_SLP_S3_N      A  @S9S_MB_2U_LIB.S9S_MB_2U(SCH_1):FM_PCH_SLP_S3_N

Q_RES  I87  R1996  [Q_RES_0402LF-33,5%,1/16W,CHIP,A]
    2  FM_SLPS4_PLD_N      B  @S9S_MB_2U_LIB.S9S_MB_2U(SCH_1):FM_SLPS4_PLD_N
    1  FM_PCH_SLP_S4_N      A  @S9S_MB_2U_LIB.S9S_MB_2U(SCH_1):FM_PCH_SLP_S4_N

Q_RES  I11  R2000  [Q_RES_0402LF-4.7K,5%,1/16W,CHIA]
    2  P3V3_AUX           B  @S9S_MB_2U_LIB.S9S_MB_2U(SCH_1):P3V3_AUX
    1  FM_PCIE_EDSFF4B_PRSNT_1_N      A  @S9S_MB_2U_LIB.S9S_MB_2U(SCH_1):FM_PCIE_EDSFF4B_PRSNT_1_N

Q_RES  I10  R2001  [Q_RES_0402LF-10K,1%,1/16W,CHIPA]
    2  P3V3_AUX           B  @S9S_MB_2U_LIB.S9S_MB_2U(SCH_1):P3V3_AUX
    1  EDSFF4B_PERST1_CLKREQ_N      A  @S9S_MB_2U_LIB.S9S_MB_2U(SCH_1):EDSFF4B_PERST1_CLKREQ_N

Q_RES  I8   R2002  [Q_RES_0402LF-10K,1%,1/16W,CHIPA]
    1  PD_EDSFF4B_PWRDIS      A  @S9S_MB_2U_LIB.S9S_MB_2U(SCH_1):PD_EDSFF4B_PWRDIS
    2  GND                B  @S9S_MB_2U_LIB.S9S_MB_2U(SCH_1):GND

Q_RES  I83  R2004  [Q_RES_0402LF-100,1%,1/16W,CHIPA]
    1  PD_PCIE_EDSFF4B_PRSNT_0_N      A  @S9S_MB_2U_LIB.S9S_MB_2U(SCH_1):PD_PCIE_EDSFF4B_PRSNT_0_N
    2  GND                B  @S9S_MB_2U_LIB.S9S_MB_2U(SCH_1):GND

Q_RES  I66  R2005  [Q_RES_0402LF-10K,1%,1/16W,EMPTA]
    2  RST_SMB_E1S_1_N      B  @S9S_MB_2U_LIB.S9S_MB_2U(SCH_1):RST_SMB_E1S_1_N
    1  P3V3_E1S_1         A  @S9S_MB_2U_LIB.S9S_MB_2U(SCH_1):P3V3_E1S_1

Q_RES  I30  R2006  [Q_RES_0402LF-10K,1%,1/16W,EMPTA]
    2  RST_SMB_E1S_2_N      B  @S9S_MB_2U_LIB.S9S_MB_2U(SCH_1):RST_SMB_E1S_2_N
    1  P3V3_E1S_2         A  @S9S_MB_2U_LIB.S9S_MB_2U(SCH_1):P3V3_E1S_2

Q_RES  I54  R2007  [Q_RES_0402LF-10K,1%,1/16W,EMPTA]
    2  RST_SMB_E1S_3_N      B  @S9S_MB_2U_LIB.S9S_MB_2U(SCH_1):RST_SMB_E1S_3_N
    1  P3V3_E1S_3         A  @S9S_MB_2U_LIB.S9S_MB_2U(SCH_1):P3V3_E1S_3

Q_RES  I36  R2014  [Q_RES_0402LF-100K,1%,1/16W,EMPA]
    1  P3V3_AUX           A  @S9S_MB_2U_LIB.S9S_MB_2U(SCH_1):P3V3_AUX
    2  FM_P3V3_E1S_0_EN      B  @S9S_MB_2U_LIB.S9S_MB_2U(SCH_1):FM_P3V3_E1S_0_EN

Q_RES  I2   R2015  [Q_RES_0402LF-100K,1%,1/16W,EMPA]
    1  P3V3_AUX           A  @S9S_MB_2U_LIB.S9S_MB_2U(SCH_1):P3V3_AUX
    2  FM_P3V3_E1S_2_EN      B  @S9S_MB_2U_LIB.S9S_MB_2U(SCH_1):FM_P3V3_E1S_2_EN

Q_RES  I14  R2016  [Q_RES_0402LF-1.33K,1%,1/16W,CHA]
    1  P3V3_E1S_2_ILM      A  @S9S_MB_2U_LIB.S9S_MB_2U(SCH_1):P3V3_E1S_2_ILM
    2  GND                B  @S9S_MB_2U_LIB.S9S_MB_2U(SCH_1):GND

Q_RES  I17  R2017  [Q_RES_0402LF-10K,1%,1/16W,CHIPA]
    2  P3V3_E1S_2_FLT_N      B  @S9S_MB_2U_LIB.S9S_MB_2U(SCH_1):P3V3_E1S_2_FLT_N
    1  P3V3_AUX           A  @S9S_MB_2U_LIB.S9S_MB_2U(SCH_1):P3V3_AUX

Q_RES  I55  R2018  [Q_RES_0402LF-100K,1%,1/16W,EMPA]
    1  P3V3_AUX           A  @S9S_MB_2U_LIB.S9S_MB_2U(SCH_1):P3V3_AUX
    2  FM_P3V3_E1S_1_EN      B  @S9S_MB_2U_LIB.S9S_MB_2U(SCH_1):FM_P3V3_E1S_1_EN

Q_RES  I21  R2019  [Q_RES_0402LF-100K,1%,1/16W,EMPA]
    1  P3V3_AUX           A  @S9S_MB_2U_LIB.S9S_MB_2U(SCH_1):P3V3_AUX
    2  FM_P3V3_E1S_3_EN      B  @S9S_MB_2U_LIB.S9S_MB_2U(SCH_1):FM_P3V3_E1S_3_EN

Q_RES  I65  R2020  [Q_RES_0402LF-1.33K,1%,1/16W,CHA]
    1  P3V3_E1S_1_ILM      A  @S9S_MB_2U_LIB.S9S_MB_2U(SCH_1):P3V3_E1S_1_ILM
    2  GND                B  @S9S_MB_2U_LIB.S9S_MB_2U(SCH_1):GND

Q_RES  I31  R2021  [Q_RES_0402LF-1.33K,1%,1/16W,CHA]
    1  P3V3_E1S_3_ILM      A  @S9S_MB_2U_LIB.S9S_MB_2U(SCH_1):P3V3_E1S_3_ILM
    2  GND                B  @S9S_MB_2U_LIB.S9S_MB_2U(SCH_1):GND

Q_RES  I67  R2022  [Q_RES_0402LF-10K,1%,1/16W,CHIPA]
    2  P3V3_E1S_1_FLT_N      B  @S9S_MB_2U_LIB.S9S_MB_2U(SCH_1):P3V3_E1S_1_FLT_N
    1  P3V3_AUX           A  @S9S_MB_2U_LIB.S9S_MB_2U(SCH_1):P3V3_AUX

Q_RES  I33  R2023  [Q_RES_0402LF-10K,1%,1/16W,CHIPA]
    2  P3V3_E1S_3_FLT_N      B  @S9S_MB_2U_LIB.S9S_MB_2U(SCH_1):P3V3_E1S_3_FLT_N
    1  P3V3_AUX           A  @S9S_MB_2U_LIB.S9S_MB_2U(SCH_1):P3V3_AUX

Q_RES  I95  R2036  [Q_RES_0402LF-100K,1%,1/16W,EMPA]
    1  P3V3_AUX           A  @S9S_MB_2U_LIB.S9S_MB_2U(SCH_1):P3V3_AUX
    2  FM_P12V_E1S_0_EN      B  @S9S_MB_2U_LIB.S9S_MB_2U(SCH_1):FM_P12V_E1S_0_EN

Q_RES  I130  R2037  [Q_RES_0402LF-100K,1%,1/16W,EMPA]
    1  P3V3_AUX           A  @S9S_MB_2U_LIB.S9S_MB_2U(SCH_1):P3V3_AUX
    2  FM_P12V_E1S_2_EN      B  @S9S_MB_2U_LIB.S9S_MB_2U(SCH_1):FM_P12V_E1S_2_EN

Q_RES  I165  R2038  [Q_RES_0402LF-576,1%,1/16W,CHIPA]
    1  P12V_E1S_0_ILM      A  @S9S_MB_2U_LIB.S9S_MB_2U(SCH_1):P12V_E1S_0_ILM
    2  GND                B  @S9S_MB_2U_LIB.S9S_MB_2U(SCH_1):GND

Q_RES  I169  R2039  [Q_RES_0402LF-576,1%,1/16W,CHIPA]
    1  P12V_E1S_2_ILM      A  @S9S_MB_2U_LIB.S9S_MB_2U(SCH_1):P12V_E1S_2_ILM
    2  GND                B  @S9S_MB_2U_LIB.S9S_MB_2U(SCH_1):GND

Q_RES  I166  R2040  [Q_RES_0402LF-10K,1%,1/16W,CHIPA]
    1  P3V3_AUX           A  @S9S_MB_2U_LIB.S9S_MB_2U(SCH_1):P3V3_AUX
    2  P12V_E1S_0_FLT_N      B  @S9S_MB_2U_LIB.S9S_MB_2U(SCH_1):P12V_E1S_0_FLT_N

Q_RES  I119  R2041  [Q_RES_0402LF-10K,1%,1/16W,CHIPA]
    1  P3V3_AUX           A  @S9S_MB_2U_LIB.S9S_MB_2U(SCH_1):P3V3_AUX
    2  P12V_E1S_2_FLT_N      B  @S9S_MB_2U_LIB.S9S_MB_2U(SCH_1):P12V_E1S_2_FLT_N

Q_RES  I107  R2042  [Q_RES_0402LF-100K,1%,1/16W,EMPA]
    1  P3V3_AUX           A  @S9S_MB_2U_LIB.S9S_MB_2U(SCH_1):P3V3_AUX
    2  FM_P12V_E1S_1_EN      B  @S9S_MB_2U_LIB.S9S_MB_2U(SCH_1):FM_P12V_E1S_1_EN

Q_RES  I147  R2043  [Q_RES_0402LF-100K,1%,1/16W,EMPA]
    1  P3V3_AUX           A  @S9S_MB_2U_LIB.S9S_MB_2U(SCH_1):P3V3_AUX
    2  FM_P12V_E1S_3_EN      B  @S9S_MB_2U_LIB.S9S_MB_2U(SCH_1):FM_P12V_E1S_3_EN

Q_RES  I167  R2044  [Q_RES_0402LF-576,1%,1/16W,CHIPA]
    1  P12V_E1S_1_ILM      A  @S9S_MB_2U_LIB.S9S_MB_2U(SCH_1):P12V_E1S_1_ILM
    2  GND                B  @S9S_MB_2U_LIB.S9S_MB_2U(SCH_1):GND

Q_RES  I168  R2045  [Q_RES_0402LF-576,1%,1/16W,CHIPA]
    1  P12V_E1S_3_ILM      A  @S9S_MB_2U_LIB.S9S_MB_2U(SCH_1):P12V_E1S_3_ILM
    2  GND                B  @S9S_MB_2U_LIB.S9S_MB_2U(SCH_1):GND

Q_RES  I116  R2046  [Q_RES_0402LF-10K,1%,1/16W,CHIPA]
    1  P3V3_AUX           A  @S9S_MB_2U_LIB.S9S_MB_2U(SCH_1):P3V3_AUX
    2  P12V_E1S_1_FLT_N      B  @S9S_MB_2U_LIB.S9S_MB_2U(SCH_1):P12V_E1S_1_FLT_N

Q_RES  I136  R2047  [Q_RES_0402LF-10K,1%,1/16W,CHIPA]
    1  P3V3_AUX           A  @S9S_MB_2U_LIB.S9S_MB_2U(SCH_1):P3V3_AUX
    2  P12V_E1S_3_FLT_N      B  @S9S_MB_2U_LIB.S9S_MB_2U(SCH_1):P12V_E1S_3_FLT_N

Q_RES  I217  R2048  [Q_RES_0402LF-0,5%,1/16W,CHIP,CA]
    1  CLK_100M_EDSFF4B_R_DP      A  @S9S_MB_2U_LIB.S9S_MB_2U(SCH_1):CLK_100M_EDSFF4B_R_DP
    2  CLK_100M_EDSFF4B_DP      B  @S9S_MB_2U_LIB.S9S_MB_2U(SCH_1):CLK_100M_EDSFF4B_DP

Q_RES  I218  R2049  [Q_RES_0402LF-0,5%,1/16W,CHIP,CA]
    1  CLK_100M_EDSFF4B_R_DN      A  @S9S_MB_2U_LIB.S9S_MB_2U(SCH_1):CLK_100M_EDSFF4B_R_DN
    2  CLK_100M_EDSFF4B_DN      B  @S9S_MB_2U_LIB.S9S_MB_2U(SCH_1):CLK_100M_EDSFF4B_DN

Q_RES  I109  R2050  [Q_RES_0402LF-33.2,1%,1/16W,CHIA]
    2  RST_PCIE_EDSFF2B_PERST_N      B  @S9S_MB_2U_LIB.S9S_MB_2U(SCH_1):RST_PCIE_EDSFF2B_PERST_N
    1  RST_PCIE_CPU0_DEV_PERST_N      A  @S9S_MB_2U_LIB.S9S_MB_2U(SCH_1):RST_PCIE_CPU0_DEV_PERST_N

Q_RES  I124  R2051  [Q_RES_0402LF-2.2K ,5%,1/16W,CHA]
    2  SMB_EDSFF1B_3V3AUX_SCL_R      B  @S9S_MB_2U_LIB.S9S_MB_2U(SCH_1):SMB_EDSFF1B_3V3AUX_SCL_R
    1  P3V3_AUX           A  @S9S_MB_2U_LIB.S9S_MB_2U(SCH_1):P3V3_AUX

Q_RES  I125  R2052  [Q_RES_0402LF-2.2K ,5%,1/16W,CHA]
    2  SMB_EDSFF1B_3V3AUX_SDA_R      B  @S9S_MB_2U_LIB.S9S_MB_2U(SCH_1):SMB_EDSFF1B_3V3AUX_SDA_R
    1  P3V3_AUX           A  @S9S_MB_2U_LIB.S9S_MB_2U(SCH_1):P3V3_AUX

Q_RES  I140  R2053  [Q_RES_0402LF-2.2K ,5%,1/16W,CHA]
    2  SMB_EDSFF2B_3V3AUX_SCL_R      B  @S9S_MB_2U_LIB.S9S_MB_2U(SCH_1):SMB_EDSFF2B_3V3AUX_SCL_R
    1  P3V3_AUX           A  @S9S_MB_2U_LIB.S9S_MB_2U(SCH_1):P3V3_AUX

Q_RES  I141  R2054  [Q_RES_0402LF-2.2K ,5%,1/16W,CHA]
    2  SMB_EDSFF2B_3V3AUX_SDA_R      B  @S9S_MB_2U_LIB.S9S_MB_2U(SCH_1):SMB_EDSFF2B_3V3AUX_SDA_R
    1  P3V3_AUX           A  @S9S_MB_2U_LIB.S9S_MB_2U(SCH_1):P3V3_AUX

Q_RES  I143  R2055  [Q_RES_0402LF-2.2K ,5%,1/16W,CHA]
    2  SMB_EDSFF4B_3V3AUX_SCL_R      B  @S9S_MB_2U_LIB.S9S_MB_2U(SCH_1):SMB_EDSFF4B_3V3AUX_SCL_R
    1  P3V3_AUX           A  @S9S_MB_2U_LIB.S9S_MB_2U(SCH_1):P3V3_AUX

Q_RES  I142  R2056  [Q_RES_0402LF-2.2K ,5%,1/16W,CHA]
    2  SMB_EDSFF4B_3V3AUX_SDA_R      B  @S9S_MB_2U_LIB.S9S_MB_2U(SCH_1):SMB_EDSFF4B_3V3AUX_SDA_R
    1  P3V3_AUX           A  @S9S_MB_2U_LIB.S9S_MB_2U(SCH_1):P3V3_AUX

Q_RES  I147  R2057  [Q_RES_0402LF-2.2K ,5%,1/16W,CHA]
    2  PU_SMB_EDSFF_3V3AUX_SCL7      B  @S9S_MB_2U_LIB.S9S_MB_2U(SCH_1):PU_SMB_EDSFF_3V3AUX_SCL7
    1  P3V3_AUX           A  @S9S_MB_2U_LIB.S9S_MB_2U(SCH_1):P3V3_AUX

Q_RES  I146  R2058  [Q_RES_0402LF-2.2K ,5%,1/16W,CHA]
    2  PU_SMB_EDSFF_3V3AUX_SDA7      B  @S9S_MB_2U_LIB.S9S_MB_2U(SCH_1):PU_SMB_EDSFF_3V3AUX_SDA7
    1  P3V3_AUX           A  @S9S_MB_2U_LIB.S9S_MB_2U(SCH_1):P3V3_AUX

Q_RES  I89  R2059  [Q_RES_0402LF-0,5%,1/16W,CHIP,CA]
    1  SMB_EDSFF1B_3V3AUX_SCL_R1      A  @S9S_MB_2U_LIB.S9S_MB_2U(SCH_1):SMB_EDSFF1B_3V3AUX_SCL_R1
    2  SMB_EDSFF1B_3V3AUX_SCL_R      B  @S9S_MB_2U_LIB.S9S_MB_2U(SCH_1):SMB_EDSFF1B_3V3AUX_SCL_R

Q_RES  I88  R2060  [Q_RES_0402LF-0,5%,1/16W,CHIP,CA]
    1  SMB_EDSFF1B_3V3AUX_SDA_R1      A  @S9S_MB_2U_LIB.S9S_MB_2U(SCH_1):SMB_EDSFF1B_3V3AUX_SDA_R1
    2  SMB_EDSFF1B_3V3AUX_SDA_R      B  @S9S_MB_2U_LIB.S9S_MB_2U(SCH_1):SMB_EDSFF1B_3V3AUX_SDA_R

Q_RES  I91  R2061  [Q_RES_0402LF-0,5%,1/16W,CHIP,CA]
    1  SMB_EDSFF2B_3V3AUX_SCL_R1      A  @S9S_MB_2U_LIB.S9S_MB_2U(SCH_1):SMB_EDSFF2B_3V3AUX_SCL_R1
    2  SMB_EDSFF2B_3V3AUX_SCL_R      B  @S9S_MB_2U_LIB.S9S_MB_2U(SCH_1):SMB_EDSFF2B_3V3AUX_SCL_R

Q_RES  I90  R2062  [Q_RES_0402LF-0,5%,1/16W,CHIP,CA]
    1  SMB_EDSFF2B_3V3AUX_SDA_R1      A  @S9S_MB_2U_LIB.S9S_MB_2U(SCH_1):SMB_EDSFF2B_3V3AUX_SDA_R1
    2  SMB_EDSFF2B_3V3AUX_SDA_R      B  @S9S_MB_2U_LIB.S9S_MB_2U(SCH_1):SMB_EDSFF2B_3V3AUX_SDA_R

Q_RES  I96  R2063  [Q_RES_0402LF-0,5%,1/16W,CHIP,CA]
    1  SMB_EDSFF4B_3V3AUX_SCL_R1      A  @S9S_MB_2U_LIB.S9S_MB_2U(SCH_1):SMB_EDSFF4B_3V3AUX_SCL_R1
    2  SMB_EDSFF4B_3V3AUX_SCL_R      B  @S9S_MB_2U_LIB.S9S_MB_2U(SCH_1):SMB_EDSFF4B_3V3AUX_SCL_R

Q_RES  I95  R2064  [Q_RES_0402LF-0,5%,1/16W,CHIP,CA]
    1  SMB_EDSFF4B_3V3AUX_SDA_R1      A  @S9S_MB_2U_LIB.S9S_MB_2U(SCH_1):SMB_EDSFF4B_3V3AUX_SDA_R1
    2  SMB_EDSFF4B_3V3AUX_SDA_R      B  @S9S_MB_2U_LIB.S9S_MB_2U(SCH_1):SMB_EDSFF4B_3V3AUX_SDA_R

Q_RES  I109  R2065  [Q_RES_0402LF-0,5%,1/16W,CHIP,CA]
    1  SMB_EDSFF_3V3AUX_SCL_R8      A  @S9S_MB_2U_LIB.S9S_MB_2U(SCH_1):SMB_EDSFF_3V3AUX_SCL_R8
    2  PU_SMB_EDSFF_3V3AUX_SCL7      B  @S9S_MB_2U_LIB.S9S_MB_2U(SCH_1):PU_SMB_EDSFF_3V3AUX_SCL7

Q_RES  I108  R2066  [Q_RES_0402LF-0,5%,1/16W,CHIP,CA]
    1  SMB_EDSFF_3V3AUX_SDA_R8      A  @S9S_MB_2U_LIB.S9S_MB_2U(SCH_1):SMB_EDSFF_3V3AUX_SDA_R8
    2  PU_SMB_EDSFF_3V3AUX_SDA7      B  @S9S_MB_2U_LIB.S9S_MB_2U(SCH_1):PU_SMB_EDSFF_3V3AUX_SDA7

Q_RES  I437  R2070  [Q_RES_0402LF-0,5%,1/16W,CHIP,CA]
    2  VOL_SEN_ALERT_R      B  @S9S_MB_2U_LIB.S9S_MB_2U(SCH_1):VOL_SEN_ALERT_R
    1  VOL_SEN_ALERT      A  @S9S_MB_2U_LIB.S9S_MB_2U(SCH_1):VOL_SEN_ALERT

Q_RES  I327  R2071  [Q_RES_0402LF-0,5%,1/16W,EMPTY,A]
    2  FM_SUSACK_N        B  @S9S_MB_2U_LIB.S9S_MB_2U(SCH_1):FM_SUSACK_N
    1  FM_BMC_SUSACK_R_N      A  @S9S_MB_2U_LIB.S9S_MB_2U(SCH_1):FM_BMC_SUSACK_R_N

Q_RES  I130  R2072  [Q_RES_0402LF-100K,1%,1/16W,CHIA]
    1  VDD3               A  @S9S_MB_2U_LIB.S9S_MB_2U(SCH_1):VDD3
    2  PU_MP5981_0_D_OC      B  @S9S_MB_2U_LIB.S9S_MB_2U(SCH_1):PU_MP5981_0_D_OC

Q_RES  I137  R2073  [Q_RES_0402LF-100K,1%,1/16W,CHIA]
    1  VDD3               A  @S9S_MB_2U_LIB.S9S_MB_2U(SCH_1):VDD3
    2  PU_MP5981_0_GOK      B  @S9S_MB_2U_LIB.S9S_MB_2U(SCH_1):PU_MP5981_0_GOK

Q_RES  I139  R2074  [Q_RES_0402LF-0,5%,1/16W,CHIP,CA]
    1  PD_MP5981_0_MODE      A  @S9S_MB_2U_LIB.S9S_MB_2U(SCH_1):PD_MP5981_0_MODE
    2  GND                B  @S9S_MB_2U_LIB.S9S_MB_2U(SCH_1):GND

Q_RES  I118  R2075  [Q_RES_0402LF-120K,1%,1/16W,CHIA]
    1  MP5981_0_CLREF      A  @S9S_MB_2U_LIB.S9S_MB_2U(SCH_1):MP5981_0_CLREF
    2  GND                B  @S9S_MB_2U_LIB.S9S_MB_2U(SCH_1):GND

Q_RES  I122  R2076  [Q_RES_0402LF-2.4K,1%,1/16W,CHIA]
    1  MP5981_0_CS        A  @S9S_MB_2U_LIB.S9S_MB_2U(SCH_1):MP5981_0_CS
    2  GND                B  @S9S_MB_2U_LIB.S9S_MB_2U(SCH_1):GND

Q_RES  I94  R2077  [Q_RES_0402LF-33.2,1%,1/16W,CHIA]
    2  IRQ_LVC3_WAKE_N      B  @S9S_MB_2U_LIB.S9S_MB_2U(SCH_1):IRQ_LVC3_WAKE_N
    1  IRQ_LVC3_WAKE_EDSFF4_N      A  @S9S_MB_2U_LIB.S9S_MB_2U(SCH_1):IRQ_LVC3_WAKE_EDSFF4_N

Q_RES  I427  R2078  [Q_RES_0402LF-33.2,1%,1/16W,CHIA]
    2  IRQ_LVC3_WAKE_N      B  @S9S_MB_2U_LIB.S9S_MB_2U(SCH_1):IRQ_LVC3_WAKE_N
    1  IRQ_LVC3_WAKE_EDSFF3_N      A  @S9S_MB_2U_LIB.S9S_MB_2U(SCH_1):IRQ_LVC3_WAKE_EDSFF3_N

Q_RES  I117  R2079  [Q_RES_0402LF-4.7K,5%,1/16W,EMPA]
    2  P3V3_AUX           B  @S9S_MB_2U_LIB.S9S_MB_2U(SCH_1):P3V3_AUX
    1  JTAG_EDSFF4_TDI      A  @S9S_MB_2U_LIB.S9S_MB_2U(SCH_1):JTAG_EDSFF4_TDI

Q_RES  I113  R2080  [Q_RES_0402LF-4.7K,5%,1/16W,EMPA]
    2  P3V3_AUX           B  @S9S_MB_2U_LIB.S9S_MB_2U(SCH_1):P3V3_AUX
    1  JTAG_EDSFF4_TDO      A  @S9S_MB_2U_LIB.S9S_MB_2U(SCH_1):JTAG_EDSFF4_TDO

Q_RES  I112  R2081  [Q_RES_0402LF-4.7K,5%,1/16W,EMPA]
    2  P3V3_AUX           B  @S9S_MB_2U_LIB.S9S_MB_2U(SCH_1):P3V3_AUX
    1  JTAG_EDSFF4_TMS      A  @S9S_MB_2U_LIB.S9S_MB_2U(SCH_1):JTAG_EDSFF4_TMS

Q_RES  I114  R2082  [Q_RES_0402LF-4.7K,5%,1/16W,EMPA]
    1  JTAG_EDSFF4_TCK      A  @S9S_MB_2U_LIB.S9S_MB_2U(SCH_1):JTAG_EDSFF4_TCK
    2  GND                B  @S9S_MB_2U_LIB.S9S_MB_2U(SCH_1):GND

Q_RES  I111  R2083  [Q_RES_0402LF-4.7K,5%,1/16W,EMPA]
    1  JTAG_EDSFF4_TRST_N      A  @S9S_MB_2U_LIB.S9S_MB_2U(SCH_1):JTAG_EDSFF4_TRST_N
    2  GND                B  @S9S_MB_2U_LIB.S9S_MB_2U(SCH_1):GND

Q_RES  I102  R2084  [Q_RES_0402LF-100K,1%,1/16W,CHIA]
    1  VDD3               A  @S9S_MB_2U_LIB.S9S_MB_2U(SCH_1):VDD3
    2  PU_MP5981_1_GOK      B  @S9S_MB_2U_LIB.S9S_MB_2U(SCH_1):PU_MP5981_1_GOK

Q_RES  I103  R2085  [Q_RES_0402LF-100K,1%,1/16W,CHIA]
    1  VDD3               A  @S9S_MB_2U_LIB.S9S_MB_2U(SCH_1):VDD3
    2  PU_MP5981_1_D_OC      B  @S9S_MB_2U_LIB.S9S_MB_2U(SCH_1):PU_MP5981_1_D_OC

Q_RES  I104  R2086  [Q_RES_0402LF-0,5%,1/16W,CHIP,CA]
    1  PD_MP5981_1_MODE      A  @S9S_MB_2U_LIB.S9S_MB_2U(SCH_1):PD_MP5981_1_MODE
    2  GND                B  @S9S_MB_2U_LIB.S9S_MB_2U(SCH_1):GND

Q_RES  I106  R2087  [Q_RES_0402LF-120K,1%,1/16W,CHIA]
    1  MP5981_1_CLREF      A  @S9S_MB_2U_LIB.S9S_MB_2U(SCH_1):MP5981_1_CLREF
    2  GND                B  @S9S_MB_2U_LIB.S9S_MB_2U(SCH_1):GND

Q_RES  I107  R2088  [Q_RES_0402LF-2.4K,1%,1/16W,CHIA]
    1  MP5981_1_CS        A  @S9S_MB_2U_LIB.S9S_MB_2U(SCH_1):MP5981_1_CS
    2  GND                B  @S9S_MB_2U_LIB.S9S_MB_2U(SCH_1):GND

Q_RES  I48  R2089  [Q_RES_0402LF-1K,5%,1/16W,EMPTYA]
    2  PCA9555_1_ADD2      B  @S9S_MB_2U_LIB.S9S_MB_2U(SCH_1):PCA9555_1_ADD2
    1  P3V3_AUX           A  @S9S_MB_2U_LIB.S9S_MB_2U(SCH_1):P3V3_AUX

Q_RES  I45  R2090  [Q_RES_0402LF-1K,5%,1/16W,CHIP,A]
    1  PCA9555_1_ADD2      A  @S9S_MB_2U_LIB.S9S_MB_2U(SCH_1):PCA9555_1_ADD2
    2  GND                B  @S9S_MB_2U_LIB.S9S_MB_2U(SCH_1):GND

Q_RES  I71  R2091  [Q_RES_0402LF-1K,5%,1/16W,EMPTYA]
    2  PCA9555_2_ADD2      B  @S9S_MB_2U_LIB.S9S_MB_2U(SCH_1):PCA9555_2_ADD2
    1  P3V3_AUX           A  @S9S_MB_2U_LIB.S9S_MB_2U(SCH_1):P3V3_AUX

Q_RES  I74  R2092  [Q_RES_0402LF-1K,5%,1/16W,CHIP,A]
    1  PCA9555_2_ADD2      A  @S9S_MB_2U_LIB.S9S_MB_2U(SCH_1):PCA9555_2_ADD2
    2  GND                B  @S9S_MB_2U_LIB.S9S_MB_2U(SCH_1):GND

Q_RES  I49  R2093  [Q_RES_0402LF-1K,5%,1/16W,EMPTYA]
    2  PCA9555_1_ADD1      B  @S9S_MB_2U_LIB.S9S_MB_2U(SCH_1):PCA9555_1_ADD1
    1  P3V3_AUX           A  @S9S_MB_2U_LIB.S9S_MB_2U(SCH_1):P3V3_AUX

Q_RES  I46  R2094  [Q_RES_0402LF-1K,5%,1/16W,CHIP,A]
    1  PCA9555_1_ADD1      A  @S9S_MB_2U_LIB.S9S_MB_2U(SCH_1):PCA9555_1_ADD1
    2  GND                B  @S9S_MB_2U_LIB.S9S_MB_2U(SCH_1):GND

Q_RES  I70  R2095  [Q_RES_0402LF-1K,5%,1/16W,EMPTYA]
    2  PCA9555_2_ADD1      B  @S9S_MB_2U_LIB.S9S_MB_2U(SCH_1):PCA9555_2_ADD1
    1  P3V3_AUX           A  @S9S_MB_2U_LIB.S9S_MB_2U(SCH_1):P3V3_AUX

Q_RES  I72  R2096  [Q_RES_0402LF-1K,5%,1/16W,CHIP,A]
    1  PCA9555_2_ADD1      A  @S9S_MB_2U_LIB.S9S_MB_2U(SCH_1):PCA9555_2_ADD1
    2  GND                B  @S9S_MB_2U_LIB.S9S_MB_2U(SCH_1):GND

Q_RES  I50  R2097  [Q_RES_0402LF-1K,5%,1/16W,EMPTYA]
    2  PCA9555_1_ADD0      B  @S9S_MB_2U_LIB.S9S_MB_2U(SCH_1):PCA9555_1_ADD0
    1  P3V3_AUX           A  @S9S_MB_2U_LIB.S9S_MB_2U(SCH_1):P3V3_AUX

Q_RES  I47  R2098  [Q_RES_0402LF-1K,5%,1/16W,CHIP,A]
    1  PCA9555_1_ADD0      A  @S9S_MB_2U_LIB.S9S_MB_2U(SCH_1):PCA9555_1_ADD0
    2  GND                B  @S9S_MB_2U_LIB.S9S_MB_2U(SCH_1):GND

Q_RES  I66  R2099  [Q_RES_0402LF-1K,5%,1/16W,EMPTYA]
    2  PCA9555_2_ADD0      B  @S9S_MB_2U_LIB.S9S_MB_2U(SCH_1):PCA9555_2_ADD0
    1  P3V3_AUX           A  @S9S_MB_2U_LIB.S9S_MB_2U(SCH_1):P3V3_AUX

Q_RES  I67  R2100  [Q_RES_0402LF-1K,5%,1/16W,CHIP,A]
    1  PCA9555_2_ADD0      A  @S9S_MB_2U_LIB.S9S_MB_2U(SCH_1):PCA9555_2_ADD0
    2  GND                B  @S9S_MB_2U_LIB.S9S_MB_2U(SCH_1):GND

Q_RES  I37  R2101  [Q_RES_0402LF-33,5%,1/16W,CHIP,A]
    1  SMB_PEHPCPU0_LVC3_SCL      A  @S9S_MB_2U_LIB.S9S_MB_2U(SCH_1):SMB_PEHPCPU0_LVC3_SCL
    2  SMB_PEHPCPU0_LVC3_R1_SCL      B  @S9S_MB_2U_LIB.S9S_MB_2U(SCH_1):SMB_PEHPCPU0_LVC3_R1_SCL

Q_RES  I38  R2102  [Q_RES_0402LF-33,5%,1/16W,CHIP,A]
    1  SMB_PEHPCPU0_LVC3_SDA      A  @S9S_MB_2U_LIB.S9S_MB_2U(SCH_1):SMB_PEHPCPU0_LVC3_SDA
    2  SMB_PEHPCPU0_LVC3_R1_SDA      B  @S9S_MB_2U_LIB.S9S_MB_2U(SCH_1):SMB_PEHPCPU0_LVC3_R1_SDA

Q_RES  I79  R2103  [Q_RES_0402LF-33,5%,1/16W,CHIP,A]
    1  SMB_PEHPCPU0_LVC3_SCL      A  @S9S_MB_2U_LIB.S9S_MB_2U(SCH_1):SMB_PEHPCPU0_LVC3_SCL
    2  SMB_PEHPCPU0_LVC3_R2_SCL      B  @S9S_MB_2U_LIB.S9S_MB_2U(SCH_1):SMB_PEHPCPU0_LVC3_R2_SCL

Q_RES  I76  R2104  [Q_RES_0402LF-33,5%,1/16W,CHIP,A]
    1  SMB_PEHPCPU0_LVC3_SDA      A  @S9S_MB_2U_LIB.S9S_MB_2U(SCH_1):SMB_PEHPCPU0_LVC3_SDA
    2  SMB_PEHPCPU0_LVC3_R2_SDA      B  @S9S_MB_2U_LIB.S9S_MB_2U(SCH_1):SMB_PEHPCPU0_LVC3_R2_SDA

Q_RES  I34  R2105  [Q_RES_0402LF-0,5%,1/16W,CHIP,CA]
    1  E1S_1_BUF_EN       A  @S9S_MB_2U_LIB.S9S_MB_2U(SCH_1):E1S_1_BUF_EN
    2  E1S_0_EN           B  @S9S_MB_2U_LIB.S9S_MB_2U(SCH_1):E1S_0_EN

Q_RES  I35  R2106  [Q_RES_0402LF-0,5%,1/16W,CHIP,CA]
    2  E1S_0_BUF_PRSNT_R_N      B  @S9S_MB_2U_LIB.S9S_MB_2U(SCH_1):E1S_0_BUF_PRSNT_R_N
    1  E1S_0_BUF_PRSNT_N      A  @S9S_MB_2U_LIB.S9S_MB_2U(SCH_1):E1S_0_BUF_PRSNT_N

Q_RES  I44  R2107  [Q_RES_0402LF-0,5%,1/16W,CHIP,CA]
    2  E1S_1_EN           B  @S9S_MB_2U_LIB.S9S_MB_2U(SCH_1):E1S_1_EN
    1  E1S_1_BUF_EN       A  @S9S_MB_2U_LIB.S9S_MB_2U(SCH_1):E1S_1_BUF_EN

Q_RES  I41  R2108  [Q_RES_0402LF-0,5%,1/16W,CHIP,CA]
    2  E1S_1_BUF_PRSNT_R_N      B  @S9S_MB_2U_LIB.S9S_MB_2U(SCH_1):E1S_1_BUF_PRSNT_R_N
    1  E1S_1_BUF_PRSNT_N      A  @S9S_MB_2U_LIB.S9S_MB_2U(SCH_1):E1S_1_BUF_PRSNT_N

Q_RES  I56  R2109  [Q_RES_0402LF-0,5%,1/16W,CHIP,CA]
    2  E1S_2_EN           B  @S9S_MB_2U_LIB.S9S_MB_2U(SCH_1):E1S_2_EN
    1  E1S_2_BUF_EN       A  @S9S_MB_2U_LIB.S9S_MB_2U(SCH_1):E1S_2_BUF_EN

Q_RES  I57  R2110  [Q_RES_0402LF-0,5%,1/16W,CHIP,CA]
    2  E1S_2_BUF_PRSNT_R_N      B  @S9S_MB_2U_LIB.S9S_MB_2U(SCH_1):E1S_2_BUF_PRSNT_R_N
    1  E1S_2_BUF_PRSNT_N      A  @S9S_MB_2U_LIB.S9S_MB_2U(SCH_1):E1S_2_BUF_PRSNT_N

Q_RES  I59  R2111  [Q_RES_0402LF-0,5%,1/16W,CHIP,CA]
    2  E1S_3_EN           B  @S9S_MB_2U_LIB.S9S_MB_2U(SCH_1):E1S_3_EN
    1  E1S_3_BUF_EN       A  @S9S_MB_2U_LIB.S9S_MB_2U(SCH_1):E1S_3_BUF_EN

Q_RES  I58  R2112  [Q_RES_0402LF-0,5%,1/16W,CHIP,CA]
    2  E1S_3_BUF_PRSNT_R_N      B  @S9S_MB_2U_LIB.S9S_MB_2U(SCH_1):E1S_3_BUF_PRSNT_R_N
    1  E1S_3_BUF_PRSNT_N      A  @S9S_MB_2U_LIB.S9S_MB_2U(SCH_1):E1S_3_BUF_PRSNT_N

Q_RES  I7   R2113  [Q_RES_0402LF-0,5%,1/16W,CHIP,CA]
    2  RST_PCIE_E1S_0_PERST_N      B  @S9S_MB_2U_LIB.S9S_MB_2U(SCH_1):RST_PCIE_E1S_0_PERST_N
    1  RST_PCIE_BUF_E1S_0_PERST_N      A  @S9S_MB_2U_LIB.S9S_MB_2U(SCH_1):RST_PCIE_BUF_E1S_0_PERST_N

Q_RES  I9   R2114  [Q_RES_0402LF-0,5%,1/16W,CHIP,CA]
    2  RST_PCIE_E1S_1_PERST_N      B  @S9S_MB_2U_LIB.S9S_MB_2U(SCH_1):RST_PCIE_E1S_1_PERST_N
    1  RST_PCIE_BUF_E1S_1_PERST_N      A  @S9S_MB_2U_LIB.S9S_MB_2U(SCH_1):RST_PCIE_BUF_E1S_1_PERST_N

Q_RES  I19  R2115  [Q_RES_0402LF-0,5%,1/16W,CHIP,CA]
    2  RST_PCIE_E1S_2_PERST_N      B  @S9S_MB_2U_LIB.S9S_MB_2U(SCH_1):RST_PCIE_E1S_2_PERST_N
    1  RST_PCIE_BUF_E1S_2_PERST_N      A  @S9S_MB_2U_LIB.S9S_MB_2U(SCH_1):RST_PCIE_BUF_E1S_2_PERST_N

Q_RES  I20  R2116  [Q_RES_0402LF-0,5%,1/16W,CHIP,CA]
    2  RST_PCIE_E1S_3_PERST_N      B  @S9S_MB_2U_LIB.S9S_MB_2U(SCH_1):RST_PCIE_E1S_3_PERST_N
    1  RST_PCIE_BUF_E1S_3_PERST_N      A  @S9S_MB_2U_LIB.S9S_MB_2U(SCH_1):RST_PCIE_BUF_E1S_3_PERST_N

Q_RES  I36  R2117  [Q_RES_0402LF-0,5%,1/16W,CHIP,CA]
    2  RST_SMB_E1S_0_N      B  @S9S_MB_2U_LIB.S9S_MB_2U(SCH_1):RST_SMB_E1S_0_N
    1  RST_SMB_BUF_E1S_0_N      A  @S9S_MB_2U_LIB.S9S_MB_2U(SCH_1):RST_SMB_BUF_E1S_0_N

Q_RES  I37  R2118  [Q_RES_0402LF-0,5%,1/16W,CHIP,CA]
    2  RST_SMB_E1S_1_N      B  @S9S_MB_2U_LIB.S9S_MB_2U(SCH_1):RST_SMB_E1S_1_N
    1  RST_SMB_BUF_E1S_1_N      A  @S9S_MB_2U_LIB.S9S_MB_2U(SCH_1):RST_SMB_BUF_E1S_1_N

Q_RES  I42  R2119  [Q_RES_0402LF-0,5%,1/16W,CHIP,CA]
    2  RST_SMB_E1S_2_N      B  @S9S_MB_2U_LIB.S9S_MB_2U(SCH_1):RST_SMB_E1S_2_N
    1  RST_SMB_BUF_E1S_2_N      A  @S9S_MB_2U_LIB.S9S_MB_2U(SCH_1):RST_SMB_BUF_E1S_2_N

Q_RES  I43  R2120  [Q_RES_0402LF-0,5%,1/16W,CHIP,CA]
    2  RST_SMB_E1S_3_N      B  @S9S_MB_2U_LIB.S9S_MB_2U(SCH_1):RST_SMB_E1S_3_N
    1  RST_SMB_BUF_E1S_3_N      A  @S9S_MB_2U_LIB.S9S_MB_2U(SCH_1):RST_SMB_BUF_E1S_3_N

Q_RES  I11  R2121  [Q_RES_0402LF-4.7K,5%,1/16W,CHIA]
    2  RST_PCIE_E1S_0_PERST_N      B  @S9S_MB_2U_LIB.S9S_MB_2U(SCH_1):RST_PCIE_E1S_0_PERST_N
    1  P3V3_AUX           A  @S9S_MB_2U_LIB.S9S_MB_2U(SCH_1):P3V3_AUX

Q_RES  I18  R2122  [Q_RES_0402LF-4.7K,5%,1/16W,CHIA]
    2  RST_PCIE_E1S_2_PERST_N      B  @S9S_MB_2U_LIB.S9S_MB_2U(SCH_1):RST_PCIE_E1S_2_PERST_N
    1  P3V3_AUX           A  @S9S_MB_2U_LIB.S9S_MB_2U(SCH_1):P3V3_AUX

Q_RES  I30  R2123  [Q_RES_0402LF-4.7K,5%,1/16W,CHIA]
    2  RST_SMB_E1S_0_N      B  @S9S_MB_2U_LIB.S9S_MB_2U(SCH_1):RST_SMB_E1S_0_N
    1  P3V3_AUX           A  @S9S_MB_2U_LIB.S9S_MB_2U(SCH_1):P3V3_AUX

Q_RES  I35  R2124  [Q_RES_0402LF-4.7K,5%,1/16W,CHIA]
    2  RST_SMB_E1S_2_N      B  @S9S_MB_2U_LIB.S9S_MB_2U(SCH_1):RST_SMB_E1S_2_N
    1  P3V3_AUX           A  @S9S_MB_2U_LIB.S9S_MB_2U(SCH_1):P3V3_AUX

Q_RES  I12  R2125  [Q_RES_0402LF-4.7K,5%,1/16W,CHIA]
    2  RST_PCIE_E1S_1_PERST_N      B  @S9S_MB_2U_LIB.S9S_MB_2U(SCH_1):RST_PCIE_E1S_1_PERST_N
    1  P3V3_AUX           A  @S9S_MB_2U_LIB.S9S_MB_2U(SCH_1):P3V3_AUX

Q_RES  I17  R2126  [Q_RES_0402LF-4.7K,5%,1/16W,CHIA]
    2  RST_PCIE_E1S_3_PERST_N      B  @S9S_MB_2U_LIB.S9S_MB_2U(SCH_1):RST_PCIE_E1S_3_PERST_N
    1  P3V3_AUX           A  @S9S_MB_2U_LIB.S9S_MB_2U(SCH_1):P3V3_AUX

Q_RES  I29  R2127  [Q_RES_0402LF-4.7K,5%,1/16W,CHIA]
    2  RST_SMB_E1S_1_N      B  @S9S_MB_2U_LIB.S9S_MB_2U(SCH_1):RST_SMB_E1S_1_N
    1  P3V3_AUX           A  @S9S_MB_2U_LIB.S9S_MB_2U(SCH_1):P3V3_AUX

Q_RES  I34  R2128  [Q_RES_0402LF-4.7K,5%,1/16W,CHIA]
    2  RST_SMB_E1S_3_N      B  @S9S_MB_2U_LIB.S9S_MB_2U(SCH_1):RST_SMB_E1S_3_N
    1  P3V3_AUX           A  @S9S_MB_2U_LIB.S9S_MB_2U(SCH_1):P3V3_AUX

Q_RES  I118  R2129  [Q_RES_0402LF-33.2,1%,1/16W,CHIA]
    2  RST_PCIE_E1S_PERST_N      B  @S9S_MB_2U_LIB.S9S_MB_2U(SCH_1):RST_PCIE_E1S_PERST_N
    1  RST_PCIE_CPU0_DEV_PERST_N      A  @S9S_MB_2U_LIB.S9S_MB_2U(SCH_1):RST_PCIE_CPU0_DEV_PERST_N

Q_RES  I322  R2130  [Q_RES_0402LF-0,5%,1/16W,CHIP,CA]
    1  USB2_4_DN          A  @S9S_MB_2U_LIB.S9S_MB_2U(SCH_1):USB2_4_DN
    2  RISER2_USB2_4_DN      B  @S9S_MB_2U_LIB.S9S_MB_2U(SCH_1):RISER2_USB2_4_DN

Q_RES  I323  R2131  [Q_RES_0402LF-0,5%,1/16W,CHIP,CA]
    1  USB2_4_DP          A  @S9S_MB_2U_LIB.S9S_MB_2U(SCH_1):USB2_4_DP
    2  RISER2_USB2_4_DP      B  @S9S_MB_2U_LIB.S9S_MB_2U(SCH_1):RISER2_USB2_4_DP

Q_RES  I74  R2132  [Q_RES_0402LF-0,5%,1/16W,EMPTY,A]
    1  JTAG_TRC_PCH_PTI<6>      A  @S9S_MB_2U_LIB.S9S_MB_2U(SCH_1):JTAG_TRC_PCH_PTI<6>
    2  FM_ESPI_PLD_R_EN      B  @S9S_MB_2U_LIB.S9S_MB_2U(SCH_1):FM_ESPI_PLD_R_EN

Q_RES  I80  R2133  [Q_RES_0402LF-1K,1%,1/16W,CHIP,A]
    2  PU_ESPI_ENABLE_STRAP      B  @S9S_MB_2U_LIB.S9S_MB_2U(SCH_1):PU_ESPI_ENABLE_STRAP
    1  P3V3_AUX           A  @S9S_MB_2U_LIB.S9S_MB_2U(SCH_1):P3V3_AUX

Q_RES  I83  R2134  [Q_RES_0402LF-10K,1%,1/16W,CHIPA]
    1  JTAG_TRC_PCH_PTI<6>      A  @S9S_MB_2U_LIB.S9S_MB_2U(SCH_1):JTAG_TRC_PCH_PTI<6>
    2  GND                B  @S9S_MB_2U_LIB.S9S_MB_2U(SCH_1):GND

Q_RES  I53  R2135  [Q_RES_0402LF-0,5%,1/16W,CHIP,CA]
    1  VIRTUAL_RESEAT_FPGA_N      A  @S9S_MB_2U_LIB.S9S_MB_2U(SCH_1):VIRTUAL_RESEAT_FPGA_N
    2  P12V_SCM_EN_N      B  @S9S_MB_2U_LIB.S9S_MB_2U(SCH_1):P12V_SCM_EN_N

Q_RES  I49  R2137  [Q_RES_0402LF-576,1%,1/16W,CHIPA]
    1  P12V_SCM_ILM       A  @S9S_MB_2U_LIB.S9S_MB_2U(SCH_1):P12V_SCM_ILM
    2  GND                B  @S9S_MB_2U_LIB.S9S_MB_2U(SCH_1):GND

Q_RES  I50  R2138  [Q_RES_0402LF-10K,1%,1/16W,CHIPA]
    1  P3V3_AUX           A  @S9S_MB_2U_LIB.S9S_MB_2U(SCH_1):P3V3_AUX
    2  P12V_SCM_FLT_N      B  @S9S_MB_2U_LIB.S9S_MB_2U(SCH_1):P12V_SCM_FLT_N

Q_RES  I442  R2139  [Q_RES_0402LF-0,5%,1/16W,CHIP,CA]
    1  FM_RISER2_JTAG_SEL_PLD_N      A  @S9S_MB_2U_LIB.S9S_MB_2U(SCH_1):FM_RISER2_JTAG_SEL_PLD_N
    2  FM_RISER2_JTAG_SEL_N      B  @S9S_MB_2U_LIB.S9S_MB_2U(SCH_1):FM_RISER2_JTAG_SEL_N

Q_RES  I328  R2140  [Q_RES_0402LF-10K,5%,1/16W,CHIPA]
    1  P3V3_AUX           A  @S9S_MB_2U_LIB.S9S_MB_2U(SCH_1):P3V3_AUX
    2  FM_RISER2_JTAG_SEL_N      B  @S9S_MB_2U_LIB.S9S_MB_2U(SCH_1):FM_RISER2_JTAG_SEL_N

Q_RES  I151  R2141  [Q_RES_0402LF-2.4K,1%,1/16W,CHIA]
    1  TP_MP5981_0_IMON      A  @S9S_MB_2U_LIB.S9S_MB_2U(SCH_1):TP_MP5981_0_IMON
    2  GND                B  @S9S_MB_2U_LIB.S9S_MB_2U(SCH_1):GND

Q_RES  I109  R2142  [Q_RES_0402LF-2.4K,1%,1/16W,CHIA]
    1  TP_MP5981_1_IMON      A  @S9S_MB_2U_LIB.S9S_MB_2U(SCH_1):TP_MP5981_1_IMON
    2  GND                B  @S9S_MB_2U_LIB.S9S_MB_2U(SCH_1):GND

Q_RES  I227  R2143  [Q_RES_0402LF-0,5%,1/16W,CHIP,CA]
    1  CLK_100M_EDSFF1A_1_R_DP      A  @S9S_MB_2U_LIB.S9S_MB_2U(SCH_1):CLK_100M_EDSFF1A_1_R_DP
    2  CLK_100M_EDSFF1A_1_DP      B  @S9S_MB_2U_LIB.S9S_MB_2U(SCH_1):CLK_100M_EDSFF1A_1_DP

Q_RES  I228  R2144  [Q_RES_0402LF-0,5%,1/16W,CHIP,CA]
    1  CLK_100M_EDSFF1A_1_R_DN      A  @S9S_MB_2U_LIB.S9S_MB_2U(SCH_1):CLK_100M_EDSFF1A_1_R_DN
    2  CLK_100M_EDSFF1A_1_DN      B  @S9S_MB_2U_LIB.S9S_MB_2U(SCH_1):CLK_100M_EDSFF1A_1_DN

Q_RES  I231  R2145  [Q_RES_0402LF-0,5%,1/16W,CHIP,CA]
    1  CLK_100M_EDSFF1B_1_R_DP      A  @S9S_MB_2U_LIB.S9S_MB_2U(SCH_1):CLK_100M_EDSFF1B_1_R_DP
    2  CLK_100M_EDSFF1B_1_DP      B  @S9S_MB_2U_LIB.S9S_MB_2U(SCH_1):CLK_100M_EDSFF1B_1_DP

Q_RES  I232  R2146  [Q_RES_0402LF-0,5%,1/16W,CHIP,CA]
    1  CLK_100M_EDSFF1B_1_R_DN      A  @S9S_MB_2U_LIB.S9S_MB_2U(SCH_1):CLK_100M_EDSFF1B_1_R_DN
    2  CLK_100M_EDSFF1B_1_DN      B  @S9S_MB_2U_LIB.S9S_MB_2U(SCH_1):CLK_100M_EDSFF1B_1_DN

Q_RES  I253  R2147  [Q_RES_0402LF-0,5%,1/16W,CHIP,CA]
    2  FM_BIOS_DEBUG_EN_R_N      B  @S9S_MB_2U_LIB.S9S_MB_2U(SCH_1):FM_BIOS_DEBUG_EN_R_N
    1  FM_BIOS_DEBUG_EN_N      A  @S9S_MB_2U_LIB.S9S_MB_2U(SCH_1):FM_BIOS_DEBUG_EN_N

Q_RES  I337  R2148  [Q_RES_0402LF-0,5%,1/16W,CHIP,CA]
    1  FM_PCIE_EDSFF3_PRSNT_1_N      A  @S9S_MB_2U_LIB.S9S_MB_2U(SCH_1):FM_PCIE_EDSFF3_PRSNT_1_N
    2  EDSFF3_CLK_EN_N      B  @S9S_MB_2U_LIB.S9S_MB_2U(SCH_1):EDSFF3_CLK_EN_N

Q_RES  I460  R2149  [Q_RES_0402LF-0,5%,1/16W,CHIP,CA]
    2  USB2_5_DN          B  @S9S_MB_2U_LIB.S9S_MB_2U(SCH_1):USB2_5_DN
    1  EDSFF3_USB2_5_DN      A  @S9S_MB_2U_LIB.S9S_MB_2U(SCH_1):EDSFF3_USB2_5_DN

Q_RES  I457  R2150  [Q_RES_0402LF-0,5%,1/16W,CHIP,CA]
    2  USB2_5_DP          B  @S9S_MB_2U_LIB.S9S_MB_2U(SCH_1):USB2_5_DP
    1  EDSFF3_USB2_5_DP      A  @S9S_MB_2U_LIB.S9S_MB_2U(SCH_1):EDSFF3_USB2_5_DP

Q_RES  I94  R2151  [Q_RES_0402LF-0,5%,1/16W,CHIP,CA]
    1  E1S_0_PWR_FAIL_N      A  @S9S_MB_2U_LIB.S9S_MB_2U(SCH_1):E1S_0_PWR_FAIL_N
    2  E1S_0_LED_ACT_N      B  @S9S_MB_2U_LIB.S9S_MB_2U(SCH_1):E1S_0_LED_ACT_N

Q_RES  I97  R2152  [Q_RES_0402LF-0,5%,1/16W,CHIP,CA]
    1  E1S_1_PWR_FAIL_N      A  @S9S_MB_2U_LIB.S9S_MB_2U(SCH_1):E1S_1_PWR_FAIL_N
    2  E1S_1_LED_ACT_N      B  @S9S_MB_2U_LIB.S9S_MB_2U(SCH_1):E1S_1_LED_ACT_N

Q_RES  I100  R2153  [Q_RES_0402LF-0,5%,1/16W,CHIP,CA]
    1  E1S_2_PWR_FAIL_N      A  @S9S_MB_2U_LIB.S9S_MB_2U(SCH_1):E1S_2_PWR_FAIL_N
    2  E1S_2_LED_ACT_N      B  @S9S_MB_2U_LIB.S9S_MB_2U(SCH_1):E1S_2_LED_ACT_N

Q_RES  I98  R2154  [Q_RES_0402LF-0,5%,1/16W,CHIP,CA]
    1  E1S_3_PWR_FAIL_N      A  @S9S_MB_2U_LIB.S9S_MB_2U(SCH_1):E1S_3_PWR_FAIL_N
    2  E1S_3_LED_ACT_N      B  @S9S_MB_2U_LIB.S9S_MB_2U(SCH_1):E1S_3_LED_ACT_N

Q_RES  I447  R2155  [Q_RES_0402LF-0,5%,1/16W,CHIP,CA]
    1  FM_BMC_READY_R_PLD_N      A  @S9S_MB_2U_LIB.S9S_MB_2U(SCH_1):FM_BMC_READY_R_PLD_N
    2  FM_BMC_READY_R_N      B  @S9S_MB_2U_LIB.S9S_MB_2U(SCH_1):FM_BMC_READY_R_N

Q_RES  I196  R2156  [Q_RES_0402LF-0,5%,1/16W,CHIP,CA]
    1  PD_MB_PRSNT        A  @S9S_MB_2U_LIB.S9S_MB_2U(SCH_1):PD_MB_PRSNT
    2  GND                B  @S9S_MB_2U_LIB.S9S_MB_2U(SCH_1):GND

Q_RES  I171  R2157  [Q_RES_0402LF-4.7K,1%,1/16W,CHIA]
    1  P3V3_AUX           A  @S9S_MB_2U_LIB.S9S_MB_2U(SCH_1):P3V3_AUX
    2  FAN_PDB_PRSNT_N      B  @S9S_MB_2U_LIB.S9S_MB_2U(SCH_1):FAN_PDB_PRSNT_N

Q_RES  I402  R2158  [Q_RES_0402LF-10K,5%,1/16W,CHIPA]
    2  PCIE_RISER2_PRSNT_N      B  @S9S_MB_2U_LIB.S9S_MB_2U(SCH_1):PCIE_RISER2_PRSNT_N
    1  P3V3_AUX           A  @S9S_MB_2U_LIB.S9S_MB_2U(SCH_1):P3V3_AUX

Q_RES  I189  R2159  [Q_RES_0402LF-0,5%,1/16W,CHIP,CA]
    2  FM_P12V_E1S_2_EN      B  @S9S_MB_2U_LIB.S9S_MB_2U(SCH_1):FM_P12V_E1S_2_EN
    1  E1S_2_EN           A  @S9S_MB_2U_LIB.S9S_MB_2U(SCH_1):E1S_2_EN

Q_RES  I187  R2160  [Q_RES_0402LF-0,5%,1/16W,CHIP,CA]
    2  FM_P12V_E1S_0_EN      B  @S9S_MB_2U_LIB.S9S_MB_2U(SCH_1):FM_P12V_E1S_0_EN
    1  E1S_0_EN           A  @S9S_MB_2U_LIB.S9S_MB_2U(SCH_1):E1S_0_EN

Q_RES  I193  R2161  [Q_RES_0402LF-0,5%,1/16W,CHIP,CA]
    2  FM_P12V_E1S_1_EN      B  @S9S_MB_2U_LIB.S9S_MB_2U(SCH_1):FM_P12V_E1S_1_EN
    1  E1S_1_EN           A  @S9S_MB_2U_LIB.S9S_MB_2U(SCH_1):E1S_1_EN

Q_RES  I191  R2162  [Q_RES_0402LF-0,5%,1/16W,CHIP,CA]
    2  FM_P12V_E1S_3_EN      B  @S9S_MB_2U_LIB.S9S_MB_2U(SCH_1):FM_P12V_E1S_3_EN
    1  E1S_3_EN           A  @S9S_MB_2U_LIB.S9S_MB_2U(SCH_1):E1S_3_EN

Q_RES  I72  R2163  [Q_RES_0402LF-0,5%,1/16W,CHIP,CA]
    2  FM_P3V3_E1S_2_EN      B  @S9S_MB_2U_LIB.S9S_MB_2U(SCH_1):FM_P3V3_E1S_2_EN
    1  E1S_2_EN           A  @S9S_MB_2U_LIB.S9S_MB_2U(SCH_1):E1S_2_EN

Q_RES  I70  R2164  [Q_RES_0402LF-0,5%,1/16W,CHIP,CA]
    2  FM_P3V3_E1S_0_EN      B  @S9S_MB_2U_LIB.S9S_MB_2U(SCH_1):FM_P3V3_E1S_0_EN
    1  E1S_0_EN           A  @S9S_MB_2U_LIB.S9S_MB_2U(SCH_1):E1S_0_EN

Q_RES  I74  R2165  [Q_RES_0402LF-0,5%,1/16W,CHIP,CA]
    2  FM_P3V3_E1S_1_EN      B  @S9S_MB_2U_LIB.S9S_MB_2U(SCH_1):FM_P3V3_E1S_1_EN
    1  E1S_1_EN           A  @S9S_MB_2U_LIB.S9S_MB_2U(SCH_1):E1S_1_EN

Q_RES  I76  R2166  [Q_RES_0402LF-0,5%,1/16W,CHIP,CA]
    2  FM_P3V3_E1S_3_EN      B  @S9S_MB_2U_LIB.S9S_MB_2U(SCH_1):FM_P3V3_E1S_3_EN
    1  E1S_3_EN           A  @S9S_MB_2U_LIB.S9S_MB_2U(SCH_1):E1S_3_EN

Q_RES  I1   R2167  [Q_RES_0402LF-10K,1%,1/16W,CHIPA]
    2  RISER1_TYPE_ID      B  @S9S_MB_2U_LIB.S9S_MB_2U(SCH_1):RISER1_TYPE_ID
    1  P3V3_AUX           A  @S9S_MB_2U_LIB.S9S_MB_2U(SCH_1):P3V3_AUX

Q_RES  I27  R2168  [Q_RES_0402LF-10K,5%,1/16W,EMPTA]
    1  P3V3_AUX           A  @S9S_MB_2U_LIB.S9S_MB_2U(SCH_1):P3V3_AUX
    2  FM_SYS_THROTTLE_R_N      B  @S9S_MB_2U_LIB.S9S_MB_2U(SCH_1):FM_SYS_THROTTLE_R_N

Q_RES  I137  R2169  [Q_RES_0402LF-0,5%,1/16W,CHIP,CA]
    1  FM_SYS_THROTTLE_R_N      A  @S9S_MB_2U_LIB.S9S_MB_2U(SCH_1):FM_SYS_THROTTLE_R_N
    2  FM_RISER1_PWRBRK_N      B  @S9S_MB_2U_LIB.S9S_MB_2U(SCH_1):FM_RISER1_PWRBRK_N

Q_RES  I132  R2170  [Q_RES_0402LF-10K,5%,1/16W,CHIPA]
    2  PCIE_RISER1_PRSNT2_N      B  @S9S_MB_2U_LIB.S9S_MB_2U(SCH_1):PCIE_RISER1_PRSNT2_N
    1  P3V3_AUX           A  @S9S_MB_2U_LIB.S9S_MB_2U(SCH_1):P3V3_AUX

Q_RES  I144  R2171  [Q_RES_0402LF-33.2,1%,1/16W,CHIA]
    1  IRQ_LVC3_WAKE_R1_N      A  @S9S_MB_2U_LIB.S9S_MB_2U(SCH_1):IRQ_LVC3_WAKE_R1_N
    2  IRQ_LVC3_WAKE_N      B  @S9S_MB_2U_LIB.S9S_MB_2U(SCH_1):IRQ_LVC3_WAKE_N

Q_RES  I135  R2172  [Q_RES_0402LF-100,1%,1/16W,CHIPA]
    1  PD_RISER1_PRSNT1      A  @S9S_MB_2U_LIB.S9S_MB_2U(SCH_1):PD_RISER1_PRSNT1
    2  GND                B  @S9S_MB_2U_LIB.S9S_MB_2U(SCH_1):GND

Q_RES  I133  R2173  [Q_RES_0402LF-10K,5%,1/16W,CHIPA]
    2  RISER1_CLK0_EN_N      B  @S9S_MB_2U_LIB.S9S_MB_2U(SCH_1):RISER1_CLK0_EN_N
    1  P3V3_AUX           A  @S9S_MB_2U_LIB.S9S_MB_2U(SCH_1):P3V3_AUX

Q_RES  I134  R2174  [Q_RES_0402LF-10K,5%,1/16W,CHIPA]
    2  RISER1_CLK1_EN_N      B  @S9S_MB_2U_LIB.S9S_MB_2U(SCH_1):RISER1_CLK1_EN_N
    1  P3V3_AUX           A  @S9S_MB_2U_LIB.S9S_MB_2U(SCH_1):P3V3_AUX

Q_RES  I148  R2175  [Q_RES_0402LF-4.7K,5%,1/16W,EMPA]
    2  P3V3_AUX           B  @S9S_MB_2U_LIB.S9S_MB_2U(SCH_1):P3V3_AUX
    1  JTAG_RISER1_TDI      A  @S9S_MB_2U_LIB.S9S_MB_2U(SCH_1):JTAG_RISER1_TDI

Q_RES  I149  R2176  [Q_RES_0402LF-4.7K,5%,1/16W,EMPA]
    2  P3V3_AUX           B  @S9S_MB_2U_LIB.S9S_MB_2U(SCH_1):P3V3_AUX
    1  JTAG_RISER1_TDO      A  @S9S_MB_2U_LIB.S9S_MB_2U(SCH_1):JTAG_RISER1_TDO

Q_RES  I147  R2177  [Q_RES_0402LF-4.7K,5%,1/16W,EMPA]
    2  P3V3_AUX           B  @S9S_MB_2U_LIB.S9S_MB_2U(SCH_1):P3V3_AUX
    1  JTAG_RISER1_TMS      A  @S9S_MB_2U_LIB.S9S_MB_2U(SCH_1):JTAG_RISER1_TMS

Q_RES  I146  R2178  [Q_RES_0402LF-4.7K,5%,1/16W,EMPA]
    1  JTAG_RISER1_TCK      A  @S9S_MB_2U_LIB.S9S_MB_2U(SCH_1):JTAG_RISER1_TCK
    2  GND                B  @S9S_MB_2U_LIB.S9S_MB_2U(SCH_1):GND

Q_RES  I145  R2179  [Q_RES_0402LF-4.7K,5%,1/16W,EMPA]
    1  JTAG_RISER1_TRST_N      A  @S9S_MB_2U_LIB.S9S_MB_2U(SCH_1):JTAG_RISER1_TRST_N
    2  GND                B  @S9S_MB_2U_LIB.S9S_MB_2U(SCH_1):GND

Q_RES  I465  R2180  [Q_RES_0402LF-10K,1%,1/16W,CHIPA]
    1  P3V3_AUX           A  @S9S_MB_2U_LIB.S9S_MB_2U(SCH_1):P3V3_AUX
    2  FM_EDSFF3_TYPE_ID      B  @S9S_MB_2U_LIB.S9S_MB_2U(SCH_1):FM_EDSFF3_TYPE_ID

Q_RES  I277  R2181  [Q_RES_0402LF-0,5%,1/16W,CHIP,CA]
    1  CLK_100M_PE_0_R_DP      A  @S9S_MB_2U_LIB.S9S_MB_2U(SCH_1):CLK_100M_PE_0_R_DP
    2  CLK_100M_PE_0_DP      B  @S9S_MB_2U_LIB.S9S_MB_2U(SCH_1):CLK_100M_PE_0_DP

Q_RES  I278  R2182  [Q_RES_0402LF-0,5%,1/16W,CHIP,CA]
    1  CLK_100M_PE_0_R_DN      A  @S9S_MB_2U_LIB.S9S_MB_2U(SCH_1):CLK_100M_PE_0_R_DN
    2  CLK_100M_PE_0_DN      B  @S9S_MB_2U_LIB.S9S_MB_2U(SCH_1):CLK_100M_PE_0_DN

Q_RES  I279  R2183  [Q_RES_0402LF-0,5%,1/16W,CHIP,CA]
    1  CLK_100M_PE_1_R_DP      A  @S9S_MB_2U_LIB.S9S_MB_2U(SCH_1):CLK_100M_PE_1_R_DP
    2  CLK_100M_PE_1_DP      B  @S9S_MB_2U_LIB.S9S_MB_2U(SCH_1):CLK_100M_PE_1_DP

Q_RES  I280  R2184  [Q_RES_0402LF-0,5%,1/16W,CHIP,CA]
    1  CLK_100M_PE_1_R_DN      A  @S9S_MB_2U_LIB.S9S_MB_2U(SCH_1):CLK_100M_PE_1_R_DN
    2  CLK_100M_PE_1_DN      B  @S9S_MB_2U_LIB.S9S_MB_2U(SCH_1):CLK_100M_PE_1_DN

Q_RES  I123  R2185  [Q_RES_0402LF-0,5%,1/16W,CHIP,CA]
    2  FM_RISER1_JTAG_SEL_PLD_N      B  @S9S_MB_2U_LIB.S9S_MB_2U(SCH_1):FM_RISER1_JTAG_SEL_PLD_N
    1  FM_JTAG_EDSFF4_SEL      A  @S9S_MB_2U_LIB.S9S_MB_2U(SCH_1):FM_JTAG_EDSFF4_SEL

Q_RES  I213  R2186  [Q_RES_0402LF-33,5%,1/16W,CHIP,A]
    2  PWRGD_PS_PWROK      B  @S9S_MB_2U_LIB.S9S_MB_2U(SCH_1):PWRGD_PS_PWROK
    1  PWRGD_HSC_P12V_PWROK      A  @S9S_MB_2U_LIB.S9S_MB_2U(SCH_1):PWRGD_HSC_P12V_PWROK

Q_RES  I173  R2187  [Q_RES_0402LF-0,5%,1/16W,CHIP,CA]
    1  SMB_RISER1_3V3AUX_SDA      A  @S9S_MB_2U_LIB.S9S_MB_2U(SCH_1):SMB_RISER1_3V3AUX_SDA
    2  SMB_PCIE0_3V3AUX_SDA_R0      B  @S9S_MB_2U_LIB.S9S_MB_2U(SCH_1):SMB_PCIE0_3V3AUX_SDA_R0

Q_RES  I174  R2188  [Q_RES_0402LF-0,5%,1/16W,CHIP,CA]
    1  SMB_RISER1_3V3AUX_SCL      A  @S9S_MB_2U_LIB.S9S_MB_2U(SCH_1):SMB_RISER1_3V3AUX_SCL
    2  SMB_PCIE0_3V3AUX_SCL_R0      B  @S9S_MB_2U_LIB.S9S_MB_2U(SCH_1):SMB_PCIE0_3V3AUX_SCL_R0

Q_RES  I171  R2189  [Q_RES_0402LF-0,5%,1/16W,CHIP,CA]
    2  SMB_SENSOR_M2_P0_3V3AUX_SCL      B  @S9S_MB_2U_LIB.S9S_MB_2U(SCH_1):SMB_SENSOR_M2_P0_3V3AUX_SCL
    1  SMB_PCIE0_3V3AUX_SCL_R3      A  @S9S_MB_2U_LIB.S9S_MB_2U(SCH_1):SMB_PCIE0_3V3AUX_SCL_R3

Q_RES  I172  R2190  [Q_RES_0402LF-0,5%,1/16W,CHIP,CA]
    2  SMB_SENSOR_M2_P0_3V3AUX_SDA      B  @S9S_MB_2U_LIB.S9S_MB_2U(SCH_1):SMB_SENSOR_M2_P0_3V3AUX_SDA
    1  SMB_PCIE0_3V3AUX_SDA_R3      A  @S9S_MB_2U_LIB.S9S_MB_2U(SCH_1):SMB_PCIE0_3V3AUX_SDA_R3

Q_RES  I113  R2191  [Q_RES_0402LF-10K,1%,1/16W,EMPTA]
    2  PCA9546_PCIE3_ADDR2      B  @S9S_MB_2U_LIB.S9S_MB_2U(SCH_1):PCA9546_PCIE3_ADDR2
    1  P3V3_AUX           A  @S9S_MB_2U_LIB.S9S_MB_2U(SCH_1):P3V3_AUX

Q_RES  I116  R2192  [Q_RES_0402LF-1K,1%,1/16W,CHIP,A]
    1  PCA9546_PCIE3_ADDR2      A  @S9S_MB_2U_LIB.S9S_MB_2U(SCH_1):PCA9546_PCIE3_ADDR2
    2  GND                B  @S9S_MB_2U_LIB.S9S_MB_2U(SCH_1):GND

Q_RES  I115  R2193  [Q_RES_0402LF-10K,1%,1/16W,CHIPA]
    2  PCA9546_PCIE3_ADDR1      B  @S9S_MB_2U_LIB.S9S_MB_2U(SCH_1):PCA9546_PCIE3_ADDR1
    1  P3V3_AUX           A  @S9S_MB_2U_LIB.S9S_MB_2U(SCH_1):P3V3_AUX

Q_RES  I117  R2194  [Q_RES_0402LF-1K,1%,1/16W,EMPTYA]
    1  PCA9546_PCIE3_ADDR1      A  @S9S_MB_2U_LIB.S9S_MB_2U(SCH_1):PCA9546_PCIE3_ADDR1
    2  GND                B  @S9S_MB_2U_LIB.S9S_MB_2U(SCH_1):GND

Q_RES  I114  R2195  [Q_RES_0402LF-10K,1%,1/16W,EMPTA]
    2  PCA9546_PCIE3_ADDR0      B  @S9S_MB_2U_LIB.S9S_MB_2U(SCH_1):PCA9546_PCIE3_ADDR0
    1  P3V3_AUX           A  @S9S_MB_2U_LIB.S9S_MB_2U(SCH_1):P3V3_AUX

Q_RES  I118  R2196  [Q_RES_0402LF-1K,1%,1/16W,CHIP,A]
    1  PCA9546_PCIE3_ADDR0      A  @S9S_MB_2U_LIB.S9S_MB_2U(SCH_1):PCA9546_PCIE3_ADDR0
    2  GND                B  @S9S_MB_2U_LIB.S9S_MB_2U(SCH_1):GND

Q_RES  I112  R2197  [Q_RES_0402LF-10K,1%,1/16W,CHIPA]
    2  PU_RST_SMB_PCIE3_N      B  @S9S_MB_2U_LIB.S9S_MB_2U(SCH_1):PU_RST_SMB_PCIE3_N
    1  P3V3_AUX           A  @S9S_MB_2U_LIB.S9S_MB_2U(SCH_1):P3V3_AUX

Q_RES  I123  R2198  [Q_RES_0402LF-2.2K ,5%,1/16W,CHA]
    2  SMB_PCIE3_3V3AUX_SCL      B  @S9S_MB_2U_LIB.S9S_MB_2U(SCH_1):SMB_PCIE3_3V3AUX_SCL
    1  P3V3_AUX           A  @S9S_MB_2U_LIB.S9S_MB_2U(SCH_1):P3V3_AUX

Q_RES  I124  R2199  [Q_RES_0402LF-2.2K ,5%,1/16W,CHA]
    2  SMB_PCIE3_3V3AUX_SDA      B  @S9S_MB_2U_LIB.S9S_MB_2U(SCH_1):SMB_PCIE3_3V3AUX_SDA
    1  P3V3_AUX           A  @S9S_MB_2U_LIB.S9S_MB_2U(SCH_1):P3V3_AUX

Q_RES  I122  R2200  [Q_RES_0402LF-2.2K ,5%,1/16W,CHA]
    2  SMB_OCP_SFF_3V3AUX_SCL      B  @S9S_MB_2U_LIB.S9S_MB_2U(SCH_1):SMB_OCP_SFF_3V3AUX_SCL
    1  P3V3_AUX           A  @S9S_MB_2U_LIB.S9S_MB_2U(SCH_1):P3V3_AUX

Q_RES  I121  R2201  [Q_RES_0402LF-2.2K ,5%,1/16W,CHA]
    2  SMB_OCP_SFF_3V3AUX_SDA      B  @S9S_MB_2U_LIB.S9S_MB_2U(SCH_1):SMB_OCP_SFF_3V3AUX_SDA
    1  P3V3_AUX           A  @S9S_MB_2U_LIB.S9S_MB_2U(SCH_1):P3V3_AUX

Q_RES  I120  R2202  [Q_RES_0402LF-2.2K ,5%,1/16W,CHA]
    2  SMB_RISER3_3V3AUX_SCL      B  @S9S_MB_2U_LIB.S9S_MB_2U(SCH_1):SMB_RISER3_3V3AUX_SCL
    1  P3V3_AUX           A  @S9S_MB_2U_LIB.S9S_MB_2U(SCH_1):P3V3_AUX

Q_RES  I119  R2203  [Q_RES_0402LF-2.2K ,5%,1/16W,CHA]
    2  SMB_RISER3_3V3AUX_SDA      B  @S9S_MB_2U_LIB.S9S_MB_2U(SCH_1):SMB_RISER3_3V3AUX_SDA
    1  P3V3_AUX           A  @S9S_MB_2U_LIB.S9S_MB_2U(SCH_1):P3V3_AUX

Q_RES  I183  R2204  [Q_RES_0402LF-2.2K ,5%,1/16W,CHA]
    2  SMB_PCIE0_3V3AUX_SCL      B  @S9S_MB_2U_LIB.S9S_MB_2U(SCH_1):SMB_PCIE0_3V3AUX_SCL
    1  P3V3_AUX           A  @S9S_MB_2U_LIB.S9S_MB_2U(SCH_1):P3V3_AUX

Q_RES  I182  R2205  [Q_RES_0402LF-2.2K ,5%,1/16W,CHA]
    2  SMB_PCIE0_3V3AUX_SDA      B  @S9S_MB_2U_LIB.S9S_MB_2U(SCH_1):SMB_PCIE0_3V3AUX_SDA
    1  P3V3_AUX           A  @S9S_MB_2U_LIB.S9S_MB_2U(SCH_1):P3V3_AUX

Q_RES  I154  R2206  [Q_RES_0402LF-2.2K ,5%,1/16W,CHA]
    2  SMB_PCIE2_3V3AUX_SCL      B  @S9S_MB_2U_LIB.S9S_MB_2U(SCH_1):SMB_PCIE2_3V3AUX_SCL
    1  P3V3_AUX           A  @S9S_MB_2U_LIB.S9S_MB_2U(SCH_1):P3V3_AUX

Q_RES  I155  R2207  [Q_RES_0402LF-2.2K ,5%,1/16W,CHA]
    2  SMB_PCIE2_3V3AUX_SDA      B  @S9S_MB_2U_LIB.S9S_MB_2U(SCH_1):SMB_PCIE2_3V3AUX_SDA
    1  P3V3_AUX           A  @S9S_MB_2U_LIB.S9S_MB_2U(SCH_1):P3V3_AUX

Q_RES  I194  R2208  [Q_RES_0402LF-0,5%,1/16W,CHIP,CA]
    1  SMB_S3M_CPU_3V3AUX_SCL      A  @S9S_MB_2U_LIB.S9S_MB_2U(SCH_1):SMB_S3M_CPU_3V3AUX_SCL
    2  SMB_S3M_CPU0_3V3AUX_SCL      B  @S9S_MB_2U_LIB.S9S_MB_2U(SCH_1):SMB_S3M_CPU0_3V3AUX_SCL

Q_RES  I197  R2209  [Q_RES_0402LF-0,5%,1/16W,CHIP,CA]
    1  SMB_S3M_CPU_3V3AUX_SDA      A  @S9S_MB_2U_LIB.S9S_MB_2U(SCH_1):SMB_S3M_CPU_3V3AUX_SDA
    2  SMB_S3M_CPU0_3V3AUX_SDA      B  @S9S_MB_2U_LIB.S9S_MB_2U(SCH_1):SMB_S3M_CPU0_3V3AUX_SDA

Q_RES  I193  R2210  [Q_RES_0402LF-0,5%,1/16W,CHIP,CA]
    1  SMB_S3M_CPU_3V3AUX_SCL      A  @S9S_MB_2U_LIB.S9S_MB_2U(SCH_1):SMB_S3M_CPU_3V3AUX_SCL
    2  SMB_S3M_CPU1_3V3AUX_SCL      B  @S9S_MB_2U_LIB.S9S_MB_2U(SCH_1):SMB_S3M_CPU1_3V3AUX_SCL

Q_RES  I196  R2211  [Q_RES_0402LF-0,5%,1/16W,CHIP,CA]
    1  SMB_S3M_CPU_3V3AUX_SDA      A  @S9S_MB_2U_LIB.S9S_MB_2U(SCH_1):SMB_S3M_CPU_3V3AUX_SDA
    2  SMB_S3M_CPU1_3V3AUX_SDA      B  @S9S_MB_2U_LIB.S9S_MB_2U(SCH_1):SMB_S3M_CPU1_3V3AUX_SDA

Q_RES  I202  R2212  [Q_RES_0402LF-2.2K ,5%,1/16W,CHA]
    1  SMB_S3M_CPU_3V3AUX_SCL      A  @S9S_MB_2U_LIB.S9S_MB_2U(SCH_1):SMB_S3M_CPU_3V3AUX_SCL
    2  P3V3_AUX           B  @S9S_MB_2U_LIB.S9S_MB_2U(SCH_1):P3V3_AUX

Q_RES  I203  R2213  [Q_RES_0402LF-2.2K ,5%,1/16W,CHA]
    1  SMB_S3M_CPU_3V3AUX_SDA      A  @S9S_MB_2U_LIB.S9S_MB_2U(SCH_1):SMB_S3M_CPU_3V3AUX_SDA
    2  P3V3_AUX           B  @S9S_MB_2U_LIB.S9S_MB_2U(SCH_1):P3V3_AUX

Q_RES  I22  R2322  [Q_RES_0402LF-49.9     ,1%  ,1/B]
    2  SVID_CLK0_CPU0_R      B  @S9S_MB_2U_LIB.S9S_MB_2U(SCH_1):SVID_CLK0_CPU0_R
    1  PVNN_TERM_CPU0      A  @S9S_MB_2U_LIB.S9S_MB_2U(SCH_1):PVNN_TERM_CPU0

Q_RES  I7   R2330  [Q_RES_0402LF-10K,1%,1/16W,EMPTA]
    1  P3V3_AUX           A  @S9S_MB_2U_LIB.S9S_MB_2U(SCH_1):P3V3_AUX
    2  FM_PVPP_HBM_CPU0_EN      B  @S9S_MB_2U_LIB.S9S_MB_2U(SCH_1):FM_PVPP_HBM_CPU0_EN

Q_RES  I16  R2332  [Q_RES_0402LF-2K,1%,1/16W,EMPTYA]
    2  GND                B  @S9S_MB_2U_LIB.S9S_MB_2U(SCH_1):GND
    1  FM_PVPP_HBM_CPU0_EN      A  @S9S_MB_2U_LIB.S9S_MB_2U(SCH_1):FM_PVPP_HBM_CPU0_EN

Q_RES  I28  R2334  [Q_RES_0402LF-0,5%,1/16W,EMPTY,A]
    1  PWRGD_PVPP_HBM_CPU0_R      A  @S9S_MB_2U_LIB.S9S_MB_2U(SCH_1):PWRGD_PVPP_HBM_CPU0_R
    2  PWRGD_PVPP_HBM_CPU0      B  @S9S_MB_2U_LIB.S9S_MB_2U(SCH_1):PWRGD_PVPP_HBM_CPU0

Q_RES  I51  R2336  [Q_RES_0402LF-26.1K,1%,1/16W,EMA]
    1  PVPP_HBM_CPU0_FB      A  @S9S_MB_2U_LIB.S9S_MB_2U(SCH_1):PVPP_HBM_CPU0_FB
    2  FM_HBM_VPP_SEL_CPU0_D      B  @S9S_MB_2U_LIB.S9S_MB_2U(SCH_1):FM_HBM_VPP_SEL_CPU0_D

Q_RES  I156  R2338  [Q_RES_0402LF-10K,1%,1/16W,EMPTA]
    1  P3V3_AUX           A  @S9S_MB_2U_LIB.S9S_MB_2U(SCH_1):P3V3_AUX
    2  FM_PVNN_MAIN_CPU0_EN      B  @S9S_MB_2U_LIB.S9S_MB_2U(SCH_1):FM_PVNN_MAIN_CPU0_EN

Q_RES  I39  R2345  [Q_RES_0402LF-49.9     ,1%  ,1/B]
    2  SVID_CLK0_CPU1_R      B  @S9S_MB_2U_LIB.S9S_MB_2U(SCH_1):SVID_CLK0_CPU1_R
    1  PVNN_TERM_CPU1      A  @S9S_MB_2U_LIB.S9S_MB_2U(SCH_1):PVNN_TERM_CPU1

Q_RES  I38  R2354  [Q_RES_0402LF-100,1%,1/16W,EMPTA]
    2  SVID_DIO0_CPU1_R      B  @S9S_MB_2U_LIB.S9S_MB_2U(SCH_1):SVID_DIO0_CPU1_R
    1  PVNN_TERM_CPU1      A  @S9S_MB_2U_LIB.S9S_MB_2U(SCH_1):PVNN_TERM_CPU1

Q_RES  I18  R2367  [Q_RES_0402LF-10K,1%,1/16W,EMPTA]
    1  P3V3_AUX           A  @S9S_MB_2U_LIB.S9S_MB_2U(SCH_1):P3V3_AUX
    2  FM_PVPP_HBM_CPU1_EN      B  @S9S_MB_2U_LIB.S9S_MB_2U(SCH_1):FM_PVPP_HBM_CPU1_EN

Q_RES  I12  R2374  [Q_RES_0402LF-2K,1%,1/16W,CHIP,A]
    2  GND                B  @S9S_MB_2U_LIB.S9S_MB_2U(SCH_1):GND
    1  FM_PVPP_HBM_CPU1_EN      A  @S9S_MB_2U_LIB.S9S_MB_2U(SCH_1):FM_PVPP_HBM_CPU1_EN

Q_RES  I40  R2380  [Q_RES_0402LF-0,5%,1/16W,CHIP,CA]
    1  PWRGD_PVPP_HBM_CPU1_R      A  @S9S_MB_2U_LIB.S9S_MB_2U(SCH_1):PWRGD_PVPP_HBM_CPU1_R
    2  PWRGD_PVPP_HBM_CPU1      B  @S9S_MB_2U_LIB.S9S_MB_2U(SCH_1):PWRGD_PVPP_HBM_CPU1

Q_RES  I51  R2381  [Q_RES_0402LF-26.1K,1%,1/16W,CHA]
    1  PVPP_HBM_CPU1_FB      A  @S9S_MB_2U_LIB.S9S_MB_2U(SCH_1):PVPP_HBM_CPU1_FB
    2  FM_HBM_VPP_SEL_CPU1_D      B  @S9S_MB_2U_LIB.S9S_MB_2U(SCH_1):FM_HBM_VPP_SEL_CPU1_D

Q_RES  I161  R2384  [Q_RES_0402LF-10K,1%,1/16W,EMPTA]
    1  P3V3_AUX           A  @S9S_MB_2U_LIB.S9S_MB_2U(SCH_1):P3V3_AUX
    2  FM_PVNN_MAIN_CPU1_EN      B  @S9S_MB_2U_LIB.S9S_MB_2U(SCH_1):FM_PVNN_MAIN_CPU1_EN

Q_RES  I168  R2385  [Q_RES_0402LF-2K,1%,1/16W,CHIP,A]
    2  GND                B  @S9S_MB_2U_LIB.S9S_MB_2U(SCH_1):GND
    1  FM_PVNN_MAIN_CPU1_EN      A  @S9S_MB_2U_LIB.S9S_MB_2U(SCH_1):FM_PVNN_MAIN_CPU1_EN

Q_RES  I183  R2387  [Q_RES_0402LF-0,5%,1/16W,CHIP,CA]
    1  PWRGD_PVNN_MAIN_CPU1_R      A  @S9S_MB_2U_LIB.S9S_MB_2U(SCH_1):PWRGD_PVNN_MAIN_CPU1_R
    2  PWRGD_PVNN_MAIN_CPU1      B  @S9S_MB_2U_LIB.S9S_MB_2U(SCH_1):PWRGD_PVNN_MAIN_CPU1

SW8S_DHNF04FTVTR  I4   S1     [SW8S_DHNF04FTVTR-SW8S_DHNF04FTA]
    3  PU_SWAP_OVERRIDE_N     A3  @S9S_MB_2U_LIB.S9S_MB_2U(SCH_1):PU_SWAP_OVERRIDE_N
    1  PU_ESPI_ENABLE_STRAP     A1  @S9S_MB_2U_LIB.S9S_MB_2U(SCH_1):PU_ESPI_ENABLE_STRAP
    2  PU_BIOS_RCVR_BOOT     A2  @S9S_MB_2U_LIB.S9S_MB_2U(SCH_1):PU_BIOS_RCVR_BOOT
    4  PD_BIOS_IMAGE_SWAP_N     A4  @S9S_MB_2U_LIB.S9S_MB_2U(SCH_1):PD_BIOS_IMAGE_SWAP_N
    8  JTAG_TRC_PCH_PTI<6>     B1  @S9S_MB_2U_LIB.S9S_MB_2U(SCH_1):JTAG_TRC_PCH_PTI<6>
    7  FM_PCH_BIOS_RCVR_MODE     B2  @S9S_MB_2U_LIB.S9S_MB_2U(SCH_1):FM_PCH_BIOS_RCVR_MODE
    5  FM_BIOS_IMAGE_SWAP_N     B4  @S9S_MB_2U_LIB.S9S_MB_2U(SCH_1):FM_BIOS_IMAGE_SWAP_N
    6  FM_ADR_COMPLETE     B3  @S9S_MB_2U_LIB.S9S_MB_2U(SCH_1):FM_ADR_COMPLETE

SW8S_DHNF04FTVTR  I35  S2     [SW8S_DHNF04FTVTR-SW8S_DHNF04FTA]
    7  RST_RTCRST_N      B2  @S9S_MB_2U_LIB.S9S_MB_2U(SCH_1):RST_RTCRST_N
    1  PU_FLASH_SECURITY_STRAP     A1  @S9S_MB_2U_LIB.S9S_MB_2U(SCH_1):PU_FLASH_SECURITY_STRAP
    2  PD_RST_RTCRST_N     A2  @S9S_MB_2U_LIB.S9S_MB_2U(SCH_1):PD_RST_RTCRST_N
    4  PD_PASSWORD_CLEAR     A4  @S9S_MB_2U_LIB.S9S_MB_2U(SCH_1):PD_PASSWORD_CLEAR
    3  PD_ME_RCVR_N      A3  @S9S_MB_2U_LIB.S9S_MB_2U(SCH_1):PD_ME_RCVR_N
    5  FM_PASSWORD_CLEAR_N     B4  @S9S_MB_2U_LIB.S9S_MB_2U(SCH_1):FM_PASSWORD_CLEAR_N
    6  FM_ME_RCVR_N      B3  @S9S_MB_2U_LIB.S9S_MB_2U(SCH_1):FM_ME_RCVR_N
    8  FM_FLASH_SECURITY_STRAP     B1  @S9S_MB_2U_LIB.S9S_MB_2U(SCH_1):FM_FLASH_SECURITY_STRAP

SOCKET4677_AZIFS054P001C01  I8   U1     [SOCKET4677_AZIFS054P001C01-SOCA]
  E39  GND            VSS1271  @S9S_MB_2U_LIB.S9S_MB_2U(SCH_1):GND
   E5  GND            VSS1125  @S9S_MB_2U_LIB.S9S_MB_2U(SCH_1):GND
  D83  GND            VSS907  @S9S_MB_2U_LIB.S9S_MB_2U(SCH_1):GND
  D81  GND            VSS906  @S9S_MB_2U_LIB.S9S_MB_2U(SCH_1):GND
  D71  GND            VSS902  @S9S_MB_2U_LIB.S9S_MB_2U(SCH_1):GND
  D69  GND            VSS901  @S9S_MB_2U_LIB.S9S_MB_2U(SCH_1):GND
  D61  GND            VSS900  @S9S_MB_2U_LIB.S9S_MB_2U(SCH_1):GND
   D6  GND            VSS899  @S9S_MB_2U_LIB.S9S_MB_2U(SCH_1):GND
  D59  GND            VSS898  @S9S_MB_2U_LIB.S9S_MB_2U(SCH_1):GND
  D57  GND            VSS897  @S9S_MB_2U_LIB.S9S_MB_2U(SCH_1):GND
  D55  GND            VSS896  @S9S_MB_2U_LIB.S9S_MB_2U(SCH_1):GND
  D53  GND            VSS895  @S9S_MB_2U_LIB.S9S_MB_2U(SCH_1):GND
  D51  GND            VSS892  @S9S_MB_2U_LIB.S9S_MB_2U(SCH_1):GND
  D49  GND            VSS891  @S9S_MB_2U_LIB.S9S_MB_2U(SCH_1):GND
  D47  GND            VSS889  @S9S_MB_2U_LIB.S9S_MB_2U(SCH_1):GND
  D44  GND            VSS888  @S9S_MB_2U_LIB.S9S_MB_2U(SCH_1):GND
  D42  GND            VSS886  @S9S_MB_2U_LIB.S9S_MB_2U(SCH_1):GND
  D40  GND            VSS885  @S9S_MB_2U_LIB.S9S_MB_2U(SCH_1):GND
  D38  GND            VSS884  @S9S_MB_2U_LIB.S9S_MB_2U(SCH_1):GND
  D36  GND            VSS881  @S9S_MB_2U_LIB.S9S_MB_2U(SCH_1):GND
  D34  GND            VSS879  @S9S_MB_2U_LIB.S9S_MB_2U(SCH_1):GND
  D32  GND            VSS878  @S9S_MB_2U_LIB.S9S_MB_2U(SCH_1):GND
  D30  GND            VSS877  @S9S_MB_2U_LIB.S9S_MB_2U(SCH_1):GND
  D28  GND            VSS876  @S9S_MB_2U_LIB.S9S_MB_2U(SCH_1):GND
  D26  GND            VSS875  @S9S_MB_2U_LIB.S9S_MB_2U(SCH_1):GND
  D24  GND            VSS874  @S9S_MB_2U_LIB.S9S_MB_2U(SCH_1):GND
  D22  GND            VSS873  @S9S_MB_2U_LIB.S9S_MB_2U(SCH_1):GND
  D20  GND            VSS871  @S9S_MB_2U_LIB.S9S_MB_2U(SCH_1):GND
  D18  GND            VSS869  @S9S_MB_2U_LIB.S9S_MB_2U(SCH_1):GND
  D16  GND            VSS868  @S9S_MB_2U_LIB.S9S_MB_2U(SCH_1):GND
  D14  GND            VSS866  @S9S_MB_2U_LIB.S9S_MB_2U(SCH_1):GND
  D12  GND            VSS865  @S9S_MB_2U_LIB.S9S_MB_2U(SCH_1):GND
  D10  GND            VSS864  @S9S_MB_2U_LIB.S9S_MB_2U(SCH_1):GND
   D8  GND            VSS663  @S9S_MB_2U_LIB.S9S_MB_2U(SCH_1):GND
  D79  GND            VSS662  @S9S_MB_2U_LIB.S9S_MB_2U(SCH_1):GND
  D67  GND            VSS659  @S9S_MB_2U_LIB.S9S_MB_2U(SCH_1):GND
  D65  GND            VSS658  @S9S_MB_2U_LIB.S9S_MB_2U(SCH_1):GND
  D63  GND            VSS657  @S9S_MB_2U_LIB.S9S_MB_2U(SCH_1):GND
  C86  GND            VSS619  @S9S_MB_2U_LIB.S9S_MB_2U(SCH_1):GND
  C82  GND            VSS618  @S9S_MB_2U_LIB.S9S_MB_2U(SCH_1):GND
  C80  GND            VSS617  @S9S_MB_2U_LIB.S9S_MB_2U(SCH_1):GND
  C78  GND            VSS616  @S9S_MB_2U_LIB.S9S_MB_2U(SCH_1):GND
  C74  GND            VSS615  @S9S_MB_2U_LIB.S9S_MB_2U(SCH_1):GND
  C72  GND            VSS614  @S9S_MB_2U_LIB.S9S_MB_2U(SCH_1):GND
  C52  GND            VSS613  @S9S_MB_2U_LIB.S9S_MB_2U(SCH_1):GND
   C5  GND            VSS612  @S9S_MB_2U_LIB.S9S_MB_2U(SCH_1):GND
  C45  GND            VSS610  @S9S_MB_2U_LIB.S9S_MB_2U(SCH_1):GND
  C39  GND            VSS609  @S9S_MB_2U_LIB.S9S_MB_2U(SCH_1):GND
  B87  GND            VSS392  @S9S_MB_2U_LIB.S9S_MB_2U(SCH_1):GND
  B83  GND            VSS391  @S9S_MB_2U_LIB.S9S_MB_2U(SCH_1):GND
  B75  GND            VSS390  @S9S_MB_2U_LIB.S9S_MB_2U(SCH_1):GND
  B67  GND            VSS389  @S9S_MB_2U_LIB.S9S_MB_2U(SCH_1):GND
  B61  GND            VSS388  @S9S_MB_2U_LIB.S9S_MB_2U(SCH_1):GND
   B6  GND            VSS387  @S9S_MB_2U_LIB.S9S_MB_2U(SCH_1):GND
  B55  GND            VSS386  @S9S_MB_2U_LIB.S9S_MB_2U(SCH_1):GND
  B49  GND            VSS385  @S9S_MB_2U_LIB.S9S_MB_2U(SCH_1):GND
  B42  GND            VSS384  @S9S_MB_2U_LIB.S9S_MB_2U(SCH_1):GND
  B36  GND            VSS382  @S9S_MB_2U_LIB.S9S_MB_2U(SCH_1):GND
  B30  GND            VSS381  @S9S_MB_2U_LIB.S9S_MB_2U(SCH_1):GND
  B24  GND            VSS380  @S9S_MB_2U_LIB.S9S_MB_2U(SCH_1):GND
  B18  GND            VSS379  @S9S_MB_2U_LIB.S9S_MB_2U(SCH_1):GND
  B12  GND            VSS378  @S9S_MB_2U_LIB.S9S_MB_2U(SCH_1):GND
  A62  GND            VSS16  @S9S_MB_2U_LIB.S9S_MB_2U(SCH_1):GND
  A60  GND            VSS15  @S9S_MB_2U_LIB.S9S_MB_2U(SCH_1):GND
  A56  GND            VSS14  @S9S_MB_2U_LIB.S9S_MB_2U(SCH_1):GND
  A54  GND            VSS13  @S9S_MB_2U_LIB.S9S_MB_2U(SCH_1):GND
  A50  GND            VSS12  @S9S_MB_2U_LIB.S9S_MB_2U(SCH_1):GND
  A41  GND            VSS11  @S9S_MB_2U_LIB.S9S_MB_2U(SCH_1):GND
  A37  GND            VSS10  @S9S_MB_2U_LIB.S9S_MB_2U(SCH_1):GND
  A35  GND             VSS9  @S9S_MB_2U_LIB.S9S_MB_2U(SCH_1):GND
  A31  GND             VSS8  @S9S_MB_2U_LIB.S9S_MB_2U(SCH_1):GND
  A29  GND             VSS7  @S9S_MB_2U_LIB.S9S_MB_2U(SCH_1):GND
  A25  GND             VSS6  @S9S_MB_2U_LIB.S9S_MB_2U(SCH_1):GND
  A23  GND             VSS5  @S9S_MB_2U_LIB.S9S_MB_2U(SCH_1):GND
  A19  GND             VSS4  @S9S_MB_2U_LIB.S9S_MB_2U(SCH_1):GND
  A17  GND             VSS3  @S9S_MB_2U_LIB.S9S_MB_2U(SCH_1):GND
  A13  GND             VSS2  @S9S_MB_2U_LIB.S9S_MB_2U(SCH_1):GND
  A11  GND             VSS1  @S9S_MB_2U_LIB.S9S_MB_2U(SCH_1):GND

SOCKET4677_AZIFS054P001C01  I5   U1     [SOCKET4677_AZIFS054P001C01-SOCA]
  N70  GND            VSS1695  @S9S_MB_2U_LIB.S9S_MB_2U(SCH_1):GND
  N58  GND            VSS1694  @S9S_MB_2U_LIB.S9S_MB_2U(SCH_1):GND
  N52  GND            VSS1693  @S9S_MB_2U_LIB.S9S_MB_2U(SCH_1):GND
  N45  GND            VSS1692  @S9S_MB_2U_LIB.S9S_MB_2U(SCH_1):GND
  N33  GND            VSS1691  @S9S_MB_2U_LIB.S9S_MB_2U(SCH_1):GND
  N27  GND            VSS1689  @S9S_MB_2U_LIB.S9S_MB_2U(SCH_1):GND
  N15  GND            VSS1688  @S9S_MB_2U_LIB.S9S_MB_2U(SCH_1):GND
  M83  GND            VSS1687  @S9S_MB_2U_LIB.S9S_MB_2U(SCH_1):GND
  M81  GND            VSS1686  @S9S_MB_2U_LIB.S9S_MB_2U(SCH_1):GND
  L78  GND            VSS1685  @S9S_MB_2U_LIB.S9S_MB_2U(SCH_1):GND
  L76  GND            VSS1684  @S9S_MB_2U_LIB.S9S_MB_2U(SCH_1):GND
  L74  GND            VSS1683  @S9S_MB_2U_LIB.S9S_MB_2U(SCH_1):GND
  L72  GND            VSS1682  @S9S_MB_2U_LIB.S9S_MB_2U(SCH_1):GND
  L68  GND            VSS1681  @S9S_MB_2U_LIB.S9S_MB_2U(SCH_1):GND
  L66  GND            VSS1680  @S9S_MB_2U_LIB.S9S_MB_2U(SCH_1):GND
  L64  GND            VSS1679  @S9S_MB_2U_LIB.S9S_MB_2U(SCH_1):GND
  L62  GND            VSS1678  @S9S_MB_2U_LIB.S9S_MB_2U(SCH_1):GND
  L60  GND            VSS1677  @S9S_MB_2U_LIB.S9S_MB_2U(SCH_1):GND
  L56  GND            VSS1676  @S9S_MB_2U_LIB.S9S_MB_2U(SCH_1):GND
  N64  GND            VSS1675  @S9S_MB_2U_LIB.S9S_MB_2U(SCH_1):GND
  L54  GND            VSS1674  @S9S_MB_2U_LIB.S9S_MB_2U(SCH_1):GND
  L52  GND            VSS1673  @S9S_MB_2U_LIB.S9S_MB_2U(SCH_1):GND
  L50  GND            VSS1672  @S9S_MB_2U_LIB.S9S_MB_2U(SCH_1):GND
   L5  GND            VSS1671  @S9S_MB_2U_LIB.S9S_MB_2U(SCH_1):GND
  L48  GND            VSS1670  @S9S_MB_2U_LIB.S9S_MB_2U(SCH_1):GND
  N39  GND            VSS1669  @S9S_MB_2U_LIB.S9S_MB_2U(SCH_1):GND
  L45  GND            VSS1668  @S9S_MB_2U_LIB.S9S_MB_2U(SCH_1):GND
  L43  GND            VSS1667  @S9S_MB_2U_LIB.S9S_MB_2U(SCH_1):GND
  L41  GND            VSS1666  @S9S_MB_2U_LIB.S9S_MB_2U(SCH_1):GND
  L39  GND            VSS1665  @S9S_MB_2U_LIB.S9S_MB_2U(SCH_1):GND
  N21  GND            VSS1664  @S9S_MB_2U_LIB.S9S_MB_2U(SCH_1):GND
  L37  GND            VSS1663  @S9S_MB_2U_LIB.S9S_MB_2U(SCH_1):GND
  L35  GND            VSS1662  @S9S_MB_2U_LIB.S9S_MB_2U(SCH_1):GND
  L33  GND            VSS1661  @S9S_MB_2U_LIB.S9S_MB_2U(SCH_1):GND
  L31  GND            VSS1660  @S9S_MB_2U_LIB.S9S_MB_2U(SCH_1):GND
  L29  GND            VSS1659  @S9S_MB_2U_LIB.S9S_MB_2U(SCH_1):GND
  L27  GND            VSS1658  @S9S_MB_2U_LIB.S9S_MB_2U(SCH_1):GND
   M8  GND            VSS1657  @S9S_MB_2U_LIB.S9S_MB_2U(SCH_1):GND
  L25  GND            VSS1656  @S9S_MB_2U_LIB.S9S_MB_2U(SCH_1):GND
  L23  GND            VSS1655  @S9S_MB_2U_LIB.S9S_MB_2U(SCH_1):GND
  M49  GND            VSS1654  @S9S_MB_2U_LIB.S9S_MB_2U(SCH_1):GND
  M42  GND            VSS1653  @S9S_MB_2U_LIB.S9S_MB_2U(SCH_1):GND
   M4  GND            VSS1652  @S9S_MB_2U_LIB.S9S_MB_2U(SCH_1):GND
  L21  GND            VSS1651  @S9S_MB_2U_LIB.S9S_MB_2U(SCH_1):GND
  L17  GND            VSS1650  @S9S_MB_2U_LIB.S9S_MB_2U(SCH_1):GND
  M12  GND            VSS1649  @S9S_MB_2U_LIB.S9S_MB_2U(SCH_1):GND
  L90  GND            VSS1648  @S9S_MB_2U_LIB.S9S_MB_2U(SCH_1):GND
   L9  GND            VSS1647  @S9S_MB_2U_LIB.S9S_MB_2U(SCH_1):GND
  L88  GND            VSS1646  @S9S_MB_2U_LIB.S9S_MB_2U(SCH_1):GND
  L15  GND            VSS1645  @S9S_MB_2U_LIB.S9S_MB_2U(SCH_1):GND
  L13  GND            VSS1644  @S9S_MB_2U_LIB.S9S_MB_2U(SCH_1):GND
  K85  GND            VSS1643  @S9S_MB_2U_LIB.S9S_MB_2U(SCH_1):GND
  K83  GND            VSS1642  @S9S_MB_2U_LIB.S9S_MB_2U(SCH_1):GND
   K8  GND            VSS1641  @S9S_MB_2U_LIB.S9S_MB_2U(SCH_1):GND
  L70  GND            VSS1640  @S9S_MB_2U_LIB.S9S_MB_2U(SCH_1):GND
  K77  GND            VSS1639  @S9S_MB_2U_LIB.S9S_MB_2U(SCH_1):GND
  J86  GND            VSS1638  @S9S_MB_2U_LIB.S9S_MB_2U(SCH_1):GND
  J84  GND            VSS1637  @S9S_MB_2U_LIB.S9S_MB_2U(SCH_1):GND
  J78  GND            VSS1636  @S9S_MB_2U_LIB.S9S_MB_2U(SCH_1):GND
  J76  GND            VSS1635  @S9S_MB_2U_LIB.S9S_MB_2U(SCH_1):GND
  L58  GND            VSS1634  @S9S_MB_2U_LIB.S9S_MB_2U(SCH_1):GND
  J58  GND            VSS1633  @S9S_MB_2U_LIB.S9S_MB_2U(SCH_1):GND
  J52  GND            VSS1632  @S9S_MB_2U_LIB.S9S_MB_2U(SCH_1):GND
  J45  GND            VSS1631  @S9S_MB_2U_LIB.S9S_MB_2U(SCH_1):GND
  J33  GND            VSS1630  @S9S_MB_2U_LIB.S9S_MB_2U(SCH_1):GND
  J27  GND            VSS1629  @S9S_MB_2U_LIB.S9S_MB_2U(SCH_1):GND
  J15  GND            VSS1628  @S9S_MB_2U_LIB.S9S_MB_2U(SCH_1):GND
  H81  GND            VSS1627  @S9S_MB_2U_LIB.S9S_MB_2U(SCH_1):GND
   H8  GND            VSS1626  @S9S_MB_2U_LIB.S9S_MB_2U(SCH_1):GND
  H79  GND            VSS1625  @S9S_MB_2U_LIB.S9S_MB_2U(SCH_1):GND
  H71  GND            VSS1624  @S9S_MB_2U_LIB.S9S_MB_2U(SCH_1):GND
  H69  GND            VSS1623  @S9S_MB_2U_LIB.S9S_MB_2U(SCH_1):GND
  H63  GND            VSS1622  @S9S_MB_2U_LIB.S9S_MB_2U(SCH_1):GND
   H6  GND            VSS1621  @S9S_MB_2U_LIB.S9S_MB_2U(SCH_1):GND
  H59  GND            VSS1620  @S9S_MB_2U_LIB.S9S_MB_2U(SCH_1):GND
  H53  GND            VSS1619  @S9S_MB_2U_LIB.S9S_MB_2U(SCH_1):GND
  H47  GND            VSS1618  @S9S_MB_2U_LIB.S9S_MB_2U(SCH_1):GND
  H44  GND            VSS1617  @S9S_MB_2U_LIB.S9S_MB_2U(SCH_1):GND
  H40  GND            VSS1616  @S9S_MB_2U_LIB.S9S_MB_2U(SCH_1):GND
   H4  GND            VSS1615  @S9S_MB_2U_LIB.S9S_MB_2U(SCH_1):GND
  L19  GND            VSS1614  @S9S_MB_2U_LIB.S9S_MB_2U(SCH_1):GND
  H38  GND            VSS1613  @S9S_MB_2U_LIB.S9S_MB_2U(SCH_1):GND
  H34  GND            VSS1612  @S9S_MB_2U_LIB.S9S_MB_2U(SCH_1):GND
  H32  GND            VSS1611  @S9S_MB_2U_LIB.S9S_MB_2U(SCH_1):GND
  H28  GND            VSS1610  @S9S_MB_2U_LIB.S9S_MB_2U(SCH_1):GND
  H26  GND            VSS1609  @S9S_MB_2U_LIB.S9S_MB_2U(SCH_1):GND
  H22  GND            VSS1608  @S9S_MB_2U_LIB.S9S_MB_2U(SCH_1):GND
  H20  GND            VSS1607  @S9S_MB_2U_LIB.S9S_MB_2U(SCH_1):GND
  H16  GND            VSS1606  @S9S_MB_2U_LIB.S9S_MB_2U(SCH_1):GND
  H10  GND            VSS1605  @S9S_MB_2U_LIB.S9S_MB_2U(SCH_1):GND
  G90  GND            VSS1604  @S9S_MB_2U_LIB.S9S_MB_2U(SCH_1):GND
  K49  GND            VSS1603  @S9S_MB_2U_LIB.S9S_MB_2U(SCH_1):GND
  K42  GND            VSS1602  @S9S_MB_2U_LIB.S9S_MB_2U(SCH_1):GND
  G88  GND            VSS1601  @S9S_MB_2U_LIB.S9S_MB_2U(SCH_1):GND
  G84  GND            VSS1600  @S9S_MB_2U_LIB.S9S_MB_2U(SCH_1):GND
   K2  GND            VSS1599  @S9S_MB_2U_LIB.S9S_MB_2U(SCH_1):GND
  K14  GND            VSS1598  @S9S_MB_2U_LIB.S9S_MB_2U(SCH_1):GND
  K12  GND            VSS1597  @S9S_MB_2U_LIB.S9S_MB_2U(SCH_1):GND
   J9  GND            VSS1596  @S9S_MB_2U_LIB.S9S_MB_2U(SCH_1):GND
  J88  GND            VSS1595  @S9S_MB_2U_LIB.S9S_MB_2U(SCH_1):GND
  G72  GND            VSS1594  @S9S_MB_2U_LIB.S9S_MB_2U(SCH_1):GND
  G62  GND            VSS1593  @S9S_MB_2U_LIB.S9S_MB_2U(SCH_1):GND
  G56  GND            VSS1592  @S9S_MB_2U_LIB.S9S_MB_2U(SCH_1):GND
  G54  GND            VSS1591  @S9S_MB_2U_LIB.S9S_MB_2U(SCH_1):GND
  G50  GND            VSS1590  @S9S_MB_2U_LIB.S9S_MB_2U(SCH_1):GND
  J70  GND            VSS1589  @S9S_MB_2U_LIB.S9S_MB_2U(SCH_1):GND
  G43  GND            VSS1588  @S9S_MB_2U_LIB.S9S_MB_2U(SCH_1):GND
  J64  GND            VSS1587  @S9S_MB_2U_LIB.S9S_MB_2U(SCH_1):GND
  G41  GND            VSS1586  @S9S_MB_2U_LIB.S9S_MB_2U(SCH_1):GND
  G37  GND            VSS1585  @S9S_MB_2U_LIB.S9S_MB_2U(SCH_1):GND
  G31  GND            VSS1584  @S9S_MB_2U_LIB.S9S_MB_2U(SCH_1):GND
  G29  GND            VSS1583  @S9S_MB_2U_LIB.S9S_MB_2U(SCH_1):GND
   J5  GND            VSS1582  @S9S_MB_2U_LIB.S9S_MB_2U(SCH_1):GND
  G23  GND            VSS1581  @S9S_MB_2U_LIB.S9S_MB_2U(SCH_1):GND
  J39  GND            VSS1580  @S9S_MB_2U_LIB.S9S_MB_2U(SCH_1):GND
  G19  GND            VSS1579  @S9S_MB_2U_LIB.S9S_MB_2U(SCH_1):GND
  G13  GND            VSS1578  @S9S_MB_2U_LIB.S9S_MB_2U(SCH_1):GND
  F89  GND            VSS1577  @S9S_MB_2U_LIB.S9S_MB_2U(SCH_1):GND
  F83  GND            VSS1576  @S9S_MB_2U_LIB.S9S_MB_2U(SCH_1):GND
  J21  GND            VSS1575  @S9S_MB_2U_LIB.S9S_MB_2U(SCH_1):GND
  F49  GND            VSS1574  @S9S_MB_2U_LIB.S9S_MB_2U(SCH_1):GND
   F4  GND            VSS1573  @S9S_MB_2U_LIB.S9S_MB_2U(SCH_1):GND
  F36  GND            VSS1572  @S9S_MB_2U_LIB.S9S_MB_2U(SCH_1):GND
  F30  GND            VSS1571  @S9S_MB_2U_LIB.S9S_MB_2U(SCH_1):GND
  F24  GND            VSS1570  @S9S_MB_2U_LIB.S9S_MB_2U(SCH_1):GND
  H75  GND            VSS1567  @S9S_MB_2U_LIB.S9S_MB_2U(SCH_1):GND
  H65  GND            VSS1564  @S9S_MB_2U_LIB.S9S_MB_2U(SCH_1):GND
  H57  GND            VSS1560  @S9S_MB_2U_LIB.S9S_MB_2U(SCH_1):GND
  H51  GND            VSS1558  @S9S_MB_2U_LIB.S9S_MB_2U(SCH_1):GND
   H2  GND            VSS1546  @S9S_MB_2U_LIB.S9S_MB_2U(SCH_1):GND
  H14  GND            VSS1544  @S9S_MB_2U_LIB.S9S_MB_2U(SCH_1):GND
  G74  GND            VSS1538  @S9S_MB_2U_LIB.S9S_MB_2U(SCH_1):GND
   G7  GND            VSS1536  @S9S_MB_2U_LIB.S9S_MB_2U(SCH_1):GND
  G68  GND            VSS1535  @S9S_MB_2U_LIB.S9S_MB_2U(SCH_1):GND
  G66  GND            VSS1534  @S9S_MB_2U_LIB.S9S_MB_2U(SCH_1):GND
  G60  GND            VSS1532  @S9S_MB_2U_LIB.S9S_MB_2U(SCH_1):GND
  G48  GND            VSS1527  @S9S_MB_2U_LIB.S9S_MB_2U(SCH_1):GND
  G35  GND            VSS1523  @S9S_MB_2U_LIB.S9S_MB_2U(SCH_1):GND
   G3  GND            VSS1521  @S9S_MB_2U_LIB.S9S_MB_2U(SCH_1):GND
  G25  GND            VSS1519  @S9S_MB_2U_LIB.S9S_MB_2U(SCH_1):GND
  G17  GND            VSS1516  @S9S_MB_2U_LIB.S9S_MB_2U(SCH_1):GND
  G11  GND            VSS1514  @S9S_MB_2U_LIB.S9S_MB_2U(SCH_1):GND
  F79  GND            VSS1511  @S9S_MB_2U_LIB.S9S_MB_2U(SCH_1):GND
  F73  GND            VSS1510  @S9S_MB_2U_LIB.S9S_MB_2U(SCH_1):GND
  F67  GND            VSS1509  @S9S_MB_2U_LIB.S9S_MB_2U(SCH_1):GND
  F61  GND            VSS1508  @S9S_MB_2U_LIB.S9S_MB_2U(SCH_1):GND
   F6  GND            VSS1507  @S9S_MB_2U_LIB.S9S_MB_2U(SCH_1):GND
  F55  GND            VSS1504  @S9S_MB_2U_LIB.S9S_MB_2U(SCH_1):GND
  F42  GND            VSS1502  @S9S_MB_2U_LIB.S9S_MB_2U(SCH_1):GND
  F18  GND            VSS1495  @S9S_MB_2U_LIB.S9S_MB_2U(SCH_1):GND
  F12  GND            VSS1494  @S9S_MB_2U_LIB.S9S_MB_2U(SCH_1):GND
  E86  GND            VSS1273  @S9S_MB_2U_LIB.S9S_MB_2U(SCH_1):GND
  E76  GND            VSS1272  @S9S_MB_2U_LIB.S9S_MB_2U(SCH_1):GND
  E78  GND            VSS1131  @S9S_MB_2U_LIB.S9S_MB_2U(SCH_1):GND
  E74  GND            VSS1129  @S9S_MB_2U_LIB.S9S_MB_2U(SCH_1):GND
  E52  GND            VSS1126  @S9S_MB_2U_LIB.S9S_MB_2U(SCH_1):GND

SOCKET4677_AZIFS054P001C01  I2   U1     [SOCKET4677_AZIFS054P001C01-SOCA]
  Y73  GND            VSS1833  @S9S_MB_2U_LIB.S9S_MB_2U(SCH_1):GND
   Y8  GND            VSS1832  @S9S_MB_2U_LIB.S9S_MB_2U(SCH_1):GND
  Y55  GND            VSS1831  @S9S_MB_2U_LIB.S9S_MB_2U(SCH_1):GND
  Y49  GND            VSS1830  @S9S_MB_2U_LIB.S9S_MB_2U(SCH_1):GND
  Y67  GND            VSS1829  @S9S_MB_2U_LIB.S9S_MB_2U(SCH_1):GND
  Y61  GND            VSS1828  @S9S_MB_2U_LIB.S9S_MB_2U(SCH_1):GND
  Y42  GND            VSS1827  @S9S_MB_2U_LIB.S9S_MB_2U(SCH_1):GND
   Y4  GND            VSS1826  @S9S_MB_2U_LIB.S9S_MB_2U(SCH_1):GND
  Y36  GND            VSS1825  @S9S_MB_2U_LIB.S9S_MB_2U(SCH_1):GND
  Y30  GND            VSS1824  @S9S_MB_2U_LIB.S9S_MB_2U(SCH_1):GND
  Y24  GND            VSS1823  @S9S_MB_2U_LIB.S9S_MB_2U(SCH_1):GND
  Y18  GND            VSS1822  @S9S_MB_2U_LIB.S9S_MB_2U(SCH_1):GND
  Y16  GND            VSS1821  @S9S_MB_2U_LIB.S9S_MB_2U(SCH_1):GND
  Y12  GND            VSS1820  @S9S_MB_2U_LIB.S9S_MB_2U(SCH_1):GND
   W9  GND            VSS1819  @S9S_MB_2U_LIB.S9S_MB_2U(SCH_1):GND
  W88  GND            VSS1818  @S9S_MB_2U_LIB.S9S_MB_2U(SCH_1):GND
  W84  GND            VSS1817  @S9S_MB_2U_LIB.S9S_MB_2U(SCH_1):GND
  W39  GND            VSS1816  @S9S_MB_2U_LIB.S9S_MB_2U(SCH_1):GND
  W52  GND            VSS1815  @S9S_MB_2U_LIB.S9S_MB_2U(SCH_1):GND
   W5  GND            VSS1814  @S9S_MB_2U_LIB.S9S_MB_2U(SCH_1):GND
  V87  GND            VSS1813  @S9S_MB_2U_LIB.S9S_MB_2U(SCH_1):GND
   V8  GND            VSS1812  @S9S_MB_2U_LIB.S9S_MB_2U(SCH_1):GND
  V79  GND            VSS1811  @S9S_MB_2U_LIB.S9S_MB_2U(SCH_1):GND
  V77  GND            VSS1810  @S9S_MB_2U_LIB.S9S_MB_2U(SCH_1):GND
  W13  GND            VSS1809  @S9S_MB_2U_LIB.S9S_MB_2U(SCH_1):GND
   W1  GND            VSS1808  @S9S_MB_2U_LIB.S9S_MB_2U(SCH_1):GND
  V91  GND            VSS1807  @S9S_MB_2U_LIB.S9S_MB_2U(SCH_1):GND
  V75  GND            VSS1806  @S9S_MB_2U_LIB.S9S_MB_2U(SCH_1):GND
  V69  GND            VSS1805  @S9S_MB_2U_LIB.S9S_MB_2U(SCH_1):GND
  V67  GND            VSS1804  @S9S_MB_2U_LIB.S9S_MB_2U(SCH_1):GND
  V65  GND            VSS1803  @S9S_MB_2U_LIB.S9S_MB_2U(SCH_1):GND
  V63  GND            VSS1802  @S9S_MB_2U_LIB.S9S_MB_2U(SCH_1):GND
  V73  GND            VSS1801  @S9S_MB_2U_LIB.S9S_MB_2U(SCH_1):GND
  V71  GND            VSS1800  @S9S_MB_2U_LIB.S9S_MB_2U(SCH_1):GND
  V61  GND            VSS1799  @S9S_MB_2U_LIB.S9S_MB_2U(SCH_1):GND
  V59  GND            VSS1798  @S9S_MB_2U_LIB.S9S_MB_2U(SCH_1):GND
  V57  GND            VSS1797  @S9S_MB_2U_LIB.S9S_MB_2U(SCH_1):GND
  V55  GND            VSS1796  @S9S_MB_2U_LIB.S9S_MB_2U(SCH_1):GND
  V53  GND            VSS1795  @S9S_MB_2U_LIB.S9S_MB_2U(SCH_1):GND
  V51  GND            VSS1794  @S9S_MB_2U_LIB.S9S_MB_2U(SCH_1):GND
  V47  GND            VSS1793  @S9S_MB_2U_LIB.S9S_MB_2U(SCH_1):GND
  V44  GND            VSS1792  @S9S_MB_2U_LIB.S9S_MB_2U(SCH_1):GND
  V42  GND            VSS1791  @S9S_MB_2U_LIB.S9S_MB_2U(SCH_1):GND
  V40  GND            VSS1790  @S9S_MB_2U_LIB.S9S_MB_2U(SCH_1):GND
  V49  GND            VSS1789  @S9S_MB_2U_LIB.S9S_MB_2U(SCH_1):GND
   V4  GND            VSS1788  @S9S_MB_2U_LIB.S9S_MB_2U(SCH_1):GND
  V38  GND            VSS1787  @S9S_MB_2U_LIB.S9S_MB_2U(SCH_1):GND
  V36  GND            VSS1786  @S9S_MB_2U_LIB.S9S_MB_2U(SCH_1):GND
  V34  GND            VSS1785  @S9S_MB_2U_LIB.S9S_MB_2U(SCH_1):GND
  V32  GND            VSS1784  @S9S_MB_2U_LIB.S9S_MB_2U(SCH_1):GND
  V30  GND            VSS1783  @S9S_MB_2U_LIB.S9S_MB_2U(SCH_1):GND
  V28  GND            VSS1782  @S9S_MB_2U_LIB.S9S_MB_2U(SCH_1):GND
  V26  GND            VSS1781  @S9S_MB_2U_LIB.S9S_MB_2U(SCH_1):GND
  V24  GND            VSS1780  @S9S_MB_2U_LIB.S9S_MB_2U(SCH_1):GND
  V22  GND            VSS1779  @S9S_MB_2U_LIB.S9S_MB_2U(SCH_1):GND
  V20  GND            VSS1778  @S9S_MB_2U_LIB.S9S_MB_2U(SCH_1):GND
  V18  GND            VSS1777  @S9S_MB_2U_LIB.S9S_MB_2U(SCH_1):GND
  V16  GND            VSS1776  @S9S_MB_2U_LIB.S9S_MB_2U(SCH_1):GND
  V12  GND            VSS1775  @S9S_MB_2U_LIB.S9S_MB_2U(SCH_1):GND
  U88  GND            VSS1774  @S9S_MB_2U_LIB.S9S_MB_2U(SCH_1):GND
  U84  GND            VSS1773  @S9S_MB_2U_LIB.S9S_MB_2U(SCH_1):GND
  U82  GND            VSS1772  @S9S_MB_2U_LIB.S9S_MB_2U(SCH_1):GND
  U39  GND            VSS1771  @S9S_MB_2U_LIB.S9S_MB_2U(SCH_1):GND
  T83  GND            VSS1770  @S9S_MB_2U_LIB.S9S_MB_2U(SCH_1):GND
   T8  GND            VSS1769  @S9S_MB_2U_LIB.S9S_MB_2U(SCH_1):GND
  T79  GND            VSS1768  @S9S_MB_2U_LIB.S9S_MB_2U(SCH_1):GND
  T73  GND            VSS1767  @S9S_MB_2U_LIB.S9S_MB_2U(SCH_1):GND
  U52  GND            VSS1766  @S9S_MB_2U_LIB.S9S_MB_2U(SCH_1):GND
  T67  GND            VSS1765  @S9S_MB_2U_LIB.S9S_MB_2U(SCH_1):GND
  T61  GND            VSS1764  @S9S_MB_2U_LIB.S9S_MB_2U(SCH_1):GND
  T42  GND            VSS1763  @S9S_MB_2U_LIB.S9S_MB_2U(SCH_1):GND
   T4  GND            VSS1762  @S9S_MB_2U_LIB.S9S_MB_2U(SCH_1):GND
  T30  GND            VSS1761  @S9S_MB_2U_LIB.S9S_MB_2U(SCH_1):GND
  T24  GND            VSS1760  @S9S_MB_2U_LIB.S9S_MB_2U(SCH_1):GND
   R9  GND            VSS1759  @S9S_MB_2U_LIB.S9S_MB_2U(SCH_1):GND
  R88  GND            VSS1758  @S9S_MB_2U_LIB.S9S_MB_2U(SCH_1):GND
  R84  GND            VSS1757  @S9S_MB_2U_LIB.S9S_MB_2U(SCH_1):GND
  R78  GND            VSS1756  @S9S_MB_2U_LIB.S9S_MB_2U(SCH_1):GND
  R74  GND            VSS1755  @S9S_MB_2U_LIB.S9S_MB_2U(SCH_1):GND
  R72  GND            VSS1754  @S9S_MB_2U_LIB.S9S_MB_2U(SCH_1):GND
  R68  GND            VSS1753  @S9S_MB_2U_LIB.S9S_MB_2U(SCH_1):GND
  R62  GND            VSS1752  @S9S_MB_2U_LIB.S9S_MB_2U(SCH_1):GND
  R56  GND            VSS1751  @S9S_MB_2U_LIB.S9S_MB_2U(SCH_1):GND
  T55  GND            VSS1750  @S9S_MB_2U_LIB.S9S_MB_2U(SCH_1):GND
  T49  GND            VSS1749  @S9S_MB_2U_LIB.S9S_MB_2U(SCH_1):GND
  R54  GND            VSS1748  @S9S_MB_2U_LIB.S9S_MB_2U(SCH_1):GND
  R50  GND            VSS1747  @S9S_MB_2U_LIB.S9S_MB_2U(SCH_1):GND
  T36  GND            VSS1746  @S9S_MB_2U_LIB.S9S_MB_2U(SCH_1):GND
   R5  GND            VSS1745  @S9S_MB_2U_LIB.S9S_MB_2U(SCH_1):GND
  R43  GND            VSS1744  @S9S_MB_2U_LIB.S9S_MB_2U(SCH_1):GND
  R41  GND            VSS1743  @S9S_MB_2U_LIB.S9S_MB_2U(SCH_1):GND
  R37  GND            VSS1742  @S9S_MB_2U_LIB.S9S_MB_2U(SCH_1):GND
  T18  GND            VSS1741  @S9S_MB_2U_LIB.S9S_MB_2U(SCH_1):GND
  T16  GND            VSS1740  @S9S_MB_2U_LIB.S9S_MB_2U(SCH_1):GND
  T12  GND            VSS1739  @S9S_MB_2U_LIB.S9S_MB_2U(SCH_1):GND
  R35  GND            VSS1738  @S9S_MB_2U_LIB.S9S_MB_2U(SCH_1):GND
  R31  GND            VSS1737  @S9S_MB_2U_LIB.S9S_MB_2U(SCH_1):GND
  R29  GND            VSS1736  @S9S_MB_2U_LIB.S9S_MB_2U(SCH_1):GND
  R25  GND            VSS1735  @S9S_MB_2U_LIB.S9S_MB_2U(SCH_1):GND
  R17  GND            VSS1734  @S9S_MB_2U_LIB.S9S_MB_2U(SCH_1):GND
  R13  GND            VSS1733  @S9S_MB_2U_LIB.S9S_MB_2U(SCH_1):GND
  P91  GND            VSS1732  @S9S_MB_2U_LIB.S9S_MB_2U(SCH_1):GND
  P87  GND            VSS1731  @S9S_MB_2U_LIB.S9S_MB_2U(SCH_1):GND
  R66  GND            VSS1730  @S9S_MB_2U_LIB.S9S_MB_2U(SCH_1):GND
   P8  GND            VSS1729  @S9S_MB_2U_LIB.S9S_MB_2U(SCH_1):GND
  R60  GND            VSS1728  @S9S_MB_2U_LIB.S9S_MB_2U(SCH_1):GND
  P77  GND            VSS1727  @S9S_MB_2U_LIB.S9S_MB_2U(SCH_1):GND
  P75  GND            VSS1726  @S9S_MB_2U_LIB.S9S_MB_2U(SCH_1):GND
  P69  GND            VSS1725  @S9S_MB_2U_LIB.S9S_MB_2U(SCH_1):GND
  P65  GND            VSS1724  @S9S_MB_2U_LIB.S9S_MB_2U(SCH_1):GND
  R48  GND            VSS1723  @S9S_MB_2U_LIB.S9S_MB_2U(SCH_1):GND
  P63  GND            VSS1722  @S9S_MB_2U_LIB.S9S_MB_2U(SCH_1):GND
  P59  GND            VSS1721  @S9S_MB_2U_LIB.S9S_MB_2U(SCH_1):GND
  P53  GND            VSS1720  @S9S_MB_2U_LIB.S9S_MB_2U(SCH_1):GND
  P47  GND            VSS1719  @S9S_MB_2U_LIB.S9S_MB_2U(SCH_1):GND
  P44  GND            VSS1718  @S9S_MB_2U_LIB.S9S_MB_2U(SCH_1):GND
  P40  GND            VSS1717  @S9S_MB_2U_LIB.S9S_MB_2U(SCH_1):GND
   P4  GND            VSS1716  @S9S_MB_2U_LIB.S9S_MB_2U(SCH_1):GND
  R23  GND            VSS1715  @S9S_MB_2U_LIB.S9S_MB_2U(SCH_1):GND
  R19  GND            VSS1714  @S9S_MB_2U_LIB.S9S_MB_2U(SCH_1):GND
  P38  GND            VSS1713  @S9S_MB_2U_LIB.S9S_MB_2U(SCH_1):GND
  P34  GND            VSS1712  @S9S_MB_2U_LIB.S9S_MB_2U(SCH_1):GND
   R1  GND            VSS1711  @S9S_MB_2U_LIB.S9S_MB_2U(SCH_1):GND
  P28  GND            VSS1710  @S9S_MB_2U_LIB.S9S_MB_2U(SCH_1):GND
  P26  GND            VSS1709  @S9S_MB_2U_LIB.S9S_MB_2U(SCH_1):GND
  P22  GND            VSS1708  @S9S_MB_2U_LIB.S9S_MB_2U(SCH_1):GND
  P20  GND            VSS1707  @S9S_MB_2U_LIB.S9S_MB_2U(SCH_1):GND
  P16  GND            VSS1706  @S9S_MB_2U_LIB.S9S_MB_2U(SCH_1):GND
  P12  GND            VSS1705  @S9S_MB_2U_LIB.S9S_MB_2U(SCH_1):GND
  P71  GND            VSS1704  @S9S_MB_2U_LIB.S9S_MB_2U(SCH_1):GND
  N88  GND            VSS1703  @S9S_MB_2U_LIB.S9S_MB_2U(SCH_1):GND
  N84  GND            VSS1702  @S9S_MB_2U_LIB.S9S_MB_2U(SCH_1):GND
  N82  GND            VSS1701  @S9S_MB_2U_LIB.S9S_MB_2U(SCH_1):GND
  N80  GND            VSS1700  @S9S_MB_2U_LIB.S9S_MB_2U(SCH_1):GND
  P57  GND            VSS1699  @S9S_MB_2U_LIB.S9S_MB_2U(SCH_1):GND
  N78  GND            VSS1698  @S9S_MB_2U_LIB.S9S_MB_2U(SCH_1):GND
  P51  GND            VSS1697  @S9S_MB_2U_LIB.S9S_MB_2U(SCH_1):GND
  N76  GND            VSS1696  @S9S_MB_2U_LIB.S9S_MB_2U(SCH_1):GND
  P32  GND            VSS1690  @S9S_MB_2U_LIB.S9S_MB_2U(SCH_1):GND
  AA80  GND            VSS37  @S9S_MB_2U_LIB.S9S_MB_2U(SCH_1):GND
  AA78  GND            VSS36  @S9S_MB_2U_LIB.S9S_MB_2U(SCH_1):GND
  AA74  GND            VSS35  @S9S_MB_2U_LIB.S9S_MB_2U(SCH_1):GND
  AA72  GND            VSS34  @S9S_MB_2U_LIB.S9S_MB_2U(SCH_1):GND
  AA68  GND            VSS33  @S9S_MB_2U_LIB.S9S_MB_2U(SCH_1):GND
  AA66  GND            VSS32  @S9S_MB_2U_LIB.S9S_MB_2U(SCH_1):GND
  AA62  GND            VSS31  @S9S_MB_2U_LIB.S9S_MB_2U(SCH_1):GND
  AA60  GND            VSS30  @S9S_MB_2U_LIB.S9S_MB_2U(SCH_1):GND
  AA56  GND            VSS29  @S9S_MB_2U_LIB.S9S_MB_2U(SCH_1):GND
  AA54  GND            VSS28  @S9S_MB_2U_LIB.S9S_MB_2U(SCH_1):GND
  AA50  GND            VSS27  @S9S_MB_2U_LIB.S9S_MB_2U(SCH_1):GND
  AA48  GND            VSS26  @S9S_MB_2U_LIB.S9S_MB_2U(SCH_1):GND
  AA43  GND            VSS25  @S9S_MB_2U_LIB.S9S_MB_2U(SCH_1):GND
  AA41  GND            VSS24  @S9S_MB_2U_LIB.S9S_MB_2U(SCH_1):GND
  AA37  GND            VSS23  @S9S_MB_2U_LIB.S9S_MB_2U(SCH_1):GND
  AA35  GND            VSS22  @S9S_MB_2U_LIB.S9S_MB_2U(SCH_1):GND
  AA31  GND            VSS21  @S9S_MB_2U_LIB.S9S_MB_2U(SCH_1):GND
  AA29  GND            VSS20  @S9S_MB_2U_LIB.S9S_MB_2U(SCH_1):GND
  AA25  GND            VSS19  @S9S_MB_2U_LIB.S9S_MB_2U(SCH_1):GND
  AA23  GND            VSS18  @S9S_MB_2U_LIB.S9S_MB_2U(SCH_1):GND
  AA19  GND            VSS17  @S9S_MB_2U_LIB.S9S_MB_2U(SCH_1):GND

SOCKET4677_AZIFS054P001C01  I8   U1     [SOCKET4677_AZIFS054P001C01-SOCA]
  AJ88  GND            VSS197  @S9S_MB_2U_LIB.S9S_MB_2U(SCH_1):GND
  AJ84  GND            VSS196  @S9S_MB_2U_LIB.S9S_MB_2U(SCH_1):GND
  AJ78  GND            VSS195  @S9S_MB_2U_LIB.S9S_MB_2U(SCH_1):GND
  AJ74  GND            VSS194  @S9S_MB_2U_LIB.S9S_MB_2U(SCH_1):GND
  AJ72  GND            VSS193  @S9S_MB_2U_LIB.S9S_MB_2U(SCH_1):GND
  AJ68  GND            VSS192  @S9S_MB_2U_LIB.S9S_MB_2U(SCH_1):GND
  AJ66  GND            VSS191  @S9S_MB_2U_LIB.S9S_MB_2U(SCH_1):GND
  AJ62  GND            VSS190  @S9S_MB_2U_LIB.S9S_MB_2U(SCH_1):GND
  AJ60  GND            VSS189  @S9S_MB_2U_LIB.S9S_MB_2U(SCH_1):GND
  AJ56  GND            VSS188  @S9S_MB_2U_LIB.S9S_MB_2U(SCH_1):GND
  AJ54  GND            VSS187  @S9S_MB_2U_LIB.S9S_MB_2U(SCH_1):GND
  AJ50  GND            VSS186  @S9S_MB_2U_LIB.S9S_MB_2U(SCH_1):GND
  AJ48  GND            VSS185  @S9S_MB_2U_LIB.S9S_MB_2U(SCH_1):GND
  AJ43  GND            VSS184  @S9S_MB_2U_LIB.S9S_MB_2U(SCH_1):GND
  AJ41  GND            VSS183  @S9S_MB_2U_LIB.S9S_MB_2U(SCH_1):GND
  AJ37  GND            VSS182  @S9S_MB_2U_LIB.S9S_MB_2U(SCH_1):GND
  AJ35  GND            VSS181  @S9S_MB_2U_LIB.S9S_MB_2U(SCH_1):GND
  AJ31  GND            VSS180  @S9S_MB_2U_LIB.S9S_MB_2U(SCH_1):GND
  AJ29  GND            VSS179  @S9S_MB_2U_LIB.S9S_MB_2U(SCH_1):GND
  AJ25  GND            VSS178  @S9S_MB_2U_LIB.S9S_MB_2U(SCH_1):GND
  AJ23  GND            VSS177  @S9S_MB_2U_LIB.S9S_MB_2U(SCH_1):GND
  AJ19  GND            VSS176  @S9S_MB_2U_LIB.S9S_MB_2U(SCH_1):GND
  AH83  GND            VSS175  @S9S_MB_2U_LIB.S9S_MB_2U(SCH_1):GND
  AH8  GND            VSS174  @S9S_MB_2U_LIB.S9S_MB_2U(SCH_1):GND
  AH79  GND            VSS173  @S9S_MB_2U_LIB.S9S_MB_2U(SCH_1):GND
  AH77  GND            VSS172  @S9S_MB_2U_LIB.S9S_MB_2U(SCH_1):GND
  AH75  GND            VSS171  @S9S_MB_2U_LIB.S9S_MB_2U(SCH_1):GND
  AH71  GND            VSS170  @S9S_MB_2U_LIB.S9S_MB_2U(SCH_1):GND
  AH69  GND            VSS169  @S9S_MB_2U_LIB.S9S_MB_2U(SCH_1):GND
  AH65  GND            VSS168  @S9S_MB_2U_LIB.S9S_MB_2U(SCH_1):GND
  AH63  GND            VSS167  @S9S_MB_2U_LIB.S9S_MB_2U(SCH_1):GND
  AH59  GND            VSS166  @S9S_MB_2U_LIB.S9S_MB_2U(SCH_1):GND
  AH57  GND            VSS165  @S9S_MB_2U_LIB.S9S_MB_2U(SCH_1):GND
  AH53  GND            VSS164  @S9S_MB_2U_LIB.S9S_MB_2U(SCH_1):GND
  AH51  GND            VSS163  @S9S_MB_2U_LIB.S9S_MB_2U(SCH_1):GND
  AH47  GND            VSS162  @S9S_MB_2U_LIB.S9S_MB_2U(SCH_1):GND
  AH44  GND            VSS161  @S9S_MB_2U_LIB.S9S_MB_2U(SCH_1):GND
  AH40  GND            VSS160  @S9S_MB_2U_LIB.S9S_MB_2U(SCH_1):GND
  AH4  GND            VSS159  @S9S_MB_2U_LIB.S9S_MB_2U(SCH_1):GND
  AH38  GND            VSS158  @S9S_MB_2U_LIB.S9S_MB_2U(SCH_1):GND
  AH34  GND            VSS157  @S9S_MB_2U_LIB.S9S_MB_2U(SCH_1):GND
  AH32  GND            VSS156  @S9S_MB_2U_LIB.S9S_MB_2U(SCH_1):GND
  AH28  GND            VSS155  @S9S_MB_2U_LIB.S9S_MB_2U(SCH_1):GND
  AH26  GND            VSS154  @S9S_MB_2U_LIB.S9S_MB_2U(SCH_1):GND
  AH22  GND            VSS153  @S9S_MB_2U_LIB.S9S_MB_2U(SCH_1):GND
  AH20  GND            VSS152  @S9S_MB_2U_LIB.S9S_MB_2U(SCH_1):GND
  AH16  GND            VSS151  @S9S_MB_2U_LIB.S9S_MB_2U(SCH_1):GND
  AH12  GND            VSS150  @S9S_MB_2U_LIB.S9S_MB_2U(SCH_1):GND
  AG9  GND            VSS149  @S9S_MB_2U_LIB.S9S_MB_2U(SCH_1):GND
  AG88  GND            VSS148  @S9S_MB_2U_LIB.S9S_MB_2U(SCH_1):GND
  AG84  GND            VSS147  @S9S_MB_2U_LIB.S9S_MB_2U(SCH_1):GND
  AG76  GND            VSS146  @S9S_MB_2U_LIB.S9S_MB_2U(SCH_1):GND
  AG70  GND            VSS145  @S9S_MB_2U_LIB.S9S_MB_2U(SCH_1):GND
  AG64  GND            VSS144  @S9S_MB_2U_LIB.S9S_MB_2U(SCH_1):GND
  AG58  GND            VSS143  @S9S_MB_2U_LIB.S9S_MB_2U(SCH_1):GND
  AG52  GND            VSS142  @S9S_MB_2U_LIB.S9S_MB_2U(SCH_1):GND
  AG5  GND            VSS141  @S9S_MB_2U_LIB.S9S_MB_2U(SCH_1):GND
  AG45  GND            VSS140  @S9S_MB_2U_LIB.S9S_MB_2U(SCH_1):GND
  AG39  GND            VSS139  @S9S_MB_2U_LIB.S9S_MB_2U(SCH_1):GND
  AG33  GND            VSS138  @S9S_MB_2U_LIB.S9S_MB_2U(SCH_1):GND
  AG27  GND            VSS137  @S9S_MB_2U_LIB.S9S_MB_2U(SCH_1):GND
  AG21  GND            VSS136  @S9S_MB_2U_LIB.S9S_MB_2U(SCH_1):GND
  AG13  GND            VSS135  @S9S_MB_2U_LIB.S9S_MB_2U(SCH_1):GND
  AG1  GND            VSS134  @S9S_MB_2U_LIB.S9S_MB_2U(SCH_1):GND
  AF91  GND            VSS133  @S9S_MB_2U_LIB.S9S_MB_2U(SCH_1):GND
  AF87  GND            VSS132  @S9S_MB_2U_LIB.S9S_MB_2U(SCH_1):GND
  AF81  GND            VSS131  @S9S_MB_2U_LIB.S9S_MB_2U(SCH_1):GND
  AF8  GND            VSS130  @S9S_MB_2U_LIB.S9S_MB_2U(SCH_1):GND
  AF42  GND            VSS129  @S9S_MB_2U_LIB.S9S_MB_2U(SCH_1):GND
  AF4  GND            VSS128  @S9S_MB_2U_LIB.S9S_MB_2U(SCH_1):GND
  AF16  GND            VSS127  @S9S_MB_2U_LIB.S9S_MB_2U(SCH_1):GND
  AF12  GND            VSS126  @S9S_MB_2U_LIB.S9S_MB_2U(SCH_1):GND
  AE88  GND            VSS125  @S9S_MB_2U_LIB.S9S_MB_2U(SCH_1):GND
  AE84  GND            VSS124  @S9S_MB_2U_LIB.S9S_MB_2U(SCH_1):GND
  AE78  GND            VSS123  @S9S_MB_2U_LIB.S9S_MB_2U(SCH_1):GND
  AE76  GND            VSS122  @S9S_MB_2U_LIB.S9S_MB_2U(SCH_1):GND
  AE74  GND            VSS121  @S9S_MB_2U_LIB.S9S_MB_2U(SCH_1):GND
  AE72  GND            VSS120  @S9S_MB_2U_LIB.S9S_MB_2U(SCH_1):GND
  AE70  GND            VSS119  @S9S_MB_2U_LIB.S9S_MB_2U(SCH_1):GND
  AE68  GND            VSS118  @S9S_MB_2U_LIB.S9S_MB_2U(SCH_1):GND
  AE66  GND            VSS117  @S9S_MB_2U_LIB.S9S_MB_2U(SCH_1):GND
  AE64  GND            VSS116  @S9S_MB_2U_LIB.S9S_MB_2U(SCH_1):GND
  AE62  GND            VSS115  @S9S_MB_2U_LIB.S9S_MB_2U(SCH_1):GND
  AE60  GND            VSS114  @S9S_MB_2U_LIB.S9S_MB_2U(SCH_1):GND
  AE58  GND            VSS113  @S9S_MB_2U_LIB.S9S_MB_2U(SCH_1):GND
  AE56  GND            VSS112  @S9S_MB_2U_LIB.S9S_MB_2U(SCH_1):GND
  AE54  GND            VSS111  @S9S_MB_2U_LIB.S9S_MB_2U(SCH_1):GND
  AE52  GND            VSS110  @S9S_MB_2U_LIB.S9S_MB_2U(SCH_1):GND
  AE50  GND            VSS109  @S9S_MB_2U_LIB.S9S_MB_2U(SCH_1):GND
  AE48  GND            VSS108  @S9S_MB_2U_LIB.S9S_MB_2U(SCH_1):GND
  AE45  GND            VSS107  @S9S_MB_2U_LIB.S9S_MB_2U(SCH_1):GND
  AE43  GND            VSS106  @S9S_MB_2U_LIB.S9S_MB_2U(SCH_1):GND
  AE41  GND            VSS105  @S9S_MB_2U_LIB.S9S_MB_2U(SCH_1):GND
  AE39  GND            VSS104  @S9S_MB_2U_LIB.S9S_MB_2U(SCH_1):GND
  AE37  GND            VSS103  @S9S_MB_2U_LIB.S9S_MB_2U(SCH_1):GND
  AE35  GND            VSS102  @S9S_MB_2U_LIB.S9S_MB_2U(SCH_1):GND
  AE33  GND            VSS101  @S9S_MB_2U_LIB.S9S_MB_2U(SCH_1):GND
  AE31  GND            VSS100  @S9S_MB_2U_LIB.S9S_MB_2U(SCH_1):GND
  AE29  GND            VSS99  @S9S_MB_2U_LIB.S9S_MB_2U(SCH_1):GND
  AE27  GND            VSS98  @S9S_MB_2U_LIB.S9S_MB_2U(SCH_1):GND
  AE25  GND            VSS97  @S9S_MB_2U_LIB.S9S_MB_2U(SCH_1):GND
  AE23  GND            VSS96  @S9S_MB_2U_LIB.S9S_MB_2U(SCH_1):GND
  AE21  GND            VSS95  @S9S_MB_2U_LIB.S9S_MB_2U(SCH_1):GND
  AE19  GND            VSS94  @S9S_MB_2U_LIB.S9S_MB_2U(SCH_1):GND
  AE17  GND            VSS93  @S9S_MB_2U_LIB.S9S_MB_2U(SCH_1):GND
  AD83  GND            VSS92  @S9S_MB_2U_LIB.S9S_MB_2U(SCH_1):GND
  AD8  GND            VSS91  @S9S_MB_2U_LIB.S9S_MB_2U(SCH_1):GND
  AD79  GND            VSS90  @S9S_MB_2U_LIB.S9S_MB_2U(SCH_1):GND
  AD42  GND            VSS89  @S9S_MB_2U_LIB.S9S_MB_2U(SCH_1):GND
  AD4  GND            VSS88  @S9S_MB_2U_LIB.S9S_MB_2U(SCH_1):GND
  AD16  GND            VSS87  @S9S_MB_2U_LIB.S9S_MB_2U(SCH_1):GND
  AD12  GND            VSS86  @S9S_MB_2U_LIB.S9S_MB_2U(SCH_1):GND
  AC9  GND            VSS85  @S9S_MB_2U_LIB.S9S_MB_2U(SCH_1):GND
  AC88  GND            VSS84  @S9S_MB_2U_LIB.S9S_MB_2U(SCH_1):GND
  AC84  GND            VSS83  @S9S_MB_2U_LIB.S9S_MB_2U(SCH_1):GND
  AC76  GND            VSS82  @S9S_MB_2U_LIB.S9S_MB_2U(SCH_1):GND
  AC70  GND            VSS81  @S9S_MB_2U_LIB.S9S_MB_2U(SCH_1):GND
  AC64  GND            VSS80  @S9S_MB_2U_LIB.S9S_MB_2U(SCH_1):GND
  AC58  GND            VSS79  @S9S_MB_2U_LIB.S9S_MB_2U(SCH_1):GND
  AC52  GND            VSS78  @S9S_MB_2U_LIB.S9S_MB_2U(SCH_1):GND
  AC5  GND            VSS77  @S9S_MB_2U_LIB.S9S_MB_2U(SCH_1):GND
  AC45  GND            VSS76  @S9S_MB_2U_LIB.S9S_MB_2U(SCH_1):GND
  AC39  GND            VSS75  @S9S_MB_2U_LIB.S9S_MB_2U(SCH_1):GND
  AC33  GND            VSS74  @S9S_MB_2U_LIB.S9S_MB_2U(SCH_1):GND
  AC27  GND            VSS73  @S9S_MB_2U_LIB.S9S_MB_2U(SCH_1):GND
  AC21  GND            VSS72  @S9S_MB_2U_LIB.S9S_MB_2U(SCH_1):GND
  AC13  GND            VSS71  @S9S_MB_2U_LIB.S9S_MB_2U(SCH_1):GND
  AC1  GND            VSS70  @S9S_MB_2U_LIB.S9S_MB_2U(SCH_1):GND
  AB91  GND            VSS69  @S9S_MB_2U_LIB.S9S_MB_2U(SCH_1):GND
  AB87  GND            VSS68  @S9S_MB_2U_LIB.S9S_MB_2U(SCH_1):GND
  AB83  GND            VSS67  @S9S_MB_2U_LIB.S9S_MB_2U(SCH_1):GND
  AB81  GND            VSS66  @S9S_MB_2U_LIB.S9S_MB_2U(SCH_1):GND
  AB8  GND            VSS65  @S9S_MB_2U_LIB.S9S_MB_2U(SCH_1):GND
  AB79  GND            VSS64  @S9S_MB_2U_LIB.S9S_MB_2U(SCH_1):GND
  AB77  GND            VSS63  @S9S_MB_2U_LIB.S9S_MB_2U(SCH_1):GND
  AB75  GND            VSS62  @S9S_MB_2U_LIB.S9S_MB_2U(SCH_1):GND
  AB71  GND            VSS61  @S9S_MB_2U_LIB.S9S_MB_2U(SCH_1):GND
  AB69  GND            VSS60  @S9S_MB_2U_LIB.S9S_MB_2U(SCH_1):GND
  AB65  GND            VSS59  @S9S_MB_2U_LIB.S9S_MB_2U(SCH_1):GND
  AB63  GND            VSS58  @S9S_MB_2U_LIB.S9S_MB_2U(SCH_1):GND
  AB59  GND            VSS57  @S9S_MB_2U_LIB.S9S_MB_2U(SCH_1):GND
  AB57  GND            VSS56  @S9S_MB_2U_LIB.S9S_MB_2U(SCH_1):GND
  AB53  GND            VSS55  @S9S_MB_2U_LIB.S9S_MB_2U(SCH_1):GND
  AB51  GND            VSS54  @S9S_MB_2U_LIB.S9S_MB_2U(SCH_1):GND
  AB47  GND            VSS53  @S9S_MB_2U_LIB.S9S_MB_2U(SCH_1):GND
  AB44  GND            VSS52  @S9S_MB_2U_LIB.S9S_MB_2U(SCH_1):GND
  AB40  GND            VSS51  @S9S_MB_2U_LIB.S9S_MB_2U(SCH_1):GND
  AB4  GND            VSS50  @S9S_MB_2U_LIB.S9S_MB_2U(SCH_1):GND
  AB38  GND            VSS49  @S9S_MB_2U_LIB.S9S_MB_2U(SCH_1):GND
  AB34  GND            VSS48  @S9S_MB_2U_LIB.S9S_MB_2U(SCH_1):GND
  AB32  GND            VSS47  @S9S_MB_2U_LIB.S9S_MB_2U(SCH_1):GND
  AB28  GND            VSS46  @S9S_MB_2U_LIB.S9S_MB_2U(SCH_1):GND
  AB26  GND            VSS45  @S9S_MB_2U_LIB.S9S_MB_2U(SCH_1):GND
  AB22  GND            VSS44  @S9S_MB_2U_LIB.S9S_MB_2U(SCH_1):GND
  AB20  GND            VSS43  @S9S_MB_2U_LIB.S9S_MB_2U(SCH_1):GND
  AB16  GND            VSS42  @S9S_MB_2U_LIB.S9S_MB_2U(SCH_1):GND
  AB12  GND            VSS41  @S9S_MB_2U_LIB.S9S_MB_2U(SCH_1):GND
  AA88  GND            VSS40  @S9S_MB_2U_LIB.S9S_MB_2U(SCH_1):GND
  AA84  GND            VSS39  @S9S_MB_2U_LIB.S9S_MB_2U(SCH_1):GND
  AA82  GND            VSS38  @S9S_MB_2U_LIB.S9S_MB_2U(SCH_1):GND

SOCKET4677_AZIFS054P001C01  I5   U1     [SOCKET4677_AZIFS054P001C01-SOCA]
  AW9  GND            VSS368  @S9S_MB_2U_LIB.S9S_MB_2U(SCH_1):GND
  AW5  GND            VSS359  @S9S_MB_2U_LIB.S9S_MB_2U(SCH_1):GND
  AW13  GND            VSS355  @S9S_MB_2U_LIB.S9S_MB_2U(SCH_1):GND
  AW1  GND            VSS354  @S9S_MB_2U_LIB.S9S_MB_2U(SCH_1):GND
  AV91  GND            VSS353  @S9S_MB_2U_LIB.S9S_MB_2U(SCH_1):GND
  AV87  GND            VSS352  @S9S_MB_2U_LIB.S9S_MB_2U(SCH_1):GND
  AV8  GND            VSS351  @S9S_MB_2U_LIB.S9S_MB_2U(SCH_1):GND
  AV77  GND            VSS350  @S9S_MB_2U_LIB.S9S_MB_2U(SCH_1):GND
  AV4  GND            VSS349  @S9S_MB_2U_LIB.S9S_MB_2U(SCH_1):GND
  AV16  GND            VSS348  @S9S_MB_2U_LIB.S9S_MB_2U(SCH_1):GND
  AV12  GND            VSS347  @S9S_MB_2U_LIB.S9S_MB_2U(SCH_1):GND
  AU88  GND            VSS346  @S9S_MB_2U_LIB.S9S_MB_2U(SCH_1):GND
  AU84  GND            VSS345  @S9S_MB_2U_LIB.S9S_MB_2U(SCH_1):GND
  AU80  GND            VSS344  @S9S_MB_2U_LIB.S9S_MB_2U(SCH_1):GND
  AU76  GND            VSS343  @S9S_MB_2U_LIB.S9S_MB_2U(SCH_1):GND
  AU74  GND            VSS342  @S9S_MB_2U_LIB.S9S_MB_2U(SCH_1):GND
  AU72  GND            VSS341  @S9S_MB_2U_LIB.S9S_MB_2U(SCH_1):GND
  AU70  GND            VSS340  @S9S_MB_2U_LIB.S9S_MB_2U(SCH_1):GND
  AU48  GND            VSS339  @S9S_MB_2U_LIB.S9S_MB_2U(SCH_1):GND
  AU45  GND            VSS338  @S9S_MB_2U_LIB.S9S_MB_2U(SCH_1):GND
  AU41  GND            VSS337  @S9S_MB_2U_LIB.S9S_MB_2U(SCH_1):GND
  AU39  GND            VSS336  @S9S_MB_2U_LIB.S9S_MB_2U(SCH_1):GND
  AU37  GND            VSS335  @S9S_MB_2U_LIB.S9S_MB_2U(SCH_1):GND
  AU31  GND            VSS334  @S9S_MB_2U_LIB.S9S_MB_2U(SCH_1):GND
  AU27  GND            VSS333  @S9S_MB_2U_LIB.S9S_MB_2U(SCH_1):GND
  AT8  GND            VSS332  @S9S_MB_2U_LIB.S9S_MB_2U(SCH_1):GND
  AT79  GND            VSS331  @S9S_MB_2U_LIB.S9S_MB_2U(SCH_1):GND
  AT77  GND            VSS330  @S9S_MB_2U_LIB.S9S_MB_2U(SCH_1):GND
  AT75  GND            VSS329  @S9S_MB_2U_LIB.S9S_MB_2U(SCH_1):GND
  AT71  GND            VSS328  @S9S_MB_2U_LIB.S9S_MB_2U(SCH_1):GND
  AT69  GND            VSS327  @S9S_MB_2U_LIB.S9S_MB_2U(SCH_1):GND
  AT65  GND            VSS326  @S9S_MB_2U_LIB.S9S_MB_2U(SCH_1):GND
  AT63  GND            VSS325  @S9S_MB_2U_LIB.S9S_MB_2U(SCH_1):GND
  AT59  GND            VSS324  @S9S_MB_2U_LIB.S9S_MB_2U(SCH_1):GND
  AT57  GND            VSS323  @S9S_MB_2U_LIB.S9S_MB_2U(SCH_1):GND
  AT53  GND            VSS322  @S9S_MB_2U_LIB.S9S_MB_2U(SCH_1):GND
  AT51  GND            VSS321  @S9S_MB_2U_LIB.S9S_MB_2U(SCH_1):GND
  AT44  GND            VSS320  @S9S_MB_2U_LIB.S9S_MB_2U(SCH_1):GND
  AT40  GND            VSS319  @S9S_MB_2U_LIB.S9S_MB_2U(SCH_1):GND
  AT4  GND            VSS318  @S9S_MB_2U_LIB.S9S_MB_2U(SCH_1):GND
  AT38  GND            VSS317  @S9S_MB_2U_LIB.S9S_MB_2U(SCH_1):GND
  AT34  GND            VSS316  @S9S_MB_2U_LIB.S9S_MB_2U(SCH_1):GND
  AT32  GND            VSS315  @S9S_MB_2U_LIB.S9S_MB_2U(SCH_1):GND
  AT28  GND            VSS314  @S9S_MB_2U_LIB.S9S_MB_2U(SCH_1):GND
  AT26  GND            VSS313  @S9S_MB_2U_LIB.S9S_MB_2U(SCH_1):GND
  AT22  GND            VSS312  @S9S_MB_2U_LIB.S9S_MB_2U(SCH_1):GND
  AT20  GND            VSS311  @S9S_MB_2U_LIB.S9S_MB_2U(SCH_1):GND
  AT16  GND            VSS310  @S9S_MB_2U_LIB.S9S_MB_2U(SCH_1):GND
  AT12  GND            VSS309  @S9S_MB_2U_LIB.S9S_MB_2U(SCH_1):GND
  AR9  GND            VSS308  @S9S_MB_2U_LIB.S9S_MB_2U(SCH_1):GND
  AR88  GND            VSS307  @S9S_MB_2U_LIB.S9S_MB_2U(SCH_1):GND
  AR84  GND            VSS306  @S9S_MB_2U_LIB.S9S_MB_2U(SCH_1):GND
  AR82  GND            VSS305  @S9S_MB_2U_LIB.S9S_MB_2U(SCH_1):GND
  AR78  GND            VSS304  @S9S_MB_2U_LIB.S9S_MB_2U(SCH_1):GND
  AR74  GND            VSS303  @S9S_MB_2U_LIB.S9S_MB_2U(SCH_1):GND
  AR72  GND            VSS302  @S9S_MB_2U_LIB.S9S_MB_2U(SCH_1):GND
  AR68  GND            VSS301  @S9S_MB_2U_LIB.S9S_MB_2U(SCH_1):GND
  AR66  GND            VSS300  @S9S_MB_2U_LIB.S9S_MB_2U(SCH_1):GND
  AR62  GND            VSS299  @S9S_MB_2U_LIB.S9S_MB_2U(SCH_1):GND
  AR60  GND            VSS298  @S9S_MB_2U_LIB.S9S_MB_2U(SCH_1):GND
  AR56  GND            VSS297  @S9S_MB_2U_LIB.S9S_MB_2U(SCH_1):GND
  AR54  GND            VSS296  @S9S_MB_2U_LIB.S9S_MB_2U(SCH_1):GND
  AR50  GND            VSS295  @S9S_MB_2U_LIB.S9S_MB_2U(SCH_1):GND
  AR5  GND            VSS294  @S9S_MB_2U_LIB.S9S_MB_2U(SCH_1):GND
  AR48  GND            VSS293  @S9S_MB_2U_LIB.S9S_MB_2U(SCH_1):GND
  AR43  GND            VSS292  @S9S_MB_2U_LIB.S9S_MB_2U(SCH_1):GND
  AR41  GND            VSS291  @S9S_MB_2U_LIB.S9S_MB_2U(SCH_1):GND
  AR37  GND            VSS290  @S9S_MB_2U_LIB.S9S_MB_2U(SCH_1):GND
  AR35  GND            VSS289  @S9S_MB_2U_LIB.S9S_MB_2U(SCH_1):GND
  AR31  GND            VSS288  @S9S_MB_2U_LIB.S9S_MB_2U(SCH_1):GND
  AR29  GND            VSS287  @S9S_MB_2U_LIB.S9S_MB_2U(SCH_1):GND
  AR25  GND            VSS286  @S9S_MB_2U_LIB.S9S_MB_2U(SCH_1):GND
  AR23  GND            VSS285  @S9S_MB_2U_LIB.S9S_MB_2U(SCH_1):GND
  AR19  GND            VSS284  @S9S_MB_2U_LIB.S9S_MB_2U(SCH_1):GND
  AR13  GND            VSS283  @S9S_MB_2U_LIB.S9S_MB_2U(SCH_1):GND
  AR1  GND            VSS282  @S9S_MB_2U_LIB.S9S_MB_2U(SCH_1):GND
  AP91  GND            VSS281  @S9S_MB_2U_LIB.S9S_MB_2U(SCH_1):GND
  AP87  GND            VSS280  @S9S_MB_2U_LIB.S9S_MB_2U(SCH_1):GND
  AP83  GND            VSS279  @S9S_MB_2U_LIB.S9S_MB_2U(SCH_1):GND
  AP8  GND            VSS278  @S9S_MB_2U_LIB.S9S_MB_2U(SCH_1):GND
  AP79  GND            VSS277  @S9S_MB_2U_LIB.S9S_MB_2U(SCH_1):GND
  AP73  GND            VSS276  @S9S_MB_2U_LIB.S9S_MB_2U(SCH_1):GND
  AP67  GND            VSS275  @S9S_MB_2U_LIB.S9S_MB_2U(SCH_1):GND
  AP61  GND            VSS274  @S9S_MB_2U_LIB.S9S_MB_2U(SCH_1):GND
  AP55  GND            VSS273  @S9S_MB_2U_LIB.S9S_MB_2U(SCH_1):GND
  AP49  GND            VSS272  @S9S_MB_2U_LIB.S9S_MB_2U(SCH_1):GND
  AP42  GND            VSS271  @S9S_MB_2U_LIB.S9S_MB_2U(SCH_1):GND
  AP4  GND            VSS270  @S9S_MB_2U_LIB.S9S_MB_2U(SCH_1):GND
  AP36  GND            VSS269  @S9S_MB_2U_LIB.S9S_MB_2U(SCH_1):GND
  AP30  GND            VSS268  @S9S_MB_2U_LIB.S9S_MB_2U(SCH_1):GND
  AP24  GND            VSS267  @S9S_MB_2U_LIB.S9S_MB_2U(SCH_1):GND
  AP18  GND            VSS266  @S9S_MB_2U_LIB.S9S_MB_2U(SCH_1):GND
  AP16  GND            VSS265  @S9S_MB_2U_LIB.S9S_MB_2U(SCH_1):GND
  AP12  GND            VSS264  @S9S_MB_2U_LIB.S9S_MB_2U(SCH_1):GND
  AN88  GND            VSS263  @S9S_MB_2U_LIB.S9S_MB_2U(SCH_1):GND
  AN84  GND            VSS262  @S9S_MB_2U_LIB.S9S_MB_2U(SCH_1):GND
  AN52  GND            VSS261  @S9S_MB_2U_LIB.S9S_MB_2U(SCH_1):GND
  AM8  GND            VSS260  @S9S_MB_2U_LIB.S9S_MB_2U(SCH_1):GND
  AM77  GND            VSS259  @S9S_MB_2U_LIB.S9S_MB_2U(SCH_1):GND
  AM75  GND            VSS258  @S9S_MB_2U_LIB.S9S_MB_2U(SCH_1):GND
  AM73  GND            VSS257  @S9S_MB_2U_LIB.S9S_MB_2U(SCH_1):GND
  AM71  GND            VSS256  @S9S_MB_2U_LIB.S9S_MB_2U(SCH_1):GND
  AM69  GND            VSS255  @S9S_MB_2U_LIB.S9S_MB_2U(SCH_1):GND
  AM67  GND            VSS254  @S9S_MB_2U_LIB.S9S_MB_2U(SCH_1):GND
  AM65  GND            VSS253  @S9S_MB_2U_LIB.S9S_MB_2U(SCH_1):GND
  AM63  GND            VSS252  @S9S_MB_2U_LIB.S9S_MB_2U(SCH_1):GND
  AM61  GND            VSS251  @S9S_MB_2U_LIB.S9S_MB_2U(SCH_1):GND
  AM59  GND            VSS250  @S9S_MB_2U_LIB.S9S_MB_2U(SCH_1):GND
  AM57  GND            VSS249  @S9S_MB_2U_LIB.S9S_MB_2U(SCH_1):GND
  AM55  GND            VSS248  @S9S_MB_2U_LIB.S9S_MB_2U(SCH_1):GND
  AM53  GND            VSS247  @S9S_MB_2U_LIB.S9S_MB_2U(SCH_1):GND
  AM51  GND            VSS246  @S9S_MB_2U_LIB.S9S_MB_2U(SCH_1):GND
  AM49  GND            VSS245  @S9S_MB_2U_LIB.S9S_MB_2U(SCH_1):GND
  AM47  GND            VSS244  @S9S_MB_2U_LIB.S9S_MB_2U(SCH_1):GND
  AM44  GND            VSS243  @S9S_MB_2U_LIB.S9S_MB_2U(SCH_1):GND
  AM42  GND            VSS242  @S9S_MB_2U_LIB.S9S_MB_2U(SCH_1):GND
  AM40  GND            VSS241  @S9S_MB_2U_LIB.S9S_MB_2U(SCH_1):GND
  AM4  GND            VSS240  @S9S_MB_2U_LIB.S9S_MB_2U(SCH_1):GND
  AM38  GND            VSS239  @S9S_MB_2U_LIB.S9S_MB_2U(SCH_1):GND
  AM36  GND            VSS238  @S9S_MB_2U_LIB.S9S_MB_2U(SCH_1):GND
  AM34  GND            VSS237  @S9S_MB_2U_LIB.S9S_MB_2U(SCH_1):GND
  AM32  GND            VSS236  @S9S_MB_2U_LIB.S9S_MB_2U(SCH_1):GND
  AM30  GND            VSS235  @S9S_MB_2U_LIB.S9S_MB_2U(SCH_1):GND
  AM28  GND            VSS234  @S9S_MB_2U_LIB.S9S_MB_2U(SCH_1):GND
  AM26  GND            VSS233  @S9S_MB_2U_LIB.S9S_MB_2U(SCH_1):GND
  AM24  GND            VSS232  @S9S_MB_2U_LIB.S9S_MB_2U(SCH_1):GND
  AM22  GND            VSS231  @S9S_MB_2U_LIB.S9S_MB_2U(SCH_1):GND
  AM20  GND            VSS230  @S9S_MB_2U_LIB.S9S_MB_2U(SCH_1):GND
  AM18  GND            VSS229  @S9S_MB_2U_LIB.S9S_MB_2U(SCH_1):GND
  AM16  GND            VSS228  @S9S_MB_2U_LIB.S9S_MB_2U(SCH_1):GND
  AM12  GND            VSS227  @S9S_MB_2U_LIB.S9S_MB_2U(SCH_1):GND
  AL9  GND            VSS226  @S9S_MB_2U_LIB.S9S_MB_2U(SCH_1):GND
  AL88  GND            VSS225  @S9S_MB_2U_LIB.S9S_MB_2U(SCH_1):GND
  AL84  GND            VSS224  @S9S_MB_2U_LIB.S9S_MB_2U(SCH_1):GND
  AL82  GND            VSS223  @S9S_MB_2U_LIB.S9S_MB_2U(SCH_1):GND
  AL80  GND            VSS222  @S9S_MB_2U_LIB.S9S_MB_2U(SCH_1):GND
  AL52  GND            VSS221  @S9S_MB_2U_LIB.S9S_MB_2U(SCH_1):GND
  AL5  GND            VSS220  @S9S_MB_2U_LIB.S9S_MB_2U(SCH_1):GND
  AL17  GND            VSS219  @S9S_MB_2U_LIB.S9S_MB_2U(SCH_1):GND
  AL13  GND            VSS218  @S9S_MB_2U_LIB.S9S_MB_2U(SCH_1):GND
  AL1  GND            VSS217  @S9S_MB_2U_LIB.S9S_MB_2U(SCH_1):GND
  AK91  GND            VSS216  @S9S_MB_2U_LIB.S9S_MB_2U(SCH_1):GND
  AK87  GND            VSS215  @S9S_MB_2U_LIB.S9S_MB_2U(SCH_1):GND
  AK83  GND            VSS214  @S9S_MB_2U_LIB.S9S_MB_2U(SCH_1):GND
  AK81  GND            VSS213  @S9S_MB_2U_LIB.S9S_MB_2U(SCH_1):GND
  AK8  GND            VSS212  @S9S_MB_2U_LIB.S9S_MB_2U(SCH_1):GND
  AK79  GND            VSS211  @S9S_MB_2U_LIB.S9S_MB_2U(SCH_1):GND
  AK73  GND            VSS210  @S9S_MB_2U_LIB.S9S_MB_2U(SCH_1):GND
  AK67  GND            VSS209  @S9S_MB_2U_LIB.S9S_MB_2U(SCH_1):GND
  AK61  GND            VSS208  @S9S_MB_2U_LIB.S9S_MB_2U(SCH_1):GND
  AK55  GND            VSS207  @S9S_MB_2U_LIB.S9S_MB_2U(SCH_1):GND
  AK49  GND            VSS206  @S9S_MB_2U_LIB.S9S_MB_2U(SCH_1):GND
  AK42  GND            VSS205  @S9S_MB_2U_LIB.S9S_MB_2U(SCH_1):GND
  AK4  GND            VSS204  @S9S_MB_2U_LIB.S9S_MB_2U(SCH_1):GND
  AK36  GND            VSS203  @S9S_MB_2U_LIB.S9S_MB_2U(SCH_1):GND
  AK30  GND            VSS202  @S9S_MB_2U_LIB.S9S_MB_2U(SCH_1):GND
  AK24  GND            VSS201  @S9S_MB_2U_LIB.S9S_MB_2U(SCH_1):GND
  AK18  GND            VSS200  @S9S_MB_2U_LIB.S9S_MB_2U(SCH_1):GND
  AK16  GND            VSS199  @S9S_MB_2U_LIB.S9S_MB_2U(SCH_1):GND
  AK12  GND            VSS198  @S9S_MB_2U_LIB.S9S_MB_2U(SCH_1):GND

SOCKET4677_AZIFS054P001C01  I2   U1     [SOCKET4677_AZIFS054P001C01-SOCA]
  BR9  GND            VSS572  @S9S_MB_2U_LIB.S9S_MB_2U(SCH_1):GND
  BR33  GND            VSS541  @S9S_MB_2U_LIB.S9S_MB_2U(SCH_1):GND
  BR31  GND            VSS540  @S9S_MB_2U_LIB.S9S_MB_2U(SCH_1):GND
  BR29  GND            VSS539  @S9S_MB_2U_LIB.S9S_MB_2U(SCH_1):GND
  BR27  GND            VSS538  @S9S_MB_2U_LIB.S9S_MB_2U(SCH_1):GND
  BR17  GND            VSS536  @S9S_MB_2U_LIB.S9S_MB_2U(SCH_1):GND
  BR13  GND            VSS535  @S9S_MB_2U_LIB.S9S_MB_2U(SCH_1):GND
  BP8  GND            VSS533  @S9S_MB_2U_LIB.S9S_MB_2U(SCH_1):GND
  BP77  GND            VSS532  @S9S_MB_2U_LIB.S9S_MB_2U(SCH_1):GND
  BP75  GND            VSS531  @S9S_MB_2U_LIB.S9S_MB_2U(SCH_1):GND
  BP73  GND            VSS530  @S9S_MB_2U_LIB.S9S_MB_2U(SCH_1):GND
  BP71  GND            VSS529  @S9S_MB_2U_LIB.S9S_MB_2U(SCH_1):GND
  BP63  GND            VSS528  @S9S_MB_2U_LIB.S9S_MB_2U(SCH_1):GND
  BP4  GND            VSS527  @S9S_MB_2U_LIB.S9S_MB_2U(SCH_1):GND
  BP20  GND            VSS525  @S9S_MB_2U_LIB.S9S_MB_2U(SCH_1):GND
  BP2  GND            VSS524  @S9S_MB_2U_LIB.S9S_MB_2U(SCH_1):GND
  BP16  GND            VSS523  @S9S_MB_2U_LIB.S9S_MB_2U(SCH_1):GND
  BP12  GND            VSS522  @S9S_MB_2U_LIB.S9S_MB_2U(SCH_1):GND
  BN70  GND            VSS520  @S9S_MB_2U_LIB.S9S_MB_2U(SCH_1):GND
  BN62  GND            VSS519  @S9S_MB_2U_LIB.S9S_MB_2U(SCH_1):GND
  BN31  GND            VSS518  @S9S_MB_2U_LIB.S9S_MB_2U(SCH_1):GND
  BM8  GND            VSS517  @S9S_MB_2U_LIB.S9S_MB_2U(SCH_1):GND
  BM77  GND            VSS516  @S9S_MB_2U_LIB.S9S_MB_2U(SCH_1):GND
  BM73  GND            VSS515  @S9S_MB_2U_LIB.S9S_MB_2U(SCH_1):GND
  BM61  GND            VSS513  @S9S_MB_2U_LIB.S9S_MB_2U(SCH_1):GND
  BM4  GND            VSS512  @S9S_MB_2U_LIB.S9S_MB_2U(SCH_1):GND
  BM26  GND            VSS511  @S9S_MB_2U_LIB.S9S_MB_2U(SCH_1):GND
  BM24  GND            VSS510  @S9S_MB_2U_LIB.S9S_MB_2U(SCH_1):GND
  BM22  GND            VSS509  @S9S_MB_2U_LIB.S9S_MB_2U(SCH_1):GND
  BM20  GND            VSS508  @S9S_MB_2U_LIB.S9S_MB_2U(SCH_1):GND
  BM16  GND            VSS507  @S9S_MB_2U_LIB.S9S_MB_2U(SCH_1):GND
  BM12  GND            VSS506  @S9S_MB_2U_LIB.S9S_MB_2U(SCH_1):GND
  BL9  GND            VSS505  @S9S_MB_2U_LIB.S9S_MB_2U(SCH_1):GND
  BL78  GND            VSS504  @S9S_MB_2U_LIB.S9S_MB_2U(SCH_1):GND
  BL72  GND            VSS503  @S9S_MB_2U_LIB.S9S_MB_2U(SCH_1):GND
  BL70  GND            VSS502  @S9S_MB_2U_LIB.S9S_MB_2U(SCH_1):GND
  BL68  GND            VSS501  @S9S_MB_2U_LIB.S9S_MB_2U(SCH_1):GND
  BL5  GND            VSS500  @S9S_MB_2U_LIB.S9S_MB_2U(SCH_1):GND
  BL17  GND            VSS499  @S9S_MB_2U_LIB.S9S_MB_2U(SCH_1):GND
  BL13  GND            VSS498  @S9S_MB_2U_LIB.S9S_MB_2U(SCH_1):GND
  BL1  GND            VSS497  @S9S_MB_2U_LIB.S9S_MB_2U(SCH_1):GND
  BK8  GND            VSS496  @S9S_MB_2U_LIB.S9S_MB_2U(SCH_1):GND
  BK79  GND            VSS495  @S9S_MB_2U_LIB.S9S_MB_2U(SCH_1):GND
  BK75  GND            VSS494  @S9S_MB_2U_LIB.S9S_MB_2U(SCH_1):GND
  BK71  GND            VSS492  @S9S_MB_2U_LIB.S9S_MB_2U(SCH_1):GND
  BK65  GND            VSS491  @S9S_MB_2U_LIB.S9S_MB_2U(SCH_1):GND
  BK4  GND            VSS490  @S9S_MB_2U_LIB.S9S_MB_2U(SCH_1):GND
  BK20  GND            VSS489  @S9S_MB_2U_LIB.S9S_MB_2U(SCH_1):GND
  BK16  GND            VSS488  @S9S_MB_2U_LIB.S9S_MB_2U(SCH_1):GND
  BK12  GND            VSS487  @S9S_MB_2U_LIB.S9S_MB_2U(SCH_1):GND
  BJ90  GND            VSS486  @S9S_MB_2U_LIB.S9S_MB_2U(SCH_1):GND
  BJ88  GND            VSS485  @S9S_MB_2U_LIB.S9S_MB_2U(SCH_1):GND
  BJ86  GND            VSS484  @S9S_MB_2U_LIB.S9S_MB_2U(SCH_1):GND
  BJ84  GND            VSS483  @S9S_MB_2U_LIB.S9S_MB_2U(SCH_1):GND
  BJ82  GND            VSS482  @S9S_MB_2U_LIB.S9S_MB_2U(SCH_1):GND
  BJ80  GND            VSS481  @S9S_MB_2U_LIB.S9S_MB_2U(SCH_1):GND
  BJ68  GND            VSS480  @S9S_MB_2U_LIB.S9S_MB_2U(SCH_1):GND
  BJ62  GND            VSS479  @S9S_MB_2U_LIB.S9S_MB_2U(SCH_1):GND
  BH83  GND            VSS477  @S9S_MB_2U_LIB.S9S_MB_2U(SCH_1):GND
  BH81  GND            VSS476  @S9S_MB_2U_LIB.S9S_MB_2U(SCH_1):GND
  BH8  GND            VSS475  @S9S_MB_2U_LIB.S9S_MB_2U(SCH_1):GND
  BH77  GND            VSS474  @S9S_MB_2U_LIB.S9S_MB_2U(SCH_1):GND
  BH73  GND            VSS473  @S9S_MB_2U_LIB.S9S_MB_2U(SCH_1):GND
  BH67  GND            VSS472  @S9S_MB_2U_LIB.S9S_MB_2U(SCH_1):GND
  BH4  GND            VSS470  @S9S_MB_2U_LIB.S9S_MB_2U(SCH_1):GND
  BH20  GND            VSS469  @S9S_MB_2U_LIB.S9S_MB_2U(SCH_1):GND
  BH16  GND            VSS468  @S9S_MB_2U_LIB.S9S_MB_2U(SCH_1):GND
  BH12  GND            VSS467  @S9S_MB_2U_LIB.S9S_MB_2U(SCH_1):GND
  BG9  GND            VSS466  @S9S_MB_2U_LIB.S9S_MB_2U(SCH_1):GND
  BG70  GND            VSS465  @S9S_MB_2U_LIB.S9S_MB_2U(SCH_1):GND
  BG5  GND            VSS464  @S9S_MB_2U_LIB.S9S_MB_2U(SCH_1):GND
  BG25  GND            VSS463  @S9S_MB_2U_LIB.S9S_MB_2U(SCH_1):GND
  BG23  GND            VSS462  @S9S_MB_2U_LIB.S9S_MB_2U(SCH_1):GND
  BG21  GND            VSS461  @S9S_MB_2U_LIB.S9S_MB_2U(SCH_1):GND
  BG17  GND            VSS460  @S9S_MB_2U_LIB.S9S_MB_2U(SCH_1):GND
  BG13  GND            VSS459  @S9S_MB_2U_LIB.S9S_MB_2U(SCH_1):GND
  BG1  GND            VSS458  @S9S_MB_2U_LIB.S9S_MB_2U(SCH_1):GND
  BF83  GND            VSS457  @S9S_MB_2U_LIB.S9S_MB_2U(SCH_1):GND
  BF8  GND            VSS456  @S9S_MB_2U_LIB.S9S_MB_2U(SCH_1):GND
  BF79  GND            VSS455  @S9S_MB_2U_LIB.S9S_MB_2U(SCH_1):GND
  BF75  GND            VSS454  @S9S_MB_2U_LIB.S9S_MB_2U(SCH_1):GND
  BF73  GND            VSS453  @S9S_MB_2U_LIB.S9S_MB_2U(SCH_1):GND
  BF63  GND            VSS452  @S9S_MB_2U_LIB.S9S_MB_2U(SCH_1):GND
  BF61  GND            VSS451  @S9S_MB_2U_LIB.S9S_MB_2U(SCH_1):GND
  BF4  GND            VSS450  @S9S_MB_2U_LIB.S9S_MB_2U(SCH_1):GND
  BF20  GND            VSS449  @S9S_MB_2U_LIB.S9S_MB_2U(SCH_1):GND
  BF16  GND            VSS448  @S9S_MB_2U_LIB.S9S_MB_2U(SCH_1):GND
  BF12  GND            VSS447  @S9S_MB_2U_LIB.S9S_MB_2U(SCH_1):GND
  BE84  GND            VSS446  @S9S_MB_2U_LIB.S9S_MB_2U(SCH_1):GND
  BE78  GND            VSS445  @S9S_MB_2U_LIB.S9S_MB_2U(SCH_1):GND
  BE76  GND            VSS444  @S9S_MB_2U_LIB.S9S_MB_2U(SCH_1):GND
  BE74  GND            VSS443  @S9S_MB_2U_LIB.S9S_MB_2U(SCH_1):GND
  BE68  GND            VSS442  @S9S_MB_2U_LIB.S9S_MB_2U(SCH_1):GND
  BE66  GND            VSS441  @S9S_MB_2U_LIB.S9S_MB_2U(SCH_1):GND
  BE64  GND            VSS440  @S9S_MB_2U_LIB.S9S_MB_2U(SCH_1):GND
  BD89  GND            VSS439  @S9S_MB_2U_LIB.S9S_MB_2U(SCH_1):GND
  BD85  GND            VSS437  @S9S_MB_2U_LIB.S9S_MB_2U(SCH_1):GND
  BD81  GND            VSS435  @S9S_MB_2U_LIB.S9S_MB_2U(SCH_1):GND
  BD8  GND            VSS434  @S9S_MB_2U_LIB.S9S_MB_2U(SCH_1):GND
  BD4  GND            VSS433  @S9S_MB_2U_LIB.S9S_MB_2U(SCH_1):GND
  BD20  GND            VSS432  @S9S_MB_2U_LIB.S9S_MB_2U(SCH_1):GND
  BD16  GND            VSS431  @S9S_MB_2U_LIB.S9S_MB_2U(SCH_1):GND
  BD12  GND            VSS430  @S9S_MB_2U_LIB.S9S_MB_2U(SCH_1):GND
  BC9  GND            VSS429  @S9S_MB_2U_LIB.S9S_MB_2U(SCH_1):GND
  BC88  GND            VSS428  @S9S_MB_2U_LIB.S9S_MB_2U(SCH_1):GND
  BC86  GND            VSS427  @S9S_MB_2U_LIB.S9S_MB_2U(SCH_1):GND
  BC84  GND            VSS426  @S9S_MB_2U_LIB.S9S_MB_2U(SCH_1):GND
  BC78  GND            VSS425  @S9S_MB_2U_LIB.S9S_MB_2U(SCH_1):GND
  BC76  GND            VSS424  @S9S_MB_2U_LIB.S9S_MB_2U(SCH_1):GND
  BC72  GND            VSS423  @S9S_MB_2U_LIB.S9S_MB_2U(SCH_1):GND
  BC66  GND            VSS422  @S9S_MB_2U_LIB.S9S_MB_2U(SCH_1):GND
  BC62  GND            VSS421  @S9S_MB_2U_LIB.S9S_MB_2U(SCH_1):GND
  BC5  GND            VSS420  @S9S_MB_2U_LIB.S9S_MB_2U(SCH_1):GND
  BC17  GND            VSS419  @S9S_MB_2U_LIB.S9S_MB_2U(SCH_1):GND
  BC13  GND            VSS418  @S9S_MB_2U_LIB.S9S_MB_2U(SCH_1):GND
  BC1  GND            VSS417  @S9S_MB_2U_LIB.S9S_MB_2U(SCH_1):GND
  BB91  GND            VSS416  @S9S_MB_2U_LIB.S9S_MB_2U(SCH_1):GND
  BB87  GND            VSS415  @S9S_MB_2U_LIB.S9S_MB_2U(SCH_1):GND
  BB83  GND            VSS414  @S9S_MB_2U_LIB.S9S_MB_2U(SCH_1):GND
  BB8  GND            VSS413  @S9S_MB_2U_LIB.S9S_MB_2U(SCH_1):GND
  BB79  GND            VSS412  @S9S_MB_2U_LIB.S9S_MB_2U(SCH_1):GND
  BB77  GND            VSS411  @S9S_MB_2U_LIB.S9S_MB_2U(SCH_1):GND
  BB71  GND            VSS410  @S9S_MB_2U_LIB.S9S_MB_2U(SCH_1):GND
  BB69  GND            VSS409  @S9S_MB_2U_LIB.S9S_MB_2U(SCH_1):GND
  BB63  GND            VSS408  @S9S_MB_2U_LIB.S9S_MB_2U(SCH_1):GND
  BB4  GND            VSS407  @S9S_MB_2U_LIB.S9S_MB_2U(SCH_1):GND
  BB26  GND            VSS406  @S9S_MB_2U_LIB.S9S_MB_2U(SCH_1):GND
  BB24  GND            VSS405  @S9S_MB_2U_LIB.S9S_MB_2U(SCH_1):GND
  BB22  GND            VSS404  @S9S_MB_2U_LIB.S9S_MB_2U(SCH_1):GND
  BB20  GND            VSS403  @S9S_MB_2U_LIB.S9S_MB_2U(SCH_1):GND
  BB16  GND            VSS402  @S9S_MB_2U_LIB.S9S_MB_2U(SCH_1):GND
  BB12  GND            VSS401  @S9S_MB_2U_LIB.S9S_MB_2U(SCH_1):GND
  BB10  GND            VSS400  @S9S_MB_2U_LIB.S9S_MB_2U(SCH_1):GND
  BA88  GND            VSS399  @S9S_MB_2U_LIB.S9S_MB_2U(SCH_1):GND
  BA84  GND            VSS398  @S9S_MB_2U_LIB.S9S_MB_2U(SCH_1):GND
  BA74  GND            VSS397  @S9S_MB_2U_LIB.S9S_MB_2U(SCH_1):GND
  BA64  GND            VSS395  @S9S_MB_2U_LIB.S9S_MB_2U(SCH_1):GND
  BA60  GND            VSS394  @S9S_MB_2U_LIB.S9S_MB_2U(SCH_1):GND
  BA17  GND            VSS393  @S9S_MB_2U_LIB.S9S_MB_2U(SCH_1):GND
  AY83  GND            VSS377  @S9S_MB_2U_LIB.S9S_MB_2U(SCH_1):GND
  AY81  GND            VSS376  @S9S_MB_2U_LIB.S9S_MB_2U(SCH_1):GND
  AY8  GND            VSS375  @S9S_MB_2U_LIB.S9S_MB_2U(SCH_1):GND
  AY79  GND            VSS374  @S9S_MB_2U_LIB.S9S_MB_2U(SCH_1):GND
  AY77  GND            VSS373  @S9S_MB_2U_LIB.S9S_MB_2U(SCH_1):GND
  AY71  GND            VSS372  @S9S_MB_2U_LIB.S9S_MB_2U(SCH_1):GND
  AY4  GND            VSS371  @S9S_MB_2U_LIB.S9S_MB_2U(SCH_1):GND
  AY16  GND            VSS370  @S9S_MB_2U_LIB.S9S_MB_2U(SCH_1):GND
  AY12  GND            VSS369  @S9S_MB_2U_LIB.S9S_MB_2U(SCH_1):GND
  AW88  GND            VSS367  @S9S_MB_2U_LIB.S9S_MB_2U(SCH_1):GND
  AW84  GND            VSS366  @S9S_MB_2U_LIB.S9S_MB_2U(SCH_1):GND
  AW82  GND            VSS365  @S9S_MB_2U_LIB.S9S_MB_2U(SCH_1):GND
  AW80  GND            VSS364  @S9S_MB_2U_LIB.S9S_MB_2U(SCH_1):GND
  AW72  GND            VSS363  @S9S_MB_2U_LIB.S9S_MB_2U(SCH_1):GND
  AW68  GND            VSS362  @S9S_MB_2U_LIB.S9S_MB_2U(SCH_1):GND
  AW66  GND            VSS361  @S9S_MB_2U_LIB.S9S_MB_2U(SCH_1):GND
  AW62  GND            VSS360  @S9S_MB_2U_LIB.S9S_MB_2U(SCH_1):GND
  AW25  GND            VSS358  @S9S_MB_2U_LIB.S9S_MB_2U(SCH_1):GND
  AW23  GND            VSS357  @S9S_MB_2U_LIB.S9S_MB_2U(SCH_1):GND
  AW21  GND            VSS356  @S9S_MB_2U_LIB.S9S_MB_2U(SCH_1):GND
  BR5  GND             VSS0  @S9S_MB_2U_LIB.S9S_MB_2U(SCH_1):GND

SOCKET4677_AZIFS054P001C01  I8   U1     [SOCKET4677_AZIFS054P001C01-SOCA]
  CK8  GND            VSS746  @S9S_MB_2U_LIB.S9S_MB_2U(SCH_1):GND
  CK26  GND            VSS743  @S9S_MB_2U_LIB.S9S_MB_2U(SCH_1):GND
  CK20  GND            VSS742  @S9S_MB_2U_LIB.S9S_MB_2U(SCH_1):GND
  CK16  GND            VSS741  @S9S_MB_2U_LIB.S9S_MB_2U(SCH_1):GND
  CK12  GND            VSS740  @S9S_MB_2U_LIB.S9S_MB_2U(SCH_1):GND
  CJ80  GND            VSS737  @S9S_MB_2U_LIB.S9S_MB_2U(SCH_1):GND
  CJ60  GND            VSS736  @S9S_MB_2U_LIB.S9S_MB_2U(SCH_1):GND
  CH89  GND            VSS734  @S9S_MB_2U_LIB.S9S_MB_2U(SCH_1):GND
  CH87  GND            VSS733  @S9S_MB_2U_LIB.S9S_MB_2U(SCH_1):GND
  CH85  GND            VSS732  @S9S_MB_2U_LIB.S9S_MB_2U(SCH_1):GND
  CH83  GND            VSS731  @S9S_MB_2U_LIB.S9S_MB_2U(SCH_1):GND
  CH8  GND            VSS730  @S9S_MB_2U_LIB.S9S_MB_2U(SCH_1):GND
  CH79  GND            VSS729  @S9S_MB_2U_LIB.S9S_MB_2U(SCH_1):GND
  CH73  GND            VSS728  @S9S_MB_2U_LIB.S9S_MB_2U(SCH_1):GND
  CH67  GND            VSS727  @S9S_MB_2U_LIB.S9S_MB_2U(SCH_1):GND
  CH4  GND            VSS722  @S9S_MB_2U_LIB.S9S_MB_2U(SCH_1):GND
  CH20  GND            VSS721  @S9S_MB_2U_LIB.S9S_MB_2U(SCH_1):GND
  CH16  GND            VSS720  @S9S_MB_2U_LIB.S9S_MB_2U(SCH_1):GND
  CH12  GND            VSS718  @S9S_MB_2U_LIB.S9S_MB_2U(SCH_1):GND
  CG9  GND            VSS716  @S9S_MB_2U_LIB.S9S_MB_2U(SCH_1):GND
  CG78  GND            VSS713  @S9S_MB_2U_LIB.S9S_MB_2U(SCH_1):GND
  CG74  GND            VSS710  @S9S_MB_2U_LIB.S9S_MB_2U(SCH_1):GND
  CG72  GND            VSS708  @S9S_MB_2U_LIB.S9S_MB_2U(SCH_1):GND
  CG70  GND            VSS707  @S9S_MB_2U_LIB.S9S_MB_2U(SCH_1):GND
  CG64  GND            VSS706  @S9S_MB_2U_LIB.S9S_MB_2U(SCH_1):GND
  CG62  GND            VSS704  @S9S_MB_2U_LIB.S9S_MB_2U(SCH_1):GND
  CG5  GND            VSS703  @S9S_MB_2U_LIB.S9S_MB_2U(SCH_1):GND
  CG25  GND            VSS701  @S9S_MB_2U_LIB.S9S_MB_2U(SCH_1):GND
  CG23  GND            VSS698  @S9S_MB_2U_LIB.S9S_MB_2U(SCH_1):GND
  CG21  GND            VSS697  @S9S_MB_2U_LIB.S9S_MB_2U(SCH_1):GND
  CG17  GND            VSS696  @S9S_MB_2U_LIB.S9S_MB_2U(SCH_1):GND
  CG13  GND            VSS695  @S9S_MB_2U_LIB.S9S_MB_2U(SCH_1):GND
  CG1  GND            VSS694  @S9S_MB_2U_LIB.S9S_MB_2U(SCH_1):GND
  CF8  GND            VSS693  @S9S_MB_2U_LIB.S9S_MB_2U(SCH_1):GND
  CF71  GND            VSS692  @S9S_MB_2U_LIB.S9S_MB_2U(SCH_1):GND
  CF69  GND            VSS691  @S9S_MB_2U_LIB.S9S_MB_2U(SCH_1):GND
  CF4  GND            VSS689  @S9S_MB_2U_LIB.S9S_MB_2U(SCH_1):GND
  CF20  GND            VSS688  @S9S_MB_2U_LIB.S9S_MB_2U(SCH_1):GND
  CF16  GND            VSS687  @S9S_MB_2U_LIB.S9S_MB_2U(SCH_1):GND
  CF12  GND            VSS686  @S9S_MB_2U_LIB.S9S_MB_2U(SCH_1):GND
  CE78  GND            VSS685  @S9S_MB_2U_LIB.S9S_MB_2U(SCH_1):GND
  CE76  GND            VSS684  @S9S_MB_2U_LIB.S9S_MB_2U(SCH_1):GND
  CE72  GND            VSS683  @S9S_MB_2U_LIB.S9S_MB_2U(SCH_1):GND
  CE66  GND            VSS682  @S9S_MB_2U_LIB.S9S_MB_2U(SCH_1):GND
  CE60  GND            VSS681  @S9S_MB_2U_LIB.S9S_MB_2U(SCH_1):GND
  CE3  GND            VSS680  @S9S_MB_2U_LIB.S9S_MB_2U(SCH_1):GND
  CD8  GND            VSS678  @S9S_MB_2U_LIB.S9S_MB_2U(SCH_1):GND
  CD77  GND            VSS677  @S9S_MB_2U_LIB.S9S_MB_2U(SCH_1):GND
  CD75  GND            VSS676  @S9S_MB_2U_LIB.S9S_MB_2U(SCH_1):GND
  CD61  GND            VSS675  @S9S_MB_2U_LIB.S9S_MB_2U(SCH_1):GND
  CD4  GND            VSS674  @S9S_MB_2U_LIB.S9S_MB_2U(SCH_1):GND
  CD20  GND            VSS673  @S9S_MB_2U_LIB.S9S_MB_2U(SCH_1):GND
  CD16  GND            VSS672  @S9S_MB_2U_LIB.S9S_MB_2U(SCH_1):GND
  CD12  GND            VSS671  @S9S_MB_2U_LIB.S9S_MB_2U(SCH_1):GND
  CC9  GND            VSS670  @S9S_MB_2U_LIB.S9S_MB_2U(SCH_1):GND
  CC74  GND            VSS669  @S9S_MB_2U_LIB.S9S_MB_2U(SCH_1):GND
  CC72  GND            VSS668  @S9S_MB_2U_LIB.S9S_MB_2U(SCH_1):GND
  CC70  GND            VSS667  @S9S_MB_2U_LIB.S9S_MB_2U(SCH_1):GND
  CC62  GND            VSS666  @S9S_MB_2U_LIB.S9S_MB_2U(SCH_1):GND
  CC5  GND            VSS665  @S9S_MB_2U_LIB.S9S_MB_2U(SCH_1):GND
  CC31  GND            VSS664  @S9S_MB_2U_LIB.S9S_MB_2U(SCH_1):GND
  CC17  GND            VSS661  @S9S_MB_2U_LIB.S9S_MB_2U(SCH_1):GND
  CC13  GND            VSS660  @S9S_MB_2U_LIB.S9S_MB_2U(SCH_1):GND
  CB89  GND            VSS656  @S9S_MB_2U_LIB.S9S_MB_2U(SCH_1):GND
  CB87  GND            VSS655  @S9S_MB_2U_LIB.S9S_MB_2U(SCH_1):GND
  CB85  GND            VSS654  @S9S_MB_2U_LIB.S9S_MB_2U(SCH_1):GND
  CB83  GND            VSS653  @S9S_MB_2U_LIB.S9S_MB_2U(SCH_1):GND
  CB81  GND            VSS652  @S9S_MB_2U_LIB.S9S_MB_2U(SCH_1):GND
  CB8  GND            VSS651  @S9S_MB_2U_LIB.S9S_MB_2U(SCH_1):GND
  CB79  GND            VSS650  @S9S_MB_2U_LIB.S9S_MB_2U(SCH_1):GND
  CB73  GND            VSS649  @S9S_MB_2U_LIB.S9S_MB_2U(SCH_1):GND
  CB71  GND            VSS648  @S9S_MB_2U_LIB.S9S_MB_2U(SCH_1):GND
  CB69  GND            VSS647  @S9S_MB_2U_LIB.S9S_MB_2U(SCH_1):GND
  CB67  GND            VSS646  @S9S_MB_2U_LIB.S9S_MB_2U(SCH_1):GND
  CB65  GND            VSS645  @S9S_MB_2U_LIB.S9S_MB_2U(SCH_1):GND
  CB63  GND            VSS644  @S9S_MB_2U_LIB.S9S_MB_2U(SCH_1):GND
  CB59  GND            VSS643  @S9S_MB_2U_LIB.S9S_MB_2U(SCH_1):GND
  CB57  GND            VSS642  @S9S_MB_2U_LIB.S9S_MB_2U(SCH_1):GND
  CB55  GND            VSS641  @S9S_MB_2U_LIB.S9S_MB_2U(SCH_1):GND
  CB53  GND            VSS640  @S9S_MB_2U_LIB.S9S_MB_2U(SCH_1):GND
  CB51  GND            VSS639  @S9S_MB_2U_LIB.S9S_MB_2U(SCH_1):GND
  CB49  GND            VSS638  @S9S_MB_2U_LIB.S9S_MB_2U(SCH_1):GND
  CB47  GND            VSS637  @S9S_MB_2U_LIB.S9S_MB_2U(SCH_1):GND
  CB44  GND            VSS636  @S9S_MB_2U_LIB.S9S_MB_2U(SCH_1):GND
  CB42  GND            VSS635  @S9S_MB_2U_LIB.S9S_MB_2U(SCH_1):GND
  CB40  GND            VSS634  @S9S_MB_2U_LIB.S9S_MB_2U(SCH_1):GND
  CB4  GND            VSS633  @S9S_MB_2U_LIB.S9S_MB_2U(SCH_1):GND
  CB38  GND            VSS632  @S9S_MB_2U_LIB.S9S_MB_2U(SCH_1):GND
  CB36  GND            VSS631  @S9S_MB_2U_LIB.S9S_MB_2U(SCH_1):GND
  CB34  GND            VSS630  @S9S_MB_2U_LIB.S9S_MB_2U(SCH_1):GND
  CB32  GND            VSS629  @S9S_MB_2U_LIB.S9S_MB_2U(SCH_1):GND
  CB28  GND            VSS628  @S9S_MB_2U_LIB.S9S_MB_2U(SCH_1):GND
  CB26  GND            VSS627  @S9S_MB_2U_LIB.S9S_MB_2U(SCH_1):GND
  CB24  GND            VSS626  @S9S_MB_2U_LIB.S9S_MB_2U(SCH_1):GND
  CB22  GND            VSS625  @S9S_MB_2U_LIB.S9S_MB_2U(SCH_1):GND
  CB20  GND            VSS624  @S9S_MB_2U_LIB.S9S_MB_2U(SCH_1):GND
  CB16  GND            VSS623  @S9S_MB_2U_LIB.S9S_MB_2U(SCH_1):GND
  CB12  GND            VSS622  @S9S_MB_2U_LIB.S9S_MB_2U(SCH_1):GND
  CA31  GND            VSS621  @S9S_MB_2U_LIB.S9S_MB_2U(SCH_1):GND
  CA3  GND            VSS620  @S9S_MB_2U_LIB.S9S_MB_2U(SCH_1):GND
  BY8  GND            VSS608  @S9S_MB_2U_LIB.S9S_MB_2U(SCH_1):GND
  BY4  GND            VSS607  @S9S_MB_2U_LIB.S9S_MB_2U(SCH_1):GND
  BY20  GND            VSS606  @S9S_MB_2U_LIB.S9S_MB_2U(SCH_1):GND
  BY16  GND            VSS605  @S9S_MB_2U_LIB.S9S_MB_2U(SCH_1):GND
  BY12  GND            VSS604  @S9S_MB_2U_LIB.S9S_MB_2U(SCH_1):GND
  BW9  GND            VSS603  @S9S_MB_2U_LIB.S9S_MB_2U(SCH_1):GND
  BW5  GND            VSS602  @S9S_MB_2U_LIB.S9S_MB_2U(SCH_1):GND
  BW31  GND            VSS601  @S9S_MB_2U_LIB.S9S_MB_2U(SCH_1):GND
  BW3  GND            VSS600  @S9S_MB_2U_LIB.S9S_MB_2U(SCH_1):GND
  BW29  GND            VSS599  @S9S_MB_2U_LIB.S9S_MB_2U(SCH_1):GND
  BW27  GND            VSS598  @S9S_MB_2U_LIB.S9S_MB_2U(SCH_1):GND
  BW17  GND            VSS597  @S9S_MB_2U_LIB.S9S_MB_2U(SCH_1):GND
  BW13  GND            VSS596  @S9S_MB_2U_LIB.S9S_MB_2U(SCH_1):GND
  BV8  GND            VSS594  @S9S_MB_2U_LIB.S9S_MB_2U(SCH_1):GND
  BV6  GND            VSS593  @S9S_MB_2U_LIB.S9S_MB_2U(SCH_1):GND
  BV4  GND            VSS592  @S9S_MB_2U_LIB.S9S_MB_2U(SCH_1):GND
  BV20  GND            VSS591  @S9S_MB_2U_LIB.S9S_MB_2U(SCH_1):GND
  BV2  GND            VSS590  @S9S_MB_2U_LIB.S9S_MB_2U(SCH_1):GND
  BV18  GND            VSS589  @S9S_MB_2U_LIB.S9S_MB_2U(SCH_1):GND
  BV16  GND            VSS588  @S9S_MB_2U_LIB.S9S_MB_2U(SCH_1):GND
  BV12  GND            VSS587  @S9S_MB_2U_LIB.S9S_MB_2U(SCH_1):GND
  BU7  GND            VSS586  @S9S_MB_2U_LIB.S9S_MB_2U(SCH_1):GND
  BU31  GND            VSS585  @S9S_MB_2U_LIB.S9S_MB_2U(SCH_1):GND
  BU25  GND            VSS584  @S9S_MB_2U_LIB.S9S_MB_2U(SCH_1):GND
  BU23  GND            VSS582  @S9S_MB_2U_LIB.S9S_MB_2U(SCH_1):GND
  BU21  GND            VSS581  @S9S_MB_2U_LIB.S9S_MB_2U(SCH_1):GND
  BU19  GND            VSS580  @S9S_MB_2U_LIB.S9S_MB_2U(SCH_1):GND
  BU15  GND            VSS579  @S9S_MB_2U_LIB.S9S_MB_2U(SCH_1):GND
  BT8  GND            VSS578  @S9S_MB_2U_LIB.S9S_MB_2U(SCH_1):GND
  BT4  GND            VSS577  @S9S_MB_2U_LIB.S9S_MB_2U(SCH_1):GND
  BT20  GND            VSS576  @S9S_MB_2U_LIB.S9S_MB_2U(SCH_1):GND
  BT16  GND            VSS575  @S9S_MB_2U_LIB.S9S_MB_2U(SCH_1):GND
  BT12  GND            VSS574  @S9S_MB_2U_LIB.S9S_MB_2U(SCH_1):GND
  BR90  GND            VSS573  @S9S_MB_2U_LIB.S9S_MB_2U(SCH_1):GND
  BR88  GND            VSS570  @S9S_MB_2U_LIB.S9S_MB_2U(SCH_1):GND
  BR86  GND            VSS569  @S9S_MB_2U_LIB.S9S_MB_2U(SCH_1):GND
  BR84  GND            VSS568  @S9S_MB_2U_LIB.S9S_MB_2U(SCH_1):GND
  BR82  GND            VSS567  @S9S_MB_2U_LIB.S9S_MB_2U(SCH_1):GND
  BR80  GND            VSS566  @S9S_MB_2U_LIB.S9S_MB_2U(SCH_1):GND
  BR76  GND            VSS565  @S9S_MB_2U_LIB.S9S_MB_2U(SCH_1):GND
  BR74  GND            VSS564  @S9S_MB_2U_LIB.S9S_MB_2U(SCH_1):GND
  BR72  GND            VSS563  @S9S_MB_2U_LIB.S9S_MB_2U(SCH_1):GND
  BR70  GND            VSS561  @S9S_MB_2U_LIB.S9S_MB_2U(SCH_1):GND
  BR68  GND            VSS560  @S9S_MB_2U_LIB.S9S_MB_2U(SCH_1):GND
  BR66  GND            VSS559  @S9S_MB_2U_LIB.S9S_MB_2U(SCH_1):GND
  BR64  GND            VSS557  @S9S_MB_2U_LIB.S9S_MB_2U(SCH_1):GND
  BR58  GND            VSS556  @S9S_MB_2U_LIB.S9S_MB_2U(SCH_1):GND
  BR56  GND            VSS555  @S9S_MB_2U_LIB.S9S_MB_2U(SCH_1):GND
  BR54  GND            VSS552  @S9S_MB_2U_LIB.S9S_MB_2U(SCH_1):GND
  BR52  GND            VSS551  @S9S_MB_2U_LIB.S9S_MB_2U(SCH_1):GND
  BR50  GND            VSS550  @S9S_MB_2U_LIB.S9S_MB_2U(SCH_1):GND
  BR48  GND            VSS549  @S9S_MB_2U_LIB.S9S_MB_2U(SCH_1):GND
  BR45  GND            VSS548  @S9S_MB_2U_LIB.S9S_MB_2U(SCH_1):GND
  BR43  GND            VSS547  @S9S_MB_2U_LIB.S9S_MB_2U(SCH_1):GND
  BR41  GND            VSS546  @S9S_MB_2U_LIB.S9S_MB_2U(SCH_1):GND
  BR39  GND            VSS545  @S9S_MB_2U_LIB.S9S_MB_2U(SCH_1):GND
  BR37  GND            VSS543  @S9S_MB_2U_LIB.S9S_MB_2U(SCH_1):GND
  BR35  GND            VSS542  @S9S_MB_2U_LIB.S9S_MB_2U(SCH_1):GND
  CK4  GND            VSS396  @S9S_MB_2U_LIB.S9S_MB_2U(SCH_1):GND
  CJ76  GND            VSS383  @S9S_MB_2U_LIB.S9S_MB_2U(SCH_1):GND

SOCKET4677_AZIFS054P001C01  I5   U1     [SOCKET4677_AZIFS054P001C01-SOCA]
  DB87  GND            VSS948  @S9S_MB_2U_LIB.S9S_MB_2U(SCH_1):GND
  DB8  GND            VSS947  @S9S_MB_2U_LIB.S9S_MB_2U(SCH_1):GND
  DB77  GND            VSS946  @S9S_MB_2U_LIB.S9S_MB_2U(SCH_1):GND
  DB71  GND            VSS944  @S9S_MB_2U_LIB.S9S_MB_2U(SCH_1):GND
  DB65  GND            VSS943  @S9S_MB_2U_LIB.S9S_MB_2U(SCH_1):GND
  DB57  GND            VSS942  @S9S_MB_2U_LIB.S9S_MB_2U(SCH_1):GND
  DB47  GND            VSS941  @S9S_MB_2U_LIB.S9S_MB_2U(SCH_1):GND
  DB40  GND            VSS940  @S9S_MB_2U_LIB.S9S_MB_2U(SCH_1):GND
  DB4  GND            VSS939  @S9S_MB_2U_LIB.S9S_MB_2U(SCH_1):GND
  DB38  GND            VSS938  @S9S_MB_2U_LIB.S9S_MB_2U(SCH_1):GND
  DB32  GND            VSS937  @S9S_MB_2U_LIB.S9S_MB_2U(SCH_1):GND
  DB28  GND            VSS936  @S9S_MB_2U_LIB.S9S_MB_2U(SCH_1):GND
  DB22  GND            VSS935  @S9S_MB_2U_LIB.S9S_MB_2U(SCH_1):GND
  DB12  GND            VSS933  @S9S_MB_2U_LIB.S9S_MB_2U(SCH_1):GND
  DA88  GND            VSS932  @S9S_MB_2U_LIB.S9S_MB_2U(SCH_1):GND
  DA84  GND            VSS931  @S9S_MB_2U_LIB.S9S_MB_2U(SCH_1):GND
  DA82  GND            VSS930  @S9S_MB_2U_LIB.S9S_MB_2U(SCH_1):GND
  DA80  GND            VSS929  @S9S_MB_2U_LIB.S9S_MB_2U(SCH_1):GND
  DA74  GND            VSS928  @S9S_MB_2U_LIB.S9S_MB_2U(SCH_1):GND
  DA72  GND            VSS927  @S9S_MB_2U_LIB.S9S_MB_2U(SCH_1):GND
  DA66  GND            VSS926  @S9S_MB_2U_LIB.S9S_MB_2U(SCH_1):GND
  DA62  GND            VSS925  @S9S_MB_2U_LIB.S9S_MB_2U(SCH_1):GND
  DA60  GND            VSS924  @S9S_MB_2U_LIB.S9S_MB_2U(SCH_1):GND
  DA58  GND            VSS923  @S9S_MB_2U_LIB.S9S_MB_2U(SCH_1):GND
  DA56  GND            VSS922  @S9S_MB_2U_LIB.S9S_MB_2U(SCH_1):GND
  DA54  GND            VSS921  @S9S_MB_2U_LIB.S9S_MB_2U(SCH_1):GND
  DA50  GND            VSS920  @S9S_MB_2U_LIB.S9S_MB_2U(SCH_1):GND
  DA48  GND            VSS919  @S9S_MB_2U_LIB.S9S_MB_2U(SCH_1):GND
  DA41  GND            VSS918  @S9S_MB_2U_LIB.S9S_MB_2U(SCH_1):GND
  DA37  GND            VSS917  @S9S_MB_2U_LIB.S9S_MB_2U(SCH_1):GND
  DA35  GND            VSS916  @S9S_MB_2U_LIB.S9S_MB_2U(SCH_1):GND
  DA33  GND            VSS915  @S9S_MB_2U_LIB.S9S_MB_2U(SCH_1):GND
  DA31  GND            VSS914  @S9S_MB_2U_LIB.S9S_MB_2U(SCH_1):GND
  DA29  GND            VSS913  @S9S_MB_2U_LIB.S9S_MB_2U(SCH_1):GND
  DA25  GND            VSS912  @S9S_MB_2U_LIB.S9S_MB_2U(SCH_1):GND
  DA23  GND            VSS911  @S9S_MB_2U_LIB.S9S_MB_2U(SCH_1):GND
  DA19  GND            VSS910  @S9S_MB_2U_LIB.S9S_MB_2U(SCH_1):GND
  CY83  GND            VSS863  @S9S_MB_2U_LIB.S9S_MB_2U(SCH_1):GND
  CY81  GND            VSS862  @S9S_MB_2U_LIB.S9S_MB_2U(SCH_1):GND
  CY8  GND            VSS860  @S9S_MB_2U_LIB.S9S_MB_2U(SCH_1):GND
  CY77  GND            VSS859  @S9S_MB_2U_LIB.S9S_MB_2U(SCH_1):GND
  CY73  GND            VSS858  @S9S_MB_2U_LIB.S9S_MB_2U(SCH_1):GND
  CY63  GND            VSS856  @S9S_MB_2U_LIB.S9S_MB_2U(SCH_1):GND
  CY30  GND            VSS855  @S9S_MB_2U_LIB.S9S_MB_2U(SCH_1):GND
  CY26  GND            VSS854  @S9S_MB_2U_LIB.S9S_MB_2U(SCH_1):GND
  CY18  GND            VSS853  @S9S_MB_2U_LIB.S9S_MB_2U(SCH_1):GND
  CY16  GND            VSS852  @S9S_MB_2U_LIB.S9S_MB_2U(SCH_1):GND
  CY12  GND            VSS851  @S9S_MB_2U_LIB.S9S_MB_2U(SCH_1):GND
  CW9  GND            VSS850  @S9S_MB_2U_LIB.S9S_MB_2U(SCH_1):GND
  CW88  GND            VSS848  @S9S_MB_2U_LIB.S9S_MB_2U(SCH_1):GND
  CW84  GND            VSS846  @S9S_MB_2U_LIB.S9S_MB_2U(SCH_1):GND
  CW78  GND            VSS843  @S9S_MB_2U_LIB.S9S_MB_2U(SCH_1):GND
  CW72  GND            VSS840  @S9S_MB_2U_LIB.S9S_MB_2U(SCH_1):GND
  CW5  GND            VSS838  @S9S_MB_2U_LIB.S9S_MB_2U(SCH_1):GND
  CW17  GND            VSS837  @S9S_MB_2U_LIB.S9S_MB_2U(SCH_1):GND
  CW13  GND            VSS836  @S9S_MB_2U_LIB.S9S_MB_2U(SCH_1):GND
  CW1  GND            VSS834  @S9S_MB_2U_LIB.S9S_MB_2U(SCH_1):GND
  CV91  GND            VSS833  @S9S_MB_2U_LIB.S9S_MB_2U(SCH_1):GND
  CV87  GND            VSS831  @S9S_MB_2U_LIB.S9S_MB_2U(SCH_1):GND
  CV83  GND            VSS828  @S9S_MB_2U_LIB.S9S_MB_2U(SCH_1):GND
  CV8  GND            VSS827  @S9S_MB_2U_LIB.S9S_MB_2U(SCH_1):GND
  CV75  GND            VSS826  @S9S_MB_2U_LIB.S9S_MB_2U(SCH_1):GND
  CV4  GND            VSS825  @S9S_MB_2U_LIB.S9S_MB_2U(SCH_1):GND
  CV12  GND            VSS824  @S9S_MB_2U_LIB.S9S_MB_2U(SCH_1):GND
  CU88  GND            VSS823  @S9S_MB_2U_LIB.S9S_MB_2U(SCH_1):GND
  CU84  GND            VSS822  @S9S_MB_2U_LIB.S9S_MB_2U(SCH_1):GND
  CU68  GND            VSS819  @S9S_MB_2U_LIB.S9S_MB_2U(SCH_1):GND
  CU66  GND            VSS818  @S9S_MB_2U_LIB.S9S_MB_2U(SCH_1):GND
  CU60  GND            VSS816  @S9S_MB_2U_LIB.S9S_MB_2U(SCH_1):GND
  CU23  GND            VSS815  @S9S_MB_2U_LIB.S9S_MB_2U(SCH_1):GND
  CU21  GND            VSS814  @S9S_MB_2U_LIB.S9S_MB_2U(SCH_1):GND
  CU19  GND            VSS813  @S9S_MB_2U_LIB.S9S_MB_2U(SCH_1):GND
  CT81  GND            VSS812  @S9S_MB_2U_LIB.S9S_MB_2U(SCH_1):GND
  CT73  GND            VSS811  @S9S_MB_2U_LIB.S9S_MB_2U(SCH_1):GND
  CT69  GND            VSS810  @S9S_MB_2U_LIB.S9S_MB_2U(SCH_1):GND
  CT12  GND            VSS805  @S9S_MB_2U_LIB.S9S_MB_2U(SCH_1):GND
  CT10  GND            VSS804  @S9S_MB_2U_LIB.S9S_MB_2U(SCH_1):GND
  CR90  GND            VSS803  @S9S_MB_2U_LIB.S9S_MB_2U(SCH_1):GND
  CR9  GND            VSS801  @S9S_MB_2U_LIB.S9S_MB_2U(SCH_1):GND
  CR88  GND            VSS800  @S9S_MB_2U_LIB.S9S_MB_2U(SCH_1):GND
  CR84  GND            VSS797  @S9S_MB_2U_LIB.S9S_MB_2U(SCH_1):GND
  CR64  GND            VSS796  @S9S_MB_2U_LIB.S9S_MB_2U(SCH_1):GND
  CR62  GND            VSS795  @S9S_MB_2U_LIB.S9S_MB_2U(SCH_1):GND
  CR5  GND            VSS794  @S9S_MB_2U_LIB.S9S_MB_2U(SCH_1):GND
  CR17  GND            VSS793  @S9S_MB_2U_LIB.S9S_MB_2U(SCH_1):GND
  CR13  GND            VSS792  @S9S_MB_2U_LIB.S9S_MB_2U(SCH_1):GND
  CR11  GND            VSS790  @S9S_MB_2U_LIB.S9S_MB_2U(SCH_1):GND
  CR1  GND            VSS789  @S9S_MB_2U_LIB.S9S_MB_2U(SCH_1):GND
  CP91  GND            VSS788  @S9S_MB_2U_LIB.S9S_MB_2U(SCH_1):GND
  CP87  GND            VSS787  @S9S_MB_2U_LIB.S9S_MB_2U(SCH_1):GND
  CP83  GND            VSS786  @S9S_MB_2U_LIB.S9S_MB_2U(SCH_1):GND
  CP8  GND            VSS785  @S9S_MB_2U_LIB.S9S_MB_2U(SCH_1):GND
  CP77  GND            VSS784  @S9S_MB_2U_LIB.S9S_MB_2U(SCH_1):GND
  CP75  GND            VSS783  @S9S_MB_2U_LIB.S9S_MB_2U(SCH_1):GND
  CP4  GND            VSS782  @S9S_MB_2U_LIB.S9S_MB_2U(SCH_1):GND
  CP18  GND            VSS781  @S9S_MB_2U_LIB.S9S_MB_2U(SCH_1):GND
  CP12  GND            VSS780  @S9S_MB_2U_LIB.S9S_MB_2U(SCH_1):GND
  CN86  GND            VSS779  @S9S_MB_2U_LIB.S9S_MB_2U(SCH_1):GND
  CN84  GND            VSS778  @S9S_MB_2U_LIB.S9S_MB_2U(SCH_1):GND
  CN74  GND            VSS777  @S9S_MB_2U_LIB.S9S_MB_2U(SCH_1):GND
  CN72  GND            VSS775  @S9S_MB_2U_LIB.S9S_MB_2U(SCH_1):GND
  CN70  GND            VSS774  @S9S_MB_2U_LIB.S9S_MB_2U(SCH_1):GND
  CN68  GND            VSS773  @S9S_MB_2U_LIB.S9S_MB_2U(SCH_1):GND
  CM85  GND            VSS772  @S9S_MB_2U_LIB.S9S_MB_2U(SCH_1):GND
  CM83  GND            VSS771  @S9S_MB_2U_LIB.S9S_MB_2U(SCH_1):GND
  CM81  GND            VSS770  @S9S_MB_2U_LIB.S9S_MB_2U(SCH_1):GND
  CM8  GND            VSS769  @S9S_MB_2U_LIB.S9S_MB_2U(SCH_1):GND
  CM79  GND            VSS768  @S9S_MB_2U_LIB.S9S_MB_2U(SCH_1):GND
  CM67  GND            VSS767  @S9S_MB_2U_LIB.S9S_MB_2U(SCH_1):GND
  CM65  GND            VSS766  @S9S_MB_2U_LIB.S9S_MB_2U(SCH_1):GND
  CM61  GND            VSS765  @S9S_MB_2U_LIB.S9S_MB_2U(SCH_1):GND
  CM4  GND            VSS764  @S9S_MB_2U_LIB.S9S_MB_2U(SCH_1):GND
  CM24  GND            VSS763  @S9S_MB_2U_LIB.S9S_MB_2U(SCH_1):GND
  CM20  GND            VSS762  @S9S_MB_2U_LIB.S9S_MB_2U(SCH_1):GND
  CM12  GND            VSS761  @S9S_MB_2U_LIB.S9S_MB_2U(SCH_1):GND
  CL9  GND            VSS760  @S9S_MB_2U_LIB.S9S_MB_2U(SCH_1):GND
  CL82  GND            VSS759  @S9S_MB_2U_LIB.S9S_MB_2U(SCH_1):GND
  CL80  GND            VSS758  @S9S_MB_2U_LIB.S9S_MB_2U(SCH_1):GND
  CL78  GND            VSS757  @S9S_MB_2U_LIB.S9S_MB_2U(SCH_1):GND
  CL74  GND            VSS756  @S9S_MB_2U_LIB.S9S_MB_2U(SCH_1):GND
  CL62  GND            VSS755  @S9S_MB_2U_LIB.S9S_MB_2U(SCH_1):GND
  CL5  GND            VSS754  @S9S_MB_2U_LIB.S9S_MB_2U(SCH_1):GND
  CL17  GND            VSS752  @S9S_MB_2U_LIB.S9S_MB_2U(SCH_1):GND
  CL13  GND            VSS751  @S9S_MB_2U_LIB.S9S_MB_2U(SCH_1):GND
  CL1  GND            VSS750  @S9S_MB_2U_LIB.S9S_MB_2U(SCH_1):GND
  CK81  GND            VSS749  @S9S_MB_2U_LIB.S9S_MB_2U(SCH_1):GND
  CK69  GND            VSS745  @S9S_MB_2U_LIB.S9S_MB_2U(SCH_1):GND
  CK63  GND            VSS744  @S9S_MB_2U_LIB.S9S_MB_2U(SCH_1):GND
  DB75  GND            VSS719  @S9S_MB_2U_LIB.S9S_MB_2U(SCH_1):GND
  DB69  GND            VSS717  @S9S_MB_2U_LIB.S9S_MB_2U(SCH_1):GND
  DB63  GND            VSS715  @S9S_MB_2U_LIB.S9S_MB_2U(SCH_1):GND
  DB59  GND            VSS714  @S9S_MB_2U_LIB.S9S_MB_2U(SCH_1):GND
  DB53  GND            VSS712  @S9S_MB_2U_LIB.S9S_MB_2U(SCH_1):GND
  DB51  GND            VSS711  @S9S_MB_2U_LIB.S9S_MB_2U(SCH_1):GND
  DB44  GND            VSS709  @S9S_MB_2U_LIB.S9S_MB_2U(SCH_1):GND
  DB34  GND            VSS705  @S9S_MB_2U_LIB.S9S_MB_2U(SCH_1):GND
  DB26  GND            VSS702  @S9S_MB_2U_LIB.S9S_MB_2U(SCH_1):GND
  DB20  GND            VSS700  @S9S_MB_2U_LIB.S9S_MB_2U(SCH_1):GND
  DB16  GND            VSS699  @S9S_MB_2U_LIB.S9S_MB_2U(SCH_1):GND
  DA68  GND            VSS690  @S9S_MB_2U_LIB.S9S_MB_2U(SCH_1):GND
  DA43  GND            VSS679  @S9S_MB_2U_LIB.S9S_MB_2U(SCH_1):GND
  CY4  GND            VSS611  @S9S_MB_2U_LIB.S9S_MB_2U(SCH_1):GND
  CW70  GND            VSS595  @S9S_MB_2U_LIB.S9S_MB_2U(SCH_1):GND
  CW33  GND            VSS583  @S9S_MB_2U_LIB.S9S_MB_2U(SCH_1):GND
  CV79  GND            VSS571  @S9S_MB_2U_LIB.S9S_MB_2U(SCH_1):GND
  CV26  GND            VSS562  @S9S_MB_2U_LIB.S9S_MB_2U(SCH_1):GND
  CV16  GND            VSS558  @S9S_MB_2U_LIB.S9S_MB_2U(SCH_1):GND
  CU78  GND            VSS554  @S9S_MB_2U_LIB.S9S_MB_2U(SCH_1):GND
  CU72  GND            VSS553  @S9S_MB_2U_LIB.S9S_MB_2U(SCH_1):GND
  CU25  GND            VSS544  @S9S_MB_2U_LIB.S9S_MB_2U(SCH_1):GND
  CT89  GND            VSS537  @S9S_MB_2U_LIB.S9S_MB_2U(SCH_1):GND
  CT8  GND            VSS534  @S9S_MB_2U_LIB.S9S_MB_2U(SCH_1):GND
  CT4  GND            VSS526  @S9S_MB_2U_LIB.S9S_MB_2U(SCH_1):GND
  CT16  GND            VSS521  @S9S_MB_2U_LIB.S9S_MB_2U(SCH_1):GND
  CR78  GND            VSS514  @S9S_MB_2U_LIB.S9S_MB_2U(SCH_1):GND
  CP79  GND            VSS493  @S9S_MB_2U_LIB.S9S_MB_2U(SCH_1):GND
  CP16  GND            VSS478  @S9S_MB_2U_LIB.S9S_MB_2U(SCH_1):GND
  CN76  GND            VSS471  @S9S_MB_2U_LIB.S9S_MB_2U(SCH_1):GND
  CM22  GND            VSS438  @S9S_MB_2U_LIB.S9S_MB_2U(SCH_1):GND
  CM16  GND            VSS436  @S9S_MB_2U_LIB.S9S_MB_2U(SCH_1):GND

SOCKET4677_AZIFS054P001C01  I2   U1     [SOCKET4677_AZIFS054P001C01-SOCA]
  DL9  GND            VSS1099  @S9S_MB_2U_LIB.S9S_MB_2U(SCH_1):GND
  DL88  GND            VSS1098  @S9S_MB_2U_LIB.S9S_MB_2U(SCH_1):GND
  DL84  GND            VSS1096  @S9S_MB_2U_LIB.S9S_MB_2U(SCH_1):GND
  DL39  GND            VSS1095  @S9S_MB_2U_LIB.S9S_MB_2U(SCH_1):GND
  DK91  GND            VSS1094  @S9S_MB_2U_LIB.S9S_MB_2U(SCH_1):GND
  DK87  GND            VSS1093  @S9S_MB_2U_LIB.S9S_MB_2U(SCH_1):GND
  DK83  GND            VSS1092  @S9S_MB_2U_LIB.S9S_MB_2U(SCH_1):GND
  DK81  GND            VSS1091  @S9S_MB_2U_LIB.S9S_MB_2U(SCH_1):GND
  DK8  GND            VSS1090  @S9S_MB_2U_LIB.S9S_MB_2U(SCH_1):GND
  DK79  GND            VSS1089  @S9S_MB_2U_LIB.S9S_MB_2U(SCH_1):GND
  DK77  GND            VSS1088  @S9S_MB_2U_LIB.S9S_MB_2U(SCH_1):GND
  DK73  GND            VSS1087  @S9S_MB_2U_LIB.S9S_MB_2U(SCH_1):GND
  DK49  GND            VSS1086  @S9S_MB_2U_LIB.S9S_MB_2U(SCH_1):GND
  DK4  GND            VSS1085  @S9S_MB_2U_LIB.S9S_MB_2U(SCH_1):GND
  DK36  GND            VSS1084  @S9S_MB_2U_LIB.S9S_MB_2U(SCH_1):GND
  DK30  GND            VSS1083  @S9S_MB_2U_LIB.S9S_MB_2U(SCH_1):GND
  DK16  GND            VSS1082  @S9S_MB_2U_LIB.S9S_MB_2U(SCH_1):GND
  DJ88  GND            VSS1081  @S9S_MB_2U_LIB.S9S_MB_2U(SCH_1):GND
  DJ84  GND            VSS1080  @S9S_MB_2U_LIB.S9S_MB_2U(SCH_1):GND
  DJ82  GND            VSS1079  @S9S_MB_2U_LIB.S9S_MB_2U(SCH_1):GND
  DJ80  GND            VSS1078  @S9S_MB_2U_LIB.S9S_MB_2U(SCH_1):GND
  DJ74  GND            VSS1076  @S9S_MB_2U_LIB.S9S_MB_2U(SCH_1):GND
  DJ72  GND            VSS1075  @S9S_MB_2U_LIB.S9S_MB_2U(SCH_1):GND
  DJ66  GND            VSS1074  @S9S_MB_2U_LIB.S9S_MB_2U(SCH_1):GND
  DJ60  GND            VSS1073  @S9S_MB_2U_LIB.S9S_MB_2U(SCH_1):GND
  DJ56  GND            VSS1072  @S9S_MB_2U_LIB.S9S_MB_2U(SCH_1):GND
  DJ50  GND            VSS1071  @S9S_MB_2U_LIB.S9S_MB_2U(SCH_1):GND
  DJ48  GND            VSS1070  @S9S_MB_2U_LIB.S9S_MB_2U(SCH_1):GND
  DJ43  GND            VSS1069  @S9S_MB_2U_LIB.S9S_MB_2U(SCH_1):GND
  DJ41  GND            VSS1068  @S9S_MB_2U_LIB.S9S_MB_2U(SCH_1):GND
  DJ37  GND            VSS1067  @S9S_MB_2U_LIB.S9S_MB_2U(SCH_1):GND
  DJ31  GND            VSS1066  @S9S_MB_2U_LIB.S9S_MB_2U(SCH_1):GND
  DJ29  GND            VSS1065  @S9S_MB_2U_LIB.S9S_MB_2U(SCH_1):GND
  DJ23  GND            VSS1062  @S9S_MB_2U_LIB.S9S_MB_2U(SCH_1):GND
  DJ19  GND            VSS1061  @S9S_MB_2U_LIB.S9S_MB_2U(SCH_1):GND
  DH85  GND            VSS1058  @S9S_MB_2U_LIB.S9S_MB_2U(SCH_1):GND
  DH8  GND            VSS1057  @S9S_MB_2U_LIB.S9S_MB_2U(SCH_1):GND
  DH77  GND            VSS1056  @S9S_MB_2U_LIB.S9S_MB_2U(SCH_1):GND
  DH71  GND            VSS1055  @S9S_MB_2U_LIB.S9S_MB_2U(SCH_1):GND
  DH65  GND            VSS1053  @S9S_MB_2U_LIB.S9S_MB_2U(SCH_1):GND
  DH57  GND            VSS1049  @S9S_MB_2U_LIB.S9S_MB_2U(SCH_1):GND
  DH47  GND            VSS1046  @S9S_MB_2U_LIB.S9S_MB_2U(SCH_1):GND
  DH40  GND            VSS1045  @S9S_MB_2U_LIB.S9S_MB_2U(SCH_1):GND
  DH4  GND            VSS1044  @S9S_MB_2U_LIB.S9S_MB_2U(SCH_1):GND
  DH38  GND            VSS1043  @S9S_MB_2U_LIB.S9S_MB_2U(SCH_1):GND
  DH32  GND            VSS1042  @S9S_MB_2U_LIB.S9S_MB_2U(SCH_1):GND
  DH28  GND            VSS1041  @S9S_MB_2U_LIB.S9S_MB_2U(SCH_1):GND
  DH22  GND            VSS1040  @S9S_MB_2U_LIB.S9S_MB_2U(SCH_1):GND
  DH12  GND            VSS1039  @S9S_MB_2U_LIB.S9S_MB_2U(SCH_1):GND
  DG9  GND            VSS1038  @S9S_MB_2U_LIB.S9S_MB_2U(SCH_1):GND
  DG88  GND            VSS1037  @S9S_MB_2U_LIB.S9S_MB_2U(SCH_1):GND
  DG84  GND            VSS1035  @S9S_MB_2U_LIB.S9S_MB_2U(SCH_1):GND
  DG80  GND            VSS1034  @S9S_MB_2U_LIB.S9S_MB_2U(SCH_1):GND
  DG76  GND            VSS1033  @S9S_MB_2U_LIB.S9S_MB_2U(SCH_1):GND
  DG70  GND            VSS1032  @S9S_MB_2U_LIB.S9S_MB_2U(SCH_1):GND
  DG5  GND            VSS1031  @S9S_MB_2U_LIB.S9S_MB_2U(SCH_1):GND
  DG45  GND            VSS1030  @S9S_MB_2U_LIB.S9S_MB_2U(SCH_1):GND
  DG39  GND            VSS1027  @S9S_MB_2U_LIB.S9S_MB_2U(SCH_1):GND
  DG33  GND            VSS1024  @S9S_MB_2U_LIB.S9S_MB_2U(SCH_1):GND
  DG27  GND            VSS1022  @S9S_MB_2U_LIB.S9S_MB_2U(SCH_1):GND
  DF87  GND            VSS1020  @S9S_MB_2U_LIB.S9S_MB_2U(SCH_1):GND
  DF8  GND            VSS1019  @S9S_MB_2U_LIB.S9S_MB_2U(SCH_1):GND
  DF79  GND            VSS1018  @S9S_MB_2U_LIB.S9S_MB_2U(SCH_1):GND
  DF4  GND            VSS1017  @S9S_MB_2U_LIB.S9S_MB_2U(SCH_1):GND
  DE88  GND            VSS1015  @S9S_MB_2U_LIB.S9S_MB_2U(SCH_1):GND
  DE84  GND            VSS1012  @S9S_MB_2U_LIB.S9S_MB_2U(SCH_1):GND
  DE82  GND            VSS1011  @S9S_MB_2U_LIB.S9S_MB_2U(SCH_1):GND
  DE76  GND            VSS1010  @S9S_MB_2U_LIB.S9S_MB_2U(SCH_1):GND
  DE74  GND            VSS1009  @S9S_MB_2U_LIB.S9S_MB_2U(SCH_1):GND
  DE72  GND            VSS1008  @S9S_MB_2U_LIB.S9S_MB_2U(SCH_1):GND
  DE68  GND            VSS1007  @S9S_MB_2U_LIB.S9S_MB_2U(SCH_1):GND
  DE66  GND            VSS1004  @S9S_MB_2U_LIB.S9S_MB_2U(SCH_1):GND
  DE64  GND            VSS1001  @S9S_MB_2U_LIB.S9S_MB_2U(SCH_1):GND
  DE62  GND            VSS999  @S9S_MB_2U_LIB.S9S_MB_2U(SCH_1):GND
  DE60  GND            VSS997  @S9S_MB_2U_LIB.S9S_MB_2U(SCH_1):GND
  DE58  GND            VSS996  @S9S_MB_2U_LIB.S9S_MB_2U(SCH_1):GND
  DE56  GND            VSS995  @S9S_MB_2U_LIB.S9S_MB_2U(SCH_1):GND
  DE54  GND            VSS994  @S9S_MB_2U_LIB.S9S_MB_2U(SCH_1):GND
  DE52  GND            VSS992  @S9S_MB_2U_LIB.S9S_MB_2U(SCH_1):GND
  DE50  GND            VSS991  @S9S_MB_2U_LIB.S9S_MB_2U(SCH_1):GND
  DE48  GND            VSS989  @S9S_MB_2U_LIB.S9S_MB_2U(SCH_1):GND
  DE45  GND            VSS988  @S9S_MB_2U_LIB.S9S_MB_2U(SCH_1):GND
  DE43  GND            VSS987  @S9S_MB_2U_LIB.S9S_MB_2U(SCH_1):GND
  DE41  GND            VSS986  @S9S_MB_2U_LIB.S9S_MB_2U(SCH_1):GND
  DE37  GND            VSS984  @S9S_MB_2U_LIB.S9S_MB_2U(SCH_1):GND
  DE35  GND            VSS983  @S9S_MB_2U_LIB.S9S_MB_2U(SCH_1):GND
  DE33  GND            VSS982  @S9S_MB_2U_LIB.S9S_MB_2U(SCH_1):GND
  DE31  GND            VSS981  @S9S_MB_2U_LIB.S9S_MB_2U(SCH_1):GND
  DE29  GND            VSS978  @S9S_MB_2U_LIB.S9S_MB_2U(SCH_1):GND
  DE27  GND            VSS977  @S9S_MB_2U_LIB.S9S_MB_2U(SCH_1):GND
  DE25  GND            VSS975  @S9S_MB_2U_LIB.S9S_MB_2U(SCH_1):GND
  DE23  GND            VSS974  @S9S_MB_2U_LIB.S9S_MB_2U(SCH_1):GND
  DE21  GND            VSS972  @S9S_MB_2U_LIB.S9S_MB_2U(SCH_1):GND
  DE19  GND            VSS971  @S9S_MB_2U_LIB.S9S_MB_2U(SCH_1):GND
  DE17  GND            VSS970  @S9S_MB_2U_LIB.S9S_MB_2U(SCH_1):GND
  DD8  GND            VSS967  @S9S_MB_2U_LIB.S9S_MB_2U(SCH_1):GND
  DD79  GND            VSS965  @S9S_MB_2U_LIB.S9S_MB_2U(SCH_1):GND
  DD4  GND            VSS964  @S9S_MB_2U_LIB.S9S_MB_2U(SCH_1):GND
  DC9  GND            VSS963  @S9S_MB_2U_LIB.S9S_MB_2U(SCH_1):GND
  DC88  GND            VSS962  @S9S_MB_2U_LIB.S9S_MB_2U(SCH_1):GND
  DC84  GND            VSS961  @S9S_MB_2U_LIB.S9S_MB_2U(SCH_1):GND
  DC80  GND            VSS960  @S9S_MB_2U_LIB.S9S_MB_2U(SCH_1):GND
  DC78  GND            VSS958  @S9S_MB_2U_LIB.S9S_MB_2U(SCH_1):GND
  DC76  GND            VSS956  @S9S_MB_2U_LIB.S9S_MB_2U(SCH_1):GND
  DC70  GND            VSS954  @S9S_MB_2U_LIB.S9S_MB_2U(SCH_1):GND
  DC5  GND            VSS953  @S9S_MB_2U_LIB.S9S_MB_2U(SCH_1):GND
  DC45  GND            VSS952  @S9S_MB_2U_LIB.S9S_MB_2U(SCH_1):GND
  DC39  GND            VSS951  @S9S_MB_2U_LIB.S9S_MB_2U(SCH_1):GND
  DC33  GND            VSS950  @S9S_MB_2U_LIB.S9S_MB_2U(SCH_1):GND
  DC27  GND            VSS949  @S9S_MB_2U_LIB.S9S_MB_2U(SCH_1):GND
  DL52  GND            VSS909  @S9S_MB_2U_LIB.S9S_MB_2U(SCH_1):GND
  DL5  GND            VSS908  @S9S_MB_2U_LIB.S9S_MB_2U(SCH_1):GND
  DL17  GND            VSS905  @S9S_MB_2U_LIB.S9S_MB_2U(SCH_1):GND
  DL13  GND            VSS904  @S9S_MB_2U_LIB.S9S_MB_2U(SCH_1):GND
  DL1  GND            VSS903  @S9S_MB_2U_LIB.S9S_MB_2U(SCH_1):GND
  DK67  GND            VSS894  @S9S_MB_2U_LIB.S9S_MB_2U(SCH_1):GND
  DK61  GND            VSS893  @S9S_MB_2U_LIB.S9S_MB_2U(SCH_1):GND
  DK55  GND            VSS890  @S9S_MB_2U_LIB.S9S_MB_2U(SCH_1):GND
  DK42  GND            VSS887  @S9S_MB_2U_LIB.S9S_MB_2U(SCH_1):GND
  DK24  GND            VSS883  @S9S_MB_2U_LIB.S9S_MB_2U(SCH_1):GND
  DK18  GND            VSS882  @S9S_MB_2U_LIB.S9S_MB_2U(SCH_1):GND
  DK12  GND            VSS880  @S9S_MB_2U_LIB.S9S_MB_2U(SCH_1):GND
  DJ68  GND            VSS872  @S9S_MB_2U_LIB.S9S_MB_2U(SCH_1):GND
  DJ62  GND            VSS870  @S9S_MB_2U_LIB.S9S_MB_2U(SCH_1):GND
  DJ54  GND            VSS867  @S9S_MB_2U_LIB.S9S_MB_2U(SCH_1):GND
  DJ35  GND            VSS861  @S9S_MB_2U_LIB.S9S_MB_2U(SCH_1):GND
  DJ25  GND            VSS857  @S9S_MB_2U_LIB.S9S_MB_2U(SCH_1):GND
  DH75  GND            VSS849  @S9S_MB_2U_LIB.S9S_MB_2U(SCH_1):GND
  DH69  GND            VSS847  @S9S_MB_2U_LIB.S9S_MB_2U(SCH_1):GND
  DH63  GND            VSS845  @S9S_MB_2U_LIB.S9S_MB_2U(SCH_1):GND
  DH59  GND            VSS844  @S9S_MB_2U_LIB.S9S_MB_2U(SCH_1):GND
  DH53  GND            VSS842  @S9S_MB_2U_LIB.S9S_MB_2U(SCH_1):GND
  DH51  GND            VSS841  @S9S_MB_2U_LIB.S9S_MB_2U(SCH_1):GND
  DH44  GND            VSS839  @S9S_MB_2U_LIB.S9S_MB_2U(SCH_1):GND
  DH34  GND            VSS835  @S9S_MB_2U_LIB.S9S_MB_2U(SCH_1):GND
  DH26  GND            VSS832  @S9S_MB_2U_LIB.S9S_MB_2U(SCH_1):GND
  DH20  GND            VSS830  @S9S_MB_2U_LIB.S9S_MB_2U(SCH_1):GND
  DH16  GND            VSS829  @S9S_MB_2U_LIB.S9S_MB_2U(SCH_1):GND
  DG64  GND            VSS821  @S9S_MB_2U_LIB.S9S_MB_2U(SCH_1):GND
  DG58  GND            VSS820  @S9S_MB_2U_LIB.S9S_MB_2U(SCH_1):GND
  DG52  GND            VSS817  @S9S_MB_2U_LIB.S9S_MB_2U(SCH_1):GND
  DG21  GND            VSS809  @S9S_MB_2U_LIB.S9S_MB_2U(SCH_1):GND
  DG13  GND            VSS808  @S9S_MB_2U_LIB.S9S_MB_2U(SCH_1):GND
  DG1  GND            VSS807  @S9S_MB_2U_LIB.S9S_MB_2U(SCH_1):GND
  DF91  GND            VSS806  @S9S_MB_2U_LIB.S9S_MB_2U(SCH_1):GND
  DF49  GND            VSS802  @S9S_MB_2U_LIB.S9S_MB_2U(SCH_1):GND
  DF16  GND            VSS799  @S9S_MB_2U_LIB.S9S_MB_2U(SCH_1):GND
  DF12  GND            VSS798  @S9S_MB_2U_LIB.S9S_MB_2U(SCH_1):GND
  DE70  GND            VSS791  @S9S_MB_2U_LIB.S9S_MB_2U(SCH_1):GND
  DE39  GND            VSS776  @S9S_MB_2U_LIB.S9S_MB_2U(SCH_1):GND
  DD49  GND            VSS753  @S9S_MB_2U_LIB.S9S_MB_2U(SCH_1):GND
  DD16  GND            VSS748  @S9S_MB_2U_LIB.S9S_MB_2U(SCH_1):GND
  DD12  GND            VSS747  @S9S_MB_2U_LIB.S9S_MB_2U(SCH_1):GND
  DC64  GND            VSS739  @S9S_MB_2U_LIB.S9S_MB_2U(SCH_1):GND
  DC58  GND            VSS738  @S9S_MB_2U_LIB.S9S_MB_2U(SCH_1):GND
  DC52  GND            VSS735  @S9S_MB_2U_LIB.S9S_MB_2U(SCH_1):GND
  DC21  GND            VSS726  @S9S_MB_2U_LIB.S9S_MB_2U(SCH_1):GND
  DC13  GND            VSS725  @S9S_MB_2U_LIB.S9S_MB_2U(SCH_1):GND
  DC1  GND            VSS724  @S9S_MB_2U_LIB.S9S_MB_2U(SCH_1):GND
  DB91  GND            VSS723  @S9S_MB_2U_LIB.S9S_MB_2U(SCH_1):GND

SOCKET4677_AZIFS054P001C01  I8   U1     [SOCKET4677_AZIFS054P001C01-SOCA]
  DW9  GND            VSS1268  @S9S_MB_2U_LIB.S9S_MB_2U(SCH_1):GND
  DW64  GND            VSS1256  @S9S_MB_2U_LIB.S9S_MB_2U(SCH_1):GND
  DW62  GND            VSS1255  @S9S_MB_2U_LIB.S9S_MB_2U(SCH_1):GND
  DW58  GND            VSS1254  @S9S_MB_2U_LIB.S9S_MB_2U(SCH_1):GND
  DW56  GND            VSS1253  @S9S_MB_2U_LIB.S9S_MB_2U(SCH_1):GND
  DW54  GND            VSS1252  @S9S_MB_2U_LIB.S9S_MB_2U(SCH_1):GND
  DW52  GND            VSS1251  @S9S_MB_2U_LIB.S9S_MB_2U(SCH_1):GND
  DW50  GND            VSS1250  @S9S_MB_2U_LIB.S9S_MB_2U(SCH_1):GND
  DW5  GND            VSS1249  @S9S_MB_2U_LIB.S9S_MB_2U(SCH_1):GND
  DW48  GND            VSS1248  @S9S_MB_2U_LIB.S9S_MB_2U(SCH_1):GND
  DW45  GND            VSS1247  @S9S_MB_2U_LIB.S9S_MB_2U(SCH_1):GND
  DW43  GND            VSS1246  @S9S_MB_2U_LIB.S9S_MB_2U(SCH_1):GND
  DW41  GND            VSS1245  @S9S_MB_2U_LIB.S9S_MB_2U(SCH_1):GND
  DW39  GND            VSS1244  @S9S_MB_2U_LIB.S9S_MB_2U(SCH_1):GND
  DW37  GND            VSS1243  @S9S_MB_2U_LIB.S9S_MB_2U(SCH_1):GND
  DW35  GND            VSS1242  @S9S_MB_2U_LIB.S9S_MB_2U(SCH_1):GND
  DW33  GND            VSS1241  @S9S_MB_2U_LIB.S9S_MB_2U(SCH_1):GND
  DW31  GND            VSS1240  @S9S_MB_2U_LIB.S9S_MB_2U(SCH_1):GND
  DW29  GND            VSS1239  @S9S_MB_2U_LIB.S9S_MB_2U(SCH_1):GND
  DW27  GND            VSS1238  @S9S_MB_2U_LIB.S9S_MB_2U(SCH_1):GND
  DW25  GND            VSS1236  @S9S_MB_2U_LIB.S9S_MB_2U(SCH_1):GND
  DW23  GND            VSS1234  @S9S_MB_2U_LIB.S9S_MB_2U(SCH_1):GND
  DW19  GND            VSS1233  @S9S_MB_2U_LIB.S9S_MB_2U(SCH_1):GND
  DW17  GND            VSS1231  @S9S_MB_2U_LIB.S9S_MB_2U(SCH_1):GND
  DW13  GND            VSS1230  @S9S_MB_2U_LIB.S9S_MB_2U(SCH_1):GND
  DW1  GND            VSS1229  @S9S_MB_2U_LIB.S9S_MB_2U(SCH_1):GND
  DV91  GND            VSS1228  @S9S_MB_2U_LIB.S9S_MB_2U(SCH_1):GND
  DV87  GND            VSS1227  @S9S_MB_2U_LIB.S9S_MB_2U(SCH_1):GND
  DV83  GND            VSS1226  @S9S_MB_2U_LIB.S9S_MB_2U(SCH_1):GND
  DV81  GND            VSS1222  @S9S_MB_2U_LIB.S9S_MB_2U(SCH_1):GND
  DV8  GND            VSS1221  @S9S_MB_2U_LIB.S9S_MB_2U(SCH_1):GND
  DV79  GND            VSS1219  @S9S_MB_2U_LIB.S9S_MB_2U(SCH_1):GND
  DV77  GND            VSS1218  @S9S_MB_2U_LIB.S9S_MB_2U(SCH_1):GND
  DU88  GND            VSS1216  @S9S_MB_2U_LIB.S9S_MB_2U(SCH_1):GND
  DU84  GND            VSS1215  @S9S_MB_2U_LIB.S9S_MB_2U(SCH_1):GND
  DU78  GND            VSS1214  @S9S_MB_2U_LIB.S9S_MB_2U(SCH_1):GND
  DU76  GND            VSS1213  @S9S_MB_2U_LIB.S9S_MB_2U(SCH_1):GND
  DU33  GND            VSS1212  @S9S_MB_2U_LIB.S9S_MB_2U(SCH_1):GND
  DU27  GND            VSS1211  @S9S_MB_2U_LIB.S9S_MB_2U(SCH_1):GND
  DU21  GND            VSS1209  @S9S_MB_2U_LIB.S9S_MB_2U(SCH_1):GND
  DT8  GND            VSS1207  @S9S_MB_2U_LIB.S9S_MB_2U(SCH_1):GND
  DT75  GND            VSS1206  @S9S_MB_2U_LIB.S9S_MB_2U(SCH_1):GND
  DT71  GND            VSS1205  @S9S_MB_2U_LIB.S9S_MB_2U(SCH_1):GND
  DT69  GND            VSS1204  @S9S_MB_2U_LIB.S9S_MB_2U(SCH_1):GND
  DT65  GND            VSS1203  @S9S_MB_2U_LIB.S9S_MB_2U(SCH_1):GND
  DT57  GND            VSS1202  @S9S_MB_2U_LIB.S9S_MB_2U(SCH_1):GND
  DT47  GND            VSS1201  @S9S_MB_2U_LIB.S9S_MB_2U(SCH_1):GND
  DT40  GND            VSS1199  @S9S_MB_2U_LIB.S9S_MB_2U(SCH_1):GND
  DT38  GND            VSS1196  @S9S_MB_2U_LIB.S9S_MB_2U(SCH_1):GND
  DT34  GND            VSS1194  @S9S_MB_2U_LIB.S9S_MB_2U(SCH_1):GND
  DT32  GND            VSS1192  @S9S_MB_2U_LIB.S9S_MB_2U(SCH_1):GND
  DT28  GND            VSS1191  @S9S_MB_2U_LIB.S9S_MB_2U(SCH_1):GND
  DT22  GND            VSS1190  @S9S_MB_2U_LIB.S9S_MB_2U(SCH_1):GND
  DT12  GND            VSS1189  @S9S_MB_2U_LIB.S9S_MB_2U(SCH_1):GND
  DR9  GND            VSS1187  @S9S_MB_2U_LIB.S9S_MB_2U(SCH_1):GND
  DR88  GND            VSS1186  @S9S_MB_2U_LIB.S9S_MB_2U(SCH_1):GND
  DR84  GND            VSS1184  @S9S_MB_2U_LIB.S9S_MB_2U(SCH_1):GND
  DR78  GND            VSS1183  @S9S_MB_2U_LIB.S9S_MB_2U(SCH_1):GND
  DR74  GND            VSS1182  @S9S_MB_2U_LIB.S9S_MB_2U(SCH_1):GND
  DR66  GND            VSS1181  @S9S_MB_2U_LIB.S9S_MB_2U(SCH_1):GND
  DR56  GND            VSS1179  @S9S_MB_2U_LIB.S9S_MB_2U(SCH_1):GND
  DR50  GND            VSS1178  @S9S_MB_2U_LIB.S9S_MB_2U(SCH_1):GND
  DR48  GND            VSS1177  @S9S_MB_2U_LIB.S9S_MB_2U(SCH_1):GND
  DR43  GND            VSS1176  @S9S_MB_2U_LIB.S9S_MB_2U(SCH_1):GND
  DR41  GND            VSS1175  @S9S_MB_2U_LIB.S9S_MB_2U(SCH_1):GND
  DR37  GND            VSS1174  @S9S_MB_2U_LIB.S9S_MB_2U(SCH_1):GND
  DR31  GND            VSS1173  @S9S_MB_2U_LIB.S9S_MB_2U(SCH_1):GND
  DR29  GND            VSS1172  @S9S_MB_2U_LIB.S9S_MB_2U(SCH_1):GND
  DR23  GND            VSS1169  @S9S_MB_2U_LIB.S9S_MB_2U(SCH_1):GND
  DR19  GND            VSS1166  @S9S_MB_2U_LIB.S9S_MB_2U(SCH_1):GND
  DR13  GND            VSS1164  @S9S_MB_2U_LIB.S9S_MB_2U(SCH_1):GND
  DR1  GND            VSS1162  @S9S_MB_2U_LIB.S9S_MB_2U(SCH_1):GND
  DP87  GND            VSS1160  @S9S_MB_2U_LIB.S9S_MB_2U(SCH_1):GND
  DP81  GND            VSS1159  @S9S_MB_2U_LIB.S9S_MB_2U(SCH_1):GND
  DP8  GND            VSS1157  @S9S_MB_2U_LIB.S9S_MB_2U(SCH_1):GND
  DP73  GND            VSS1154  @S9S_MB_2U_LIB.S9S_MB_2U(SCH_1):GND
  DP49  GND            VSS1153  @S9S_MB_2U_LIB.S9S_MB_2U(SCH_1):GND
  DP4  GND            VSS1152  @S9S_MB_2U_LIB.S9S_MB_2U(SCH_1):GND
  DP36  GND            VSS1151  @S9S_MB_2U_LIB.S9S_MB_2U(SCH_1):GND
  DP30  GND            VSS1150  @S9S_MB_2U_LIB.S9S_MB_2U(SCH_1):GND
  DP16  GND            VSS1149  @S9S_MB_2U_LIB.S9S_MB_2U(SCH_1):GND
  DN88  GND            VSS1148  @S9S_MB_2U_LIB.S9S_MB_2U(SCH_1):GND
  DN84  GND            VSS1147  @S9S_MB_2U_LIB.S9S_MB_2U(SCH_1):GND
  DN78  GND            VSS1143  @S9S_MB_2U_LIB.S9S_MB_2U(SCH_1):GND
  DM8  GND            VSS1140  @S9S_MB_2U_LIB.S9S_MB_2U(SCH_1):GND
  DM79  GND            VSS1139  @S9S_MB_2U_LIB.S9S_MB_2U(SCH_1):GND
  DM77  GND            VSS1138  @S9S_MB_2U_LIB.S9S_MB_2U(SCH_1):GND
  DM75  GND            VSS1137  @S9S_MB_2U_LIB.S9S_MB_2U(SCH_1):GND
  DM71  GND            VSS1136  @S9S_MB_2U_LIB.S9S_MB_2U(SCH_1):GND
  DM69  GND            VSS1135  @S9S_MB_2U_LIB.S9S_MB_2U(SCH_1):GND
  DM67  GND            VSS1134  @S9S_MB_2U_LIB.S9S_MB_2U(SCH_1):GND
  DM65  GND            VSS1133  @S9S_MB_2U_LIB.S9S_MB_2U(SCH_1):GND
  DM63  GND            VSS1132  @S9S_MB_2U_LIB.S9S_MB_2U(SCH_1):GND
  DM61  GND            VSS1130  @S9S_MB_2U_LIB.S9S_MB_2U(SCH_1):GND
  DM59  GND            VSS1128  @S9S_MB_2U_LIB.S9S_MB_2U(SCH_1):GND
  DM57  GND            VSS1127  @S9S_MB_2U_LIB.S9S_MB_2U(SCH_1):GND
  DM55  GND            VSS1124  @S9S_MB_2U_LIB.S9S_MB_2U(SCH_1):GND
  DM53  GND            VSS1123  @S9S_MB_2U_LIB.S9S_MB_2U(SCH_1):GND
  DM49  GND            VSS1122  @S9S_MB_2U_LIB.S9S_MB_2U(SCH_1):GND
  DM47  GND            VSS1121  @S9S_MB_2U_LIB.S9S_MB_2U(SCH_1):GND
  DM44  GND            VSS1120  @S9S_MB_2U_LIB.S9S_MB_2U(SCH_1):GND
  DM42  GND            VSS1119  @S9S_MB_2U_LIB.S9S_MB_2U(SCH_1):GND
  DM40  GND            VSS1118  @S9S_MB_2U_LIB.S9S_MB_2U(SCH_1):GND
  DM4  GND            VSS1117  @S9S_MB_2U_LIB.S9S_MB_2U(SCH_1):GND
  DM38  GND            VSS1114  @S9S_MB_2U_LIB.S9S_MB_2U(SCH_1):GND
  DM36  GND            VSS1113  @S9S_MB_2U_LIB.S9S_MB_2U(SCH_1):GND
  DM34  GND            VSS1110  @S9S_MB_2U_LIB.S9S_MB_2U(SCH_1):GND
  DM32  GND            VSS1109  @S9S_MB_2U_LIB.S9S_MB_2U(SCH_1):GND
  DM30  GND            VSS1108  @S9S_MB_2U_LIB.S9S_MB_2U(SCH_1):GND
  DM28  GND            VSS1107  @S9S_MB_2U_LIB.S9S_MB_2U(SCH_1):GND
  DM26  GND            VSS1106  @S9S_MB_2U_LIB.S9S_MB_2U(SCH_1):GND
  DM24  GND            VSS1105  @S9S_MB_2U_LIB.S9S_MB_2U(SCH_1):GND
  DM22  GND            VSS1104  @S9S_MB_2U_LIB.S9S_MB_2U(SCH_1):GND
  DM20  GND            VSS1103  @S9S_MB_2U_LIB.S9S_MB_2U(SCH_1):GND
  DM18  GND            VSS1102  @S9S_MB_2U_LIB.S9S_MB_2U(SCH_1):GND
  DM16  GND            VSS1101  @S9S_MB_2U_LIB.S9S_MB_2U(SCH_1):GND
  DM12  GND            VSS1100  @S9S_MB_2U_LIB.S9S_MB_2U(SCH_1):GND
  DW60  GND            VSS1097  @S9S_MB_2U_LIB.S9S_MB_2U(SCH_1):GND
  DW21  GND            VSS1077  @S9S_MB_2U_LIB.S9S_MB_2U(SCH_1):GND
  DV42  GND            VSS1064  @S9S_MB_2U_LIB.S9S_MB_2U(SCH_1):GND
  DV4  GND            VSS1063  @S9S_MB_2U_LIB.S9S_MB_2U(SCH_1):GND
  DV16  GND            VSS1060  @S9S_MB_2U_LIB.S9S_MB_2U(SCH_1):GND
  DV12  GND            VSS1059  @S9S_MB_2U_LIB.S9S_MB_2U(SCH_1):GND
  DU70  GND            VSS1054  @S9S_MB_2U_LIB.S9S_MB_2U(SCH_1):GND
  DU64  GND            VSS1052  @S9S_MB_2U_LIB.S9S_MB_2U(SCH_1):GND
  DU58  GND            VSS1051  @S9S_MB_2U_LIB.S9S_MB_2U(SCH_1):GND
  DU52  GND            VSS1050  @S9S_MB_2U_LIB.S9S_MB_2U(SCH_1):GND
  DU45  GND            VSS1048  @S9S_MB_2U_LIB.S9S_MB_2U(SCH_1):GND
  DU39  GND            VSS1047  @S9S_MB_2U_LIB.S9S_MB_2U(SCH_1):GND
  DT83  GND            VSS1036  @S9S_MB_2U_LIB.S9S_MB_2U(SCH_1):GND
  DT63  GND            VSS1029  @S9S_MB_2U_LIB.S9S_MB_2U(SCH_1):GND
  DT59  GND            VSS1028  @S9S_MB_2U_LIB.S9S_MB_2U(SCH_1):GND
  DT53  GND            VSS1026  @S9S_MB_2U_LIB.S9S_MB_2U(SCH_1):GND
  DT51  GND            VSS1025  @S9S_MB_2U_LIB.S9S_MB_2U(SCH_1):GND
  DT44  GND            VSS1023  @S9S_MB_2U_LIB.S9S_MB_2U(SCH_1):GND
  DT4  GND            VSS1021  @S9S_MB_2U_LIB.S9S_MB_2U(SCH_1):GND
  DT26  GND            VSS1016  @S9S_MB_2U_LIB.S9S_MB_2U(SCH_1):GND
  DT20  GND            VSS1014  @S9S_MB_2U_LIB.S9S_MB_2U(SCH_1):GND
  DT16  GND            VSS1013  @S9S_MB_2U_LIB.S9S_MB_2U(SCH_1):GND
  DR72  GND            VSS1006  @S9S_MB_2U_LIB.S9S_MB_2U(SCH_1):GND
  DR68  GND            VSS1005  @S9S_MB_2U_LIB.S9S_MB_2U(SCH_1):GND
  DR62  GND            VSS1003  @S9S_MB_2U_LIB.S9S_MB_2U(SCH_1):GND
  DR60  GND            VSS1002  @S9S_MB_2U_LIB.S9S_MB_2U(SCH_1):GND
  DR54  GND            VSS1000  @S9S_MB_2U_LIB.S9S_MB_2U(SCH_1):GND
  DR5  GND            VSS998  @S9S_MB_2U_LIB.S9S_MB_2U(SCH_1):GND
  DR35  GND            VSS993  @S9S_MB_2U_LIB.S9S_MB_2U(SCH_1):GND
  DR25  GND            VSS990  @S9S_MB_2U_LIB.S9S_MB_2U(SCH_1):GND
  DP91  GND            VSS985  @S9S_MB_2U_LIB.S9S_MB_2U(SCH_1):GND
  DP67  GND            VSS980  @S9S_MB_2U_LIB.S9S_MB_2U(SCH_1):GND
  DP61  GND            VSS979  @S9S_MB_2U_LIB.S9S_MB_2U(SCH_1):GND
  DP55  GND            VSS976  @S9S_MB_2U_LIB.S9S_MB_2U(SCH_1):GND
  DP42  GND            VSS973  @S9S_MB_2U_LIB.S9S_MB_2U(SCH_1):GND
  DP24  GND            VSS969  @S9S_MB_2U_LIB.S9S_MB_2U(SCH_1):GND
  DP18  GND            VSS968  @S9S_MB_2U_LIB.S9S_MB_2U(SCH_1):GND
  DP12  GND            VSS966  @S9S_MB_2U_LIB.S9S_MB_2U(SCH_1):GND
  DN52  GND            VSS959  @S9S_MB_2U_LIB.S9S_MB_2U(SCH_1):GND
  DN39  GND            VSS957  @S9S_MB_2U_LIB.S9S_MB_2U(SCH_1):GND
  DN17  GND            VSS955  @S9S_MB_2U_LIB.S9S_MB_2U(SCH_1):GND
  DM73  GND            VSS945  @S9S_MB_2U_LIB.S9S_MB_2U(SCH_1):GND
  DM51  GND            VSS934  @S9S_MB_2U_LIB.S9S_MB_2U(SCH_1):GND

SOCKET4677_AZIFS054P001C01  I5   U1     [SOCKET4677_AZIFS054P001C01-SOCA]
  EH4  GND            VSS1420  @S9S_MB_2U_LIB.S9S_MB_2U(SCH_1):GND
  EH30  GND            VSS1418  @S9S_MB_2U_LIB.S9S_MB_2U(SCH_1):GND
  EH24  GND            VSS1417  @S9S_MB_2U_LIB.S9S_MB_2U(SCH_1):GND
  EH16  GND            VSS1416  @S9S_MB_2U_LIB.S9S_MB_2U(SCH_1):GND
  EG90  GND            VSS1415  @S9S_MB_2U_LIB.S9S_MB_2U(SCH_1):GND
  EG9  GND            VSS1414  @S9S_MB_2U_LIB.S9S_MB_2U(SCH_1):GND
  EG88  GND            VSS1413  @S9S_MB_2U_LIB.S9S_MB_2U(SCH_1):GND
  EG86  GND            VSS1412  @S9S_MB_2U_LIB.S9S_MB_2U(SCH_1):GND
  EG84  GND            VSS1411  @S9S_MB_2U_LIB.S9S_MB_2U(SCH_1):GND
  EG82  GND            VSS1410  @S9S_MB_2U_LIB.S9S_MB_2U(SCH_1):GND
  EG39  GND            VSS1408  @S9S_MB_2U_LIB.S9S_MB_2U(SCH_1):GND
  EF87  GND            VSS1407  @S9S_MB_2U_LIB.S9S_MB_2U(SCH_1):GND
  EF85  GND            VSS1406  @S9S_MB_2U_LIB.S9S_MB_2U(SCH_1):GND
  EF8  GND            VSS1404  @S9S_MB_2U_LIB.S9S_MB_2U(SCH_1):GND
  EF77  GND            VSS1403  @S9S_MB_2U_LIB.S9S_MB_2U(SCH_1):GND
  EF71  GND            VSS1402  @S9S_MB_2U_LIB.S9S_MB_2U(SCH_1):GND
  EF69  GND            VSS1399  @S9S_MB_2U_LIB.S9S_MB_2U(SCH_1):GND
  EF67  GND            VSS1395  @S9S_MB_2U_LIB.S9S_MB_2U(SCH_1):GND
  EF65  GND            VSS1393  @S9S_MB_2U_LIB.S9S_MB_2U(SCH_1):GND
  EF63  GND            VSS1392  @S9S_MB_2U_LIB.S9S_MB_2U(SCH_1):GND
  EF61  GND            VSS1390  @S9S_MB_2U_LIB.S9S_MB_2U(SCH_1):GND
  EF59  GND            VSS1389  @S9S_MB_2U_LIB.S9S_MB_2U(SCH_1):GND
  EF57  GND            VSS1388  @S9S_MB_2U_LIB.S9S_MB_2U(SCH_1):GND
  EF55  GND            VSS1387  @S9S_MB_2U_LIB.S9S_MB_2U(SCH_1):GND
  EF53  GND            VSS1386  @S9S_MB_2U_LIB.S9S_MB_2U(SCH_1):GND
  EF49  GND            VSS1385  @S9S_MB_2U_LIB.S9S_MB_2U(SCH_1):GND
  EF47  GND            VSS1384  @S9S_MB_2U_LIB.S9S_MB_2U(SCH_1):GND
  EF44  GND            VSS1383  @S9S_MB_2U_LIB.S9S_MB_2U(SCH_1):GND
  EF42  GND            VSS1382  @S9S_MB_2U_LIB.S9S_MB_2U(SCH_1):GND
  EF40  GND            VSS1376  @S9S_MB_2U_LIB.S9S_MB_2U(SCH_1):GND
  EF4  GND            VSS1374  @S9S_MB_2U_LIB.S9S_MB_2U(SCH_1):GND
  EF38  GND            VSS1373  @S9S_MB_2U_LIB.S9S_MB_2U(SCH_1):GND
  EF36  GND            VSS1370  @S9S_MB_2U_LIB.S9S_MB_2U(SCH_1):GND
  EF34  GND            VSS1367  @S9S_MB_2U_LIB.S9S_MB_2U(SCH_1):GND
  EF32  GND            VSS1365  @S9S_MB_2U_LIB.S9S_MB_2U(SCH_1):GND
  EF30  GND            VSS1364  @S9S_MB_2U_LIB.S9S_MB_2U(SCH_1):GND
  EF28  GND            VSS1363  @S9S_MB_2U_LIB.S9S_MB_2U(SCH_1):GND
  EF26  GND            VSS1362  @S9S_MB_2U_LIB.S9S_MB_2U(SCH_1):GND
  EF24  GND            VSS1361  @S9S_MB_2U_LIB.S9S_MB_2U(SCH_1):GND
  EF22  GND            VSS1360  @S9S_MB_2U_LIB.S9S_MB_2U(SCH_1):GND
  EF20  GND            VSS1358  @S9S_MB_2U_LIB.S9S_MB_2U(SCH_1):GND
  EF2  GND            VSS1356  @S9S_MB_2U_LIB.S9S_MB_2U(SCH_1):GND
  EF18  GND            VSS1354  @S9S_MB_2U_LIB.S9S_MB_2U(SCH_1):GND
  EF16  GND            VSS1353  @S9S_MB_2U_LIB.S9S_MB_2U(SCH_1):GND
  EF12  GND            VSS1352  @S9S_MB_2U_LIB.S9S_MB_2U(SCH_1):GND
  EE88  GND            VSS1351  @S9S_MB_2U_LIB.S9S_MB_2U(SCH_1):GND
  EE80  GND            VSS1350  @S9S_MB_2U_LIB.S9S_MB_2U(SCH_1):GND
  EE78  GND            VSS1349  @S9S_MB_2U_LIB.S9S_MB_2U(SCH_1):GND
  ED8  GND            VSS1348  @S9S_MB_2U_LIB.S9S_MB_2U(SCH_1):GND
  ED49  GND            VSS1346  @S9S_MB_2U_LIB.S9S_MB_2U(SCH_1):GND
  ED4  GND            VSS1344  @S9S_MB_2U_LIB.S9S_MB_2U(SCH_1):GND
  ED36  GND            VSS1342  @S9S_MB_2U_LIB.S9S_MB_2U(SCH_1):GND
  ED30  GND            VSS1341  @S9S_MB_2U_LIB.S9S_MB_2U(SCH_1):GND
  ED24  GND            VSS1339  @S9S_MB_2U_LIB.S9S_MB_2U(SCH_1):GND
  ED16  GND            VSS1338  @S9S_MB_2U_LIB.S9S_MB_2U(SCH_1):GND
  EC9  GND            VSS1337  @S9S_MB_2U_LIB.S9S_MB_2U(SCH_1):GND
  EC88  GND            VSS1336  @S9S_MB_2U_LIB.S9S_MB_2U(SCH_1):GND
  EC84  GND            VSS1335  @S9S_MB_2U_LIB.S9S_MB_2U(SCH_1):GND
  EC82  GND            VSS1333  @S9S_MB_2U_LIB.S9S_MB_2U(SCH_1):GND
  EC74  GND            VSS1332  @S9S_MB_2U_LIB.S9S_MB_2U(SCH_1):GND
  EC72  GND            VSS1330  @S9S_MB_2U_LIB.S9S_MB_2U(SCH_1):GND
  EC66  GND            VSS1329  @S9S_MB_2U_LIB.S9S_MB_2U(SCH_1):GND
  EC56  GND            VSS1327  @S9S_MB_2U_LIB.S9S_MB_2U(SCH_1):GND
  EC50  GND            VSS1326  @S9S_MB_2U_LIB.S9S_MB_2U(SCH_1):GND
  EC48  GND            VSS1324  @S9S_MB_2U_LIB.S9S_MB_2U(SCH_1):GND
  EC43  GND            VSS1323  @S9S_MB_2U_LIB.S9S_MB_2U(SCH_1):GND
  EC41  GND            VSS1321  @S9S_MB_2U_LIB.S9S_MB_2U(SCH_1):GND
  EH6  GND            VSS1318  @S9S_MB_2U_LIB.S9S_MB_2U(SCH_1):GND
  EC37  GND            VSS1317  @S9S_MB_2U_LIB.S9S_MB_2U(SCH_1):GND
  EC31  GND            VSS1316  @S9S_MB_2U_LIB.S9S_MB_2U(SCH_1):GND
  EC29  GND            VSS1314  @S9S_MB_2U_LIB.S9S_MB_2U(SCH_1):GND
  EC23  GND            VSS1313  @S9S_MB_2U_LIB.S9S_MB_2U(SCH_1):GND
  EC19  GND            VSS1311  @S9S_MB_2U_LIB.S9S_MB_2U(SCH_1):GND
  EC13  GND            VSS1310  @S9S_MB_2U_LIB.S9S_MB_2U(SCH_1):GND
  EC1  GND            VSS1309  @S9S_MB_2U_LIB.S9S_MB_2U(SCH_1):GND
  EB87  GND            VSS1308  @S9S_MB_2U_LIB.S9S_MB_2U(SCH_1):GND
  EB83  GND            VSS1307  @S9S_MB_2U_LIB.S9S_MB_2U(SCH_1):GND
  EB8  GND            VSS1306  @S9S_MB_2U_LIB.S9S_MB_2U(SCH_1):GND
  EH18  GND            VSS1305  @S9S_MB_2U_LIB.S9S_MB_2U(SCH_1):GND
  EB79  GND            VSS1304  @S9S_MB_2U_LIB.S9S_MB_2U(SCH_1):GND
  EH14  GND            VSS1303  @S9S_MB_2U_LIB.S9S_MB_2U(SCH_1):GND
  EH12  GND            VSS1302  @S9S_MB_2U_LIB.S9S_MB_2U(SCH_1):GND
  EB75  GND            VSS1301  @S9S_MB_2U_LIB.S9S_MB_2U(SCH_1):GND
  EB71  GND            VSS1300  @S9S_MB_2U_LIB.S9S_MB_2U(SCH_1):GND
  EB69  GND            VSS1299  @S9S_MB_2U_LIB.S9S_MB_2U(SCH_1):GND
  EB65  GND            VSS1298  @S9S_MB_2U_LIB.S9S_MB_2U(SCH_1):GND
  EB57  GND            VSS1297  @S9S_MB_2U_LIB.S9S_MB_2U(SCH_1):GND
  EB47  GND            VSS1296  @S9S_MB_2U_LIB.S9S_MB_2U(SCH_1):GND
  EB40  GND            VSS1295  @S9S_MB_2U_LIB.S9S_MB_2U(SCH_1):GND
  EG7  GND            VSS1294  @S9S_MB_2U_LIB.S9S_MB_2U(SCH_1):GND
  EB38  GND            VSS1293  @S9S_MB_2U_LIB.S9S_MB_2U(SCH_1):GND
  EB32  GND            VSS1292  @S9S_MB_2U_LIB.S9S_MB_2U(SCH_1):GND
  EG52  GND            VSS1291  @S9S_MB_2U_LIB.S9S_MB_2U(SCH_1):GND
  EG5  GND            VSS1290  @S9S_MB_2U_LIB.S9S_MB_2U(SCH_1):GND
  EB28  GND            VSS1289  @S9S_MB_2U_LIB.S9S_MB_2U(SCH_1):GND
  EB22  GND            VSS1288  @S9S_MB_2U_LIB.S9S_MB_2U(SCH_1):GND
  EB12  GND            VSS1287  @S9S_MB_2U_LIB.S9S_MB_2U(SCH_1):GND
  EA88  GND            VSS1286  @S9S_MB_2U_LIB.S9S_MB_2U(SCH_1):GND
  EA84  GND            VSS1285  @S9S_MB_2U_LIB.S9S_MB_2U(SCH_1):GND
  EG13  GND            VSS1284  @S9S_MB_2U_LIB.S9S_MB_2U(SCH_1):GND
  EF89  GND            VSS1283  @S9S_MB_2U_LIB.S9S_MB_2U(SCH_1):GND
  EA80  GND            VSS1282  @S9S_MB_2U_LIB.S9S_MB_2U(SCH_1):GND
  EA78  GND            VSS1281  @S9S_MB_2U_LIB.S9S_MB_2U(SCH_1):GND
  EA76  GND            VSS1280  @S9S_MB_2U_LIB.S9S_MB_2U(SCH_1):GND
  EA70  GND            VSS1279  @S9S_MB_2U_LIB.S9S_MB_2U(SCH_1):GND
  EA33  GND            VSS1278  @S9S_MB_2U_LIB.S9S_MB_2U(SCH_1):GND
  EF75  GND            VSS1277  @S9S_MB_2U_LIB.S9S_MB_2U(SCH_1):GND
  EF73  GND            VSS1276  @S9S_MB_2U_LIB.S9S_MB_2U(SCH_1):GND
  EA27  GND            VSS1275  @S9S_MB_2U_LIB.S9S_MB_2U(SCH_1):GND
  EA21  GND            VSS1274  @S9S_MB_2U_LIB.S9S_MB_2U(SCH_1):GND
  DY8  GND            VSS1270  @S9S_MB_2U_LIB.S9S_MB_2U(SCH_1):GND
  DY77  GND            VSS1269  @S9S_MB_2U_LIB.S9S_MB_2U(SCH_1):GND
  DW88  GND            VSS1267  @S9S_MB_2U_LIB.S9S_MB_2U(SCH_1):GND
  DW84  GND            VSS1266  @S9S_MB_2U_LIB.S9S_MB_2U(SCH_1):GND
  EF51  GND            VSS1265  @S9S_MB_2U_LIB.S9S_MB_2U(SCH_1):GND
  DW82  GND            VSS1264  @S9S_MB_2U_LIB.S9S_MB_2U(SCH_1):GND
  DW80  GND            VSS1263  @S9S_MB_2U_LIB.S9S_MB_2U(SCH_1):GND
  DW76  GND            VSS1262  @S9S_MB_2U_LIB.S9S_MB_2U(SCH_1):GND
  DW74  GND            VSS1261  @S9S_MB_2U_LIB.S9S_MB_2U(SCH_1):GND
  DW72  GND            VSS1260  @S9S_MB_2U_LIB.S9S_MB_2U(SCH_1):GND
  DW70  GND            VSS1259  @S9S_MB_2U_LIB.S9S_MB_2U(SCH_1):GND
  DW68  GND            VSS1258  @S9S_MB_2U_LIB.S9S_MB_2U(SCH_1):GND
  DW66  GND            VSS1257  @S9S_MB_2U_LIB.S9S_MB_2U(SCH_1):GND
  EE52  GND            VSS1237  @S9S_MB_2U_LIB.S9S_MB_2U(SCH_1):GND
  EE39  GND            VSS1235  @S9S_MB_2U_LIB.S9S_MB_2U(SCH_1):GND
  EE17  GND            VSS1232  @S9S_MB_2U_LIB.S9S_MB_2U(SCH_1):GND
  ED73  GND            VSS1225  @S9S_MB_2U_LIB.S9S_MB_2U(SCH_1):GND
  ED67  GND            VSS1224  @S9S_MB_2U_LIB.S9S_MB_2U(SCH_1):GND
  ED61  GND            VSS1223  @S9S_MB_2U_LIB.S9S_MB_2U(SCH_1):GND
  ED55  GND            VSS1220  @S9S_MB_2U_LIB.S9S_MB_2U(SCH_1):GND
  ED42  GND            VSS1217  @S9S_MB_2U_LIB.S9S_MB_2U(SCH_1):GND
  ED18  GND            VSS1210  @S9S_MB_2U_LIB.S9S_MB_2U(SCH_1):GND
  ED12  GND            VSS1208  @S9S_MB_2U_LIB.S9S_MB_2U(SCH_1):GND
  EC68  GND            VSS1200  @S9S_MB_2U_LIB.S9S_MB_2U(SCH_1):GND
  EC62  GND            VSS1198  @S9S_MB_2U_LIB.S9S_MB_2U(SCH_1):GND
  EC60  GND            VSS1197  @S9S_MB_2U_LIB.S9S_MB_2U(SCH_1):GND
  EC54  GND            VSS1195  @S9S_MB_2U_LIB.S9S_MB_2U(SCH_1):GND
  EC5  GND            VSS1193  @S9S_MB_2U_LIB.S9S_MB_2U(SCH_1):GND
  EC35  GND            VSS1188  @S9S_MB_2U_LIB.S9S_MB_2U(SCH_1):GND
  EC25  GND            VSS1185  @S9S_MB_2U_LIB.S9S_MB_2U(SCH_1):GND
  EB91  GND            VSS1180  @S9S_MB_2U_LIB.S9S_MB_2U(SCH_1):GND
  EB63  GND            VSS1171  @S9S_MB_2U_LIB.S9S_MB_2U(SCH_1):GND
  EB59  GND            VSS1170  @S9S_MB_2U_LIB.S9S_MB_2U(SCH_1):GND
  EB53  GND            VSS1168  @S9S_MB_2U_LIB.S9S_MB_2U(SCH_1):GND
  EB51  GND            VSS1167  @S9S_MB_2U_LIB.S9S_MB_2U(SCH_1):GND
  EB44  GND            VSS1165  @S9S_MB_2U_LIB.S9S_MB_2U(SCH_1):GND
  EB4  GND            VSS1163  @S9S_MB_2U_LIB.S9S_MB_2U(SCH_1):GND
  EB34  GND            VSS1161  @S9S_MB_2U_LIB.S9S_MB_2U(SCH_1):GND
  EB26  GND            VSS1158  @S9S_MB_2U_LIB.S9S_MB_2U(SCH_1):GND
  EB20  GND            VSS1156  @S9S_MB_2U_LIB.S9S_MB_2U(SCH_1):GND
  EB16  GND            VSS1155  @S9S_MB_2U_LIB.S9S_MB_2U(SCH_1):GND
  EA64  GND            VSS1146  @S9S_MB_2U_LIB.S9S_MB_2U(SCH_1):GND
  EA58  GND            VSS1145  @S9S_MB_2U_LIB.S9S_MB_2U(SCH_1):GND
  EA52  GND            VSS1144  @S9S_MB_2U_LIB.S9S_MB_2U(SCH_1):GND
  EA45  GND            VSS1142  @S9S_MB_2U_LIB.S9S_MB_2U(SCH_1):GND
  EA39  GND            VSS1141  @S9S_MB_2U_LIB.S9S_MB_2U(SCH_1):GND
  DY42  GND            VSS1116  @S9S_MB_2U_LIB.S9S_MB_2U(SCH_1):GND
  DY4  GND            VSS1115  @S9S_MB_2U_LIB.S9S_MB_2U(SCH_1):GND
  DY16  GND            VSS1112  @S9S_MB_2U_LIB.S9S_MB_2U(SCH_1):GND
  DY12  GND            VSS1111  @S9S_MB_2U_LIB.S9S_MB_2U(SCH_1):GND

SOCKET4677_AZIFS054P001C01  I2   U1     [SOCKET4677_AZIFS054P001C01-SOCA]
  ET57  GND            VSS1569  @S9S_MB_2U_LIB.S9S_MB_2U(SCH_1):GND
  ET38  GND            VSS1565  @S9S_MB_2U_LIB.S9S_MB_2U(SCH_1):GND
  ET34  GND            VSS1563  @S9S_MB_2U_LIB.S9S_MB_2U(SCH_1):GND
  ET28  GND            VSS1562  @S9S_MB_2U_LIB.S9S_MB_2U(SCH_1):GND
  ET22  GND            VSS1561  @S9S_MB_2U_LIB.S9S_MB_2U(SCH_1):GND
  ET16  GND            VSS1559  @S9S_MB_2U_LIB.S9S_MB_2U(SCH_1):GND
  ET10  GND            VSS1557  @S9S_MB_2U_LIB.S9S_MB_2U(SCH_1):GND
  ER86  GND            VSS1556  @S9S_MB_2U_LIB.S9S_MB_2U(SCH_1):GND
  ER84  GND            VSS1555  @S9S_MB_2U_LIB.S9S_MB_2U(SCH_1):GND
  ER80  GND            VSS1554  @S9S_MB_2U_LIB.S9S_MB_2U(SCH_1):GND
  ER78  GND            VSS1553  @S9S_MB_2U_LIB.S9S_MB_2U(SCH_1):GND
  ER74  GND            VSS1552  @S9S_MB_2U_LIB.S9S_MB_2U(SCH_1):GND
  ER70  GND            VSS1551  @S9S_MB_2U_LIB.S9S_MB_2U(SCH_1):GND
  ER7  GND            VSS1550  @S9S_MB_2U_LIB.S9S_MB_2U(SCH_1):GND
  ER5  GND            VSS1549  @S9S_MB_2U_LIB.S9S_MB_2U(SCH_1):GND
  ER33  GND            VSS1548  @S9S_MB_2U_LIB.S9S_MB_2U(SCH_1):GND
  ER27  GND            VSS1547  @S9S_MB_2U_LIB.S9S_MB_2U(SCH_1):GND
  EP83  GND            VSS1545  @S9S_MB_2U_LIB.S9S_MB_2U(SCH_1):GND
  EP67  GND            VSS1543  @S9S_MB_2U_LIB.S9S_MB_2U(SCH_1):GND
  EN80  GND            VSS1542  @S9S_MB_2U_LIB.S9S_MB_2U(SCH_1):GND
  EN78  GND            VSS1541  @S9S_MB_2U_LIB.S9S_MB_2U(SCH_1):GND
  EN64  GND            VSS1540  @S9S_MB_2U_LIB.S9S_MB_2U(SCH_1):GND
  EN56  GND            VSS1539  @S9S_MB_2U_LIB.S9S_MB_2U(SCH_1):GND
  EN54  GND            VSS1537  @S9S_MB_2U_LIB.S9S_MB_2U(SCH_1):GND
  EN52  GND            VSS1533  @S9S_MB_2U_LIB.S9S_MB_2U(SCH_1):GND
  EN50  GND            VSS1531  @S9S_MB_2U_LIB.S9S_MB_2U(SCH_1):GND
  EN48  GND            VSS1530  @S9S_MB_2U_LIB.S9S_MB_2U(SCH_1):GND
  EN45  GND            VSS1529  @S9S_MB_2U_LIB.S9S_MB_2U(SCH_1):GND
  EN43  GND            VSS1528  @S9S_MB_2U_LIB.S9S_MB_2U(SCH_1):GND
  EN41  GND            VSS1526  @S9S_MB_2U_LIB.S9S_MB_2U(SCH_1):GND
  EN37  GND            VSS1525  @S9S_MB_2U_LIB.S9S_MB_2U(SCH_1):GND
  EN35  GND            VSS1524  @S9S_MB_2U_LIB.S9S_MB_2U(SCH_1):GND
  EN33  GND            VSS1522  @S9S_MB_2U_LIB.S9S_MB_2U(SCH_1):GND
  EN31  GND            VSS1520  @S9S_MB_2U_LIB.S9S_MB_2U(SCH_1):GND
  EN29  GND            VSS1518  @S9S_MB_2U_LIB.S9S_MB_2U(SCH_1):GND
  EN27  GND            VSS1517  @S9S_MB_2U_LIB.S9S_MB_2U(SCH_1):GND
  EN25  GND            VSS1515  @S9S_MB_2U_LIB.S9S_MB_2U(SCH_1):GND
  EN23  GND            VSS1513  @S9S_MB_2U_LIB.S9S_MB_2U(SCH_1):GND
  EN21  GND            VSS1512  @S9S_MB_2U_LIB.S9S_MB_2U(SCH_1):GND
  EN19  GND            VSS1506  @S9S_MB_2U_LIB.S9S_MB_2U(SCH_1):GND
  EN17  GND            VSS1505  @S9S_MB_2U_LIB.S9S_MB_2U(SCH_1):GND
  EN15  GND            VSS1503  @S9S_MB_2U_LIB.S9S_MB_2U(SCH_1):GND
  EN13  GND            VSS1501  @S9S_MB_2U_LIB.S9S_MB_2U(SCH_1):GND
  EN11  GND            VSS1500  @S9S_MB_2U_LIB.S9S_MB_2U(SCH_1):GND
  EM83  GND            VSS1499  @S9S_MB_2U_LIB.S9S_MB_2U(SCH_1):GND
  EM81  GND            VSS1498  @S9S_MB_2U_LIB.S9S_MB_2U(SCH_1):GND
  EM8  GND            VSS1497  @S9S_MB_2U_LIB.S9S_MB_2U(SCH_1):GND
  EM73  GND            VSS1496  @S9S_MB_2U_LIB.S9S_MB_2U(SCH_1):GND
  ET59  GND            VSS1493  @S9S_MB_2U_LIB.S9S_MB_2U(SCH_1):GND
  EM42  GND            VSS1492  @S9S_MB_2U_LIB.S9S_MB_2U(SCH_1):GND
  ET53  GND            VSS1491  @S9S_MB_2U_LIB.S9S_MB_2U(SCH_1):GND
  EL76  GND            VSS1489  @S9S_MB_2U_LIB.S9S_MB_2U(SCH_1):GND
  EL64  GND            VSS1488  @S9S_MB_2U_LIB.S9S_MB_2U(SCH_1):GND
  EL5  GND            VSS1486  @S9S_MB_2U_LIB.S9S_MB_2U(SCH_1):GND
  EL45  GND            VSS1485  @S9S_MB_2U_LIB.S9S_MB_2U(SCH_1):GND
  ET32  GND            VSS1484  @S9S_MB_2U_LIB.S9S_MB_2U(SCH_1):GND
  EL39  GND            VSS1483  @S9S_MB_2U_LIB.S9S_MB_2U(SCH_1):GND
  ET26  GND            VSS1482  @S9S_MB_2U_LIB.S9S_MB_2U(SCH_1):GND
  EL33  GND            VSS1481  @S9S_MB_2U_LIB.S9S_MB_2U(SCH_1):GND
  ET20  GND            VSS1480  @S9S_MB_2U_LIB.S9S_MB_2U(SCH_1):GND
  EL3  GND            VSS1479  @S9S_MB_2U_LIB.S9S_MB_2U(SCH_1):GND
  ET14  GND            VSS1478  @S9S_MB_2U_LIB.S9S_MB_2U(SCH_1):GND
  EL27  GND            VSS1477  @S9S_MB_2U_LIB.S9S_MB_2U(SCH_1):GND
  ER9  GND            VSS1476  @S9S_MB_2U_LIB.S9S_MB_2U(SCH_1):GND
  EL21  GND            VSS1475  @S9S_MB_2U_LIB.S9S_MB_2U(SCH_1):GND
  EK75  GND            VSS1474  @S9S_MB_2U_LIB.S9S_MB_2U(SCH_1):GND
  EK69  GND            VSS1473  @S9S_MB_2U_LIB.S9S_MB_2U(SCH_1):GND
  EK65  GND            VSS1472  @S9S_MB_2U_LIB.S9S_MB_2U(SCH_1):GND
  EK57  GND            VSS1471  @S9S_MB_2U_LIB.S9S_MB_2U(SCH_1):GND
  EK47  GND            VSS1470  @S9S_MB_2U_LIB.S9S_MB_2U(SCH_1):GND
  EK40  GND            VSS1469  @S9S_MB_2U_LIB.S9S_MB_2U(SCH_1):GND
  ER64  GND            VSS1468  @S9S_MB_2U_LIB.S9S_MB_2U(SCH_1):GND
  ER58  GND            VSS1467  @S9S_MB_2U_LIB.S9S_MB_2U(SCH_1):GND
  EK4  GND            VSS1466  @S9S_MB_2U_LIB.S9S_MB_2U(SCH_1):GND
  EK38  GND            VSS1465  @S9S_MB_2U_LIB.S9S_MB_2U(SCH_1):GND
  ER52  GND            VSS1464  @S9S_MB_2U_LIB.S9S_MB_2U(SCH_1):GND
  EK34  GND            VSS1463  @S9S_MB_2U_LIB.S9S_MB_2U(SCH_1):GND
  ER39  GND            VSS1462  @S9S_MB_2U_LIB.S9S_MB_2U(SCH_1):GND
  EK32  GND            VSS1461  @S9S_MB_2U_LIB.S9S_MB_2U(SCH_1):GND
  EK28  GND            VSS1460  @S9S_MB_2U_LIB.S9S_MB_2U(SCH_1):GND
  EK22  GND            VSS1459  @S9S_MB_2U_LIB.S9S_MB_2U(SCH_1):GND
  EK2  GND            VSS1458  @S9S_MB_2U_LIB.S9S_MB_2U(SCH_1):GND
  ER21  GND            VSS1457  @S9S_MB_2U_LIB.S9S_MB_2U(SCH_1):GND
  ER15  GND            VSS1456  @S9S_MB_2U_LIB.S9S_MB_2U(SCH_1):GND
  EK14  GND            VSS1455  @S9S_MB_2U_LIB.S9S_MB_2U(SCH_1):GND
  EP77  GND            VSS1454  @S9S_MB_2U_LIB.S9S_MB_2U(SCH_1):GND
  EP71  GND            VSS1453  @S9S_MB_2U_LIB.S9S_MB_2U(SCH_1):GND
  EP69  GND            VSS1452  @S9S_MB_2U_LIB.S9S_MB_2U(SCH_1):GND
  EK10  GND            VSS1451  @S9S_MB_2U_LIB.S9S_MB_2U(SCH_1):GND
  EJ9  GND            VSS1450  @S9S_MB_2U_LIB.S9S_MB_2U(SCH_1):GND
  EJ88  GND            VSS1449  @S9S_MB_2U_LIB.S9S_MB_2U(SCH_1):GND
  EJ78  GND            VSS1448  @S9S_MB_2U_LIB.S9S_MB_2U(SCH_1):GND
  EJ74  GND            VSS1447  @S9S_MB_2U_LIB.S9S_MB_2U(SCH_1):GND
  EN9  GND            VSS1446  @S9S_MB_2U_LIB.S9S_MB_2U(SCH_1):GND
  EN88  GND            VSS1445  @S9S_MB_2U_LIB.S9S_MB_2U(SCH_1):GND
  EJ7  GND            VSS1444  @S9S_MB_2U_LIB.S9S_MB_2U(SCH_1):GND
  EJ66  GND            VSS1443  @S9S_MB_2U_LIB.S9S_MB_2U(SCH_1):GND
  EJ60  GND            VSS1442  @S9S_MB_2U_LIB.S9S_MB_2U(SCH_1):GND
  EN72  GND            VSS1441  @S9S_MB_2U_LIB.S9S_MB_2U(SCH_1):GND
  EN66  GND            VSS1440  @S9S_MB_2U_LIB.S9S_MB_2U(SCH_1):GND
  EJ56  GND            VSS1439  @S9S_MB_2U_LIB.S9S_MB_2U(SCH_1):GND
  EN62  GND            VSS1438  @S9S_MB_2U_LIB.S9S_MB_2U(SCH_1):GND
  EN60  GND            VSS1437  @S9S_MB_2U_LIB.S9S_MB_2U(SCH_1):GND
  EN58  GND            VSS1436  @S9S_MB_2U_LIB.S9S_MB_2U(SCH_1):GND
  EJ50  GND            VSS1435  @S9S_MB_2U_LIB.S9S_MB_2U(SCH_1):GND
  EJ48  GND            VSS1434  @S9S_MB_2U_LIB.S9S_MB_2U(SCH_1):GND
  EJ43  GND            VSS1433  @S9S_MB_2U_LIB.S9S_MB_2U(SCH_1):GND
  EJ41  GND            VSS1432  @S9S_MB_2U_LIB.S9S_MB_2U(SCH_1):GND
  EJ37  GND            VSS1431  @S9S_MB_2U_LIB.S9S_MB_2U(SCH_1):GND
  EJ31  GND            VSS1430  @S9S_MB_2U_LIB.S9S_MB_2U(SCH_1):GND
  EJ29  GND            VSS1429  @S9S_MB_2U_LIB.S9S_MB_2U(SCH_1):GND
  EJ23  GND            VSS1428  @S9S_MB_2U_LIB.S9S_MB_2U(SCH_1):GND
  EN39  GND            VSS1427  @S9S_MB_2U_LIB.S9S_MB_2U(SCH_1):GND
  EJ19  GND            VSS1426  @S9S_MB_2U_LIB.S9S_MB_2U(SCH_1):GND
  EJ13  GND            VSS1425  @S9S_MB_2U_LIB.S9S_MB_2U(SCH_1):GND
  EH83  GND            VSS1424  @S9S_MB_2U_LIB.S9S_MB_2U(SCH_1):GND
  EH81  GND            VSS1423  @S9S_MB_2U_LIB.S9S_MB_2U(SCH_1):GND
  EH73  GND            VSS1422  @S9S_MB_2U_LIB.S9S_MB_2U(SCH_1):GND
  EH49  GND            VSS1421  @S9S_MB_2U_LIB.S9S_MB_2U(SCH_1):GND
  EH36  GND            VSS1419  @S9S_MB_2U_LIB.S9S_MB_2U(SCH_1):GND
  EM79  GND            VSS1409  @S9S_MB_2U_LIB.S9S_MB_2U(SCH_1):GND
  EM49  GND            VSS1405  @S9S_MB_2U_LIB.S9S_MB_2U(SCH_1):GND
  EL9  GND            VSS1401  @S9S_MB_2U_LIB.S9S_MB_2U(SCH_1):GND
  EL86  GND            VSS1400  @S9S_MB_2U_LIB.S9S_MB_2U(SCH_1):GND
  EL72  GND            VSS1398  @S9S_MB_2U_LIB.S9S_MB_2U(SCH_1):GND
  EL70  GND            VSS1397  @S9S_MB_2U_LIB.S9S_MB_2U(SCH_1):GND
  EL7  GND            VSS1396  @S9S_MB_2U_LIB.S9S_MB_2U(SCH_1):GND
  EL58  GND            VSS1394  @S9S_MB_2U_LIB.S9S_MB_2U(SCH_1):GND
  EL52  GND            VSS1391  @S9S_MB_2U_LIB.S9S_MB_2U(SCH_1):GND
  EL15  GND            VSS1381  @S9S_MB_2U_LIB.S9S_MB_2U(SCH_1):GND
  EK89  GND            VSS1380  @S9S_MB_2U_LIB.S9S_MB_2U(SCH_1):GND
  EK83  GND            VSS1379  @S9S_MB_2U_LIB.S9S_MB_2U(SCH_1):GND
  EK79  GND            VSS1378  @S9S_MB_2U_LIB.S9S_MB_2U(SCH_1):GND
  EK77  GND            VSS1377  @S9S_MB_2U_LIB.S9S_MB_2U(SCH_1):GND
  EK71  GND            VSS1375  @S9S_MB_2U_LIB.S9S_MB_2U(SCH_1):GND
  EK63  GND            VSS1372  @S9S_MB_2U_LIB.S9S_MB_2U(SCH_1):GND
  EK59  GND            VSS1371  @S9S_MB_2U_LIB.S9S_MB_2U(SCH_1):GND
  EK53  GND            VSS1369  @S9S_MB_2U_LIB.S9S_MB_2U(SCH_1):GND
  EK51  GND            VSS1368  @S9S_MB_2U_LIB.S9S_MB_2U(SCH_1):GND
  EK44  GND            VSS1366  @S9S_MB_2U_LIB.S9S_MB_2U(SCH_1):GND
  EK26  GND            VSS1359  @S9S_MB_2U_LIB.S9S_MB_2U(SCH_1):GND
  EK20  GND            VSS1357  @S9S_MB_2U_LIB.S9S_MB_2U(SCH_1):GND
  EK16  GND            VSS1355  @S9S_MB_2U_LIB.S9S_MB_2U(SCH_1):GND
  EJ72  GND            VSS1347  @S9S_MB_2U_LIB.S9S_MB_2U(SCH_1):GND
  EJ68  GND            VSS1345  @S9S_MB_2U_LIB.S9S_MB_2U(SCH_1):GND
  EJ62  GND            VSS1343  @S9S_MB_2U_LIB.S9S_MB_2U(SCH_1):GND
  EJ54  GND            VSS1340  @S9S_MB_2U_LIB.S9S_MB_2U(SCH_1):GND
  EJ35  GND            VSS1334  @S9S_MB_2U_LIB.S9S_MB_2U(SCH_1):GND
  EJ25  GND            VSS1331  @S9S_MB_2U_LIB.S9S_MB_2U(SCH_1):GND
  EJ17  GND            VSS1328  @S9S_MB_2U_LIB.S9S_MB_2U(SCH_1):GND
  EJ11  GND            VSS1325  @S9S_MB_2U_LIB.S9S_MB_2U(SCH_1):GND
  EH79  GND            VSS1322  @S9S_MB_2U_LIB.S9S_MB_2U(SCH_1):GND
  EH67  GND            VSS1320  @S9S_MB_2U_LIB.S9S_MB_2U(SCH_1):GND
  EH61  GND            VSS1319  @S9S_MB_2U_LIB.S9S_MB_2U(SCH_1):GND
  EH55  GND            VSS1315  @S9S_MB_2U_LIB.S9S_MB_2U(SCH_1):GND
  EH42  GND            VSS1312  @S9S_MB_2U_LIB.S9S_MB_2U(SCH_1):GND
  ER50  GND            GND_ER50  @S9S_MB_2U_LIB.S9S_MB_2U(SCH_1):GND
  ER48  GND            GND_ER48  @S9S_MB_2U_LIB.S9S_MB_2U(SCH_1):GND
  ER43  GND            GND_ER43  @S9S_MB_2U_LIB.S9S_MB_2U(SCH_1):GND
  ER41  GND            GND_ER41  @S9S_MB_2U_LIB.S9S_MB_2U(SCH_1):GND

SOCKET4677_AZIFS054P001C01  I1   U1     [SOCKET4677_AZIFS054P001C01-SOCA]
  Y89  PVCCFA_EHV_FIVRA_CPU1  VCCFA_EHV_FIVRA104  @S9S_MB_2U_LIB.S9S_MB_2U(SCH_1):PVCCFA_EHV_FIVRA_CPU1
  Y85  PVCCFA_EHV_FIVRA_CPU1  VCCFA_EHV_FIVRA103  @S9S_MB_2U_LIB.S9S_MB_2U(SCH_1):PVCCFA_EHV_FIVRA_CPU1
  Y79  PVCCFA_EHV_FIVRA_CPU1  VCCFA_EHV_FIVRA102  @S9S_MB_2U_LIB.S9S_MB_2U(SCH_1):PVCCFA_EHV_FIVRA_CPU1
  W80  PVCCFA_EHV_FIVRA_CPU1  VCCFA_EHV_FIVRA101  @S9S_MB_2U_LIB.S9S_MB_2U(SCH_1):PVCCFA_EHV_FIVRA_CPU1
   U7  PVCCFA_EHV_FIVRA_CPU1  VCCFA_EHV_FIVRA100  @S9S_MB_2U_LIB.S9S_MB_2U(SCH_1):PVCCFA_EHV_FIVRA_CPU1
  U15  PVCCFA_EHV_FIVRA_CPU1  VCCFA_EHV_FIVRA99  @S9S_MB_2U_LIB.S9S_MB_2U(SCH_1):PVCCFA_EHV_FIVRA_CPU1
  U11  PVCCFA_EHV_FIVRA_CPU1  VCCFA_EHV_FIVRA98  @S9S_MB_2U_LIB.S9S_MB_2U(SCH_1):PVCCFA_EHV_FIVRA_CPU1
  T89  PVCCFA_EHV_FIVRA_CPU1  VCCFA_EHV_FIVRA97  @S9S_MB_2U_LIB.S9S_MB_2U(SCH_1):PVCCFA_EHV_FIVRA_CPU1
  T85  PVCCFA_EHV_FIVRA_CPU1  VCCFA_EHV_FIVRA96  @S9S_MB_2U_LIB.S9S_MB_2U(SCH_1):PVCCFA_EHV_FIVRA_CPU1
  R80  PVCCFA_EHV_FIVRA_CPU1  VCCFA_EHV_FIVRA95  @S9S_MB_2U_LIB.S9S_MB_2U(SCH_1):PVCCFA_EHV_FIVRA_CPU1
  P79  PVCCFA_EHV_FIVRA_CPU1  VCCFA_EHV_FIVRA94  @S9S_MB_2U_LIB.S9S_MB_2U(SCH_1):PVCCFA_EHV_FIVRA_CPU1
   N7  PVCCFA_EHV_FIVRA_CPU1  VCCFA_EHV_FIVRA93  @S9S_MB_2U_LIB.S9S_MB_2U(SCH_1):PVCCFA_EHV_FIVRA_CPU1
  N11  PVCCFA_EHV_FIVRA_CPU1  VCCFA_EHV_FIVRA92  @S9S_MB_2U_LIB.S9S_MB_2U(SCH_1):PVCCFA_EHV_FIVRA_CPU1
  M89  PVCCFA_EHV_FIVRA_CPU1  VCCFA_EHV_FIVRA91  @S9S_MB_2U_LIB.S9S_MB_2U(SCH_1):PVCCFA_EHV_FIVRA_CPU1
  M85  PVCCFA_EHV_FIVRA_CPU1  VCCFA_EHV_FIVRA90  @S9S_MB_2U_LIB.S9S_MB_2U(SCH_1):PVCCFA_EHV_FIVRA_CPU1
  L84  PVCCFA_EHV_FIVRA_CPU1  VCCFA_EHV_FIVRA89  @S9S_MB_2U_LIB.S9S_MB_2U(SCH_1):PVCCFA_EHV_FIVRA_CPU1
  K87  PVCCFA_EHV_FIVRA_CPU1  VCCFA_EHV_FIVRA88  @S9S_MB_2U_LIB.S9S_MB_2U(SCH_1):PVCCFA_EHV_FIVRA_CPU1
  J80  PVCCFA_EHV_FIVRA_CPU1  VCCFA_EHV_FIVRA87  @S9S_MB_2U_LIB.S9S_MB_2U(SCH_1):PVCCFA_EHV_FIVRA_CPU1
   J7  PVCCFA_EHV_FIVRA_CPU1  VCCFA_EHV_FIVRA86  @S9S_MB_2U_LIB.S9S_MB_2U(SCH_1):PVCCFA_EHV_FIVRA_CPU1
  J11  PVCCFA_EHV_FIVRA_CPU1  VCCFA_EHV_FIVRA85  @S9S_MB_2U_LIB.S9S_MB_2U(SCH_1):PVCCFA_EHV_FIVRA_CPU1
  H89  PVCCFA_EHV_FIVRA_CPU1  VCCFA_EHV_FIVRA84  @S9S_MB_2U_LIB.S9S_MB_2U(SCH_1):PVCCFA_EHV_FIVRA_CPU1
  EN84  PVCCFA_EHV_FIVRA_CPU1  VCCFA_EHV_FIVRA83  @S9S_MB_2U_LIB.S9S_MB_2U(SCH_1):PVCCFA_EHV_FIVRA_CPU1
  EJ84  PVCCFA_EHV_FIVRA_CPU1  VCCFA_EHV_FIVRA82  @S9S_MB_2U_LIB.S9S_MB_2U(SCH_1):PVCCFA_EHV_FIVRA_CPU1
  EJ15  PVCCFA_EHV_FIVRA_CPU1  VCCFA_EHV_FIVRA81  @S9S_MB_2U_LIB.S9S_MB_2U(SCH_1):PVCCFA_EHV_FIVRA_CPU1
  EG80  PVCCFA_EHV_FIVRA_CPU1  VCCFA_EHV_FIVRA80  @S9S_MB_2U_LIB.S9S_MB_2U(SCH_1):PVCCFA_EHV_FIVRA_CPU1
  EF79  PVCCFA_EHV_FIVRA_CPU1  VCCFA_EHV_FIVRA79  @S9S_MB_2U_LIB.S9S_MB_2U(SCH_1):PVCCFA_EHV_FIVRA_CPU1
  EE84  PVCCFA_EHV_FIVRA_CPU1  VCCFA_EHV_FIVRA78  @S9S_MB_2U_LIB.S9S_MB_2U(SCH_1):PVCCFA_EHV_FIVRA_CPU1
  EE7  PVCCFA_EHV_FIVRA_CPU1  VCCFA_EHV_FIVRA77  @S9S_MB_2U_LIB.S9S_MB_2U(SCH_1):PVCCFA_EHV_FIVRA_CPU1
  EE15  PVCCFA_EHV_FIVRA_CPU1  VCCFA_EHV_FIVRA76  @S9S_MB_2U_LIB.S9S_MB_2U(SCH_1):PVCCFA_EHV_FIVRA_CPU1
  EE11  PVCCFA_EHV_FIVRA_CPU1  VCCFA_EHV_FIVRA75  @S9S_MB_2U_LIB.S9S_MB_2U(SCH_1):PVCCFA_EHV_FIVRA_CPU1
  ED89  PVCCFA_EHV_FIVRA_CPU1  VCCFA_EHV_FIVRA74  @S9S_MB_2U_LIB.S9S_MB_2U(SCH_1):PVCCFA_EHV_FIVRA_CPU1
  ED85  PVCCFA_EHV_FIVRA_CPU1  VCCFA_EHV_FIVRA73  @S9S_MB_2U_LIB.S9S_MB_2U(SCH_1):PVCCFA_EHV_FIVRA_CPU1
  ED79  PVCCFA_EHV_FIVRA_CPU1  VCCFA_EHV_FIVRA72  @S9S_MB_2U_LIB.S9S_MB_2U(SCH_1):PVCCFA_EHV_FIVRA_CPU1
  EC78  PVCCFA_EHV_FIVRA_CPU1  VCCFA_EHV_FIVRA71  @S9S_MB_2U_LIB.S9S_MB_2U(SCH_1):PVCCFA_EHV_FIVRA_CPU1
  EA7  PVCCFA_EHV_FIVRA_CPU1  VCCFA_EHV_FIVRA70  @S9S_MB_2U_LIB.S9S_MB_2U(SCH_1):PVCCFA_EHV_FIVRA_CPU1
  EA3  PVCCFA_EHV_FIVRA_CPU1  VCCFA_EHV_FIVRA69  @S9S_MB_2U_LIB.S9S_MB_2U(SCH_1):PVCCFA_EHV_FIVRA_CPU1
  EA15  PVCCFA_EHV_FIVRA_CPU1  VCCFA_EHV_FIVRA68  @S9S_MB_2U_LIB.S9S_MB_2U(SCH_1):PVCCFA_EHV_FIVRA_CPU1
  EA11  PVCCFA_EHV_FIVRA_CPU1  VCCFA_EHV_FIVRA67  @S9S_MB_2U_LIB.S9S_MB_2U(SCH_1):PVCCFA_EHV_FIVRA_CPU1
  DY89  PVCCFA_EHV_FIVRA_CPU1  VCCFA_EHV_FIVRA66  @S9S_MB_2U_LIB.S9S_MB_2U(SCH_1):PVCCFA_EHV_FIVRA_CPU1
  DY85  PVCCFA_EHV_FIVRA_CPU1  VCCFA_EHV_FIVRA65  @S9S_MB_2U_LIB.S9S_MB_2U(SCH_1):PVCCFA_EHV_FIVRA_CPU1
  DU7  PVCCFA_EHV_FIVRA_CPU1  VCCFA_EHV_FIVRA64  @S9S_MB_2U_LIB.S9S_MB_2U(SCH_1):PVCCFA_EHV_FIVRA_CPU1
  DU3  PVCCFA_EHV_FIVRA_CPU1  VCCFA_EHV_FIVRA63  @S9S_MB_2U_LIB.S9S_MB_2U(SCH_1):PVCCFA_EHV_FIVRA_CPU1
  DU15  PVCCFA_EHV_FIVRA_CPU1  VCCFA_EHV_FIVRA62  @S9S_MB_2U_LIB.S9S_MB_2U(SCH_1):PVCCFA_EHV_FIVRA_CPU1
  DU11  PVCCFA_EHV_FIVRA_CPU1  VCCFA_EHV_FIVRA61  @S9S_MB_2U_LIB.S9S_MB_2U(SCH_1):PVCCFA_EHV_FIVRA_CPU1
  DT89  PVCCFA_EHV_FIVRA_CPU1  VCCFA_EHV_FIVRA60  @S9S_MB_2U_LIB.S9S_MB_2U(SCH_1):PVCCFA_EHV_FIVRA_CPU1
  DT85  PVCCFA_EHV_FIVRA_CPU1  VCCFA_EHV_FIVRA59  @S9S_MB_2U_LIB.S9S_MB_2U(SCH_1):PVCCFA_EHV_FIVRA_CPU1
  DT79  PVCCFA_EHV_FIVRA_CPU1  VCCFA_EHV_FIVRA58  @S9S_MB_2U_LIB.S9S_MB_2U(SCH_1):PVCCFA_EHV_FIVRA_CPU1
  DN7  PVCCFA_EHV_FIVRA_CPU1  VCCFA_EHV_FIVRA57  @S9S_MB_2U_LIB.S9S_MB_2U(SCH_1):PVCCFA_EHV_FIVRA_CPU1
  DN3  PVCCFA_EHV_FIVRA_CPU1  VCCFA_EHV_FIVRA56  @S9S_MB_2U_LIB.S9S_MB_2U(SCH_1):PVCCFA_EHV_FIVRA_CPU1
  DN15  PVCCFA_EHV_FIVRA_CPU1  VCCFA_EHV_FIVRA55  @S9S_MB_2U_LIB.S9S_MB_2U(SCH_1):PVCCFA_EHV_FIVRA_CPU1
  DN11  PVCCFA_EHV_FIVRA_CPU1  VCCFA_EHV_FIVRA54  @S9S_MB_2U_LIB.S9S_MB_2U(SCH_1):PVCCFA_EHV_FIVRA_CPU1
  DM89  PVCCFA_EHV_FIVRA_CPU1  VCCFA_EHV_FIVRA53  @S9S_MB_2U_LIB.S9S_MB_2U(SCH_1):PVCCFA_EHV_FIVRA_CPU1
  DM85  PVCCFA_EHV_FIVRA_CPU1  VCCFA_EHV_FIVRA52  @S9S_MB_2U_LIB.S9S_MB_2U(SCH_1):PVCCFA_EHV_FIVRA_CPU1
  DM83  PVCCFA_EHV_FIVRA_CPU1  VCCFA_EHV_FIVRA51  @S9S_MB_2U_LIB.S9S_MB_2U(SCH_1):PVCCFA_EHV_FIVRA_CPU1
  DH89  PVCCFA_EHV_FIVRA_CPU1  VCCFA_EHV_FIVRA50  @S9S_MB_2U_LIB.S9S_MB_2U(SCH_1):PVCCFA_EHV_FIVRA_CPU1
  DD89  PVCCFA_EHV_FIVRA_CPU1  VCCFA_EHV_FIVRA49  @S9S_MB_2U_LIB.S9S_MB_2U(SCH_1):PVCCFA_EHV_FIVRA_CPU1
  DD85  PVCCFA_EHV_FIVRA_CPU1  VCCFA_EHV_FIVRA48  @S9S_MB_2U_LIB.S9S_MB_2U(SCH_1):PVCCFA_EHV_FIVRA_CPU1
  DD83  PVCCFA_EHV_FIVRA_CPU1  VCCFA_EHV_FIVRA47  @S9S_MB_2U_LIB.S9S_MB_2U(SCH_1):PVCCFA_EHV_FIVRA_CPU1
  DD77  PVCCFA_EHV_FIVRA_CPU1  VCCFA_EHV_FIVRA46  @S9S_MB_2U_LIB.S9S_MB_2U(SCH_1):PVCCFA_EHV_FIVRA_CPU1
  CY89  PVCCFA_EHV_FIVRA_CPU1  VCCFA_EHV_FIVRA45  @S9S_MB_2U_LIB.S9S_MB_2U(SCH_1):PVCCFA_EHV_FIVRA_CPU1
  CY85  PVCCFA_EHV_FIVRA_CPU1  VCCFA_EHV_FIVRA44  @S9S_MB_2U_LIB.S9S_MB_2U(SCH_1):PVCCFA_EHV_FIVRA_CPU1
  CY79  PVCCFA_EHV_FIVRA_CPU1  VCCFA_EHV_FIVRA43  @S9S_MB_2U_LIB.S9S_MB_2U(SCH_1):PVCCFA_EHV_FIVRA_CPU1
  CY75  PVCCFA_EHV_FIVRA_CPU1  VCCFA_EHV_FIVRA42  @S9S_MB_2U_LIB.S9S_MB_2U(SCH_1):PVCCFA_EHV_FIVRA_CPU1
  CT85  PVCCFA_EHV_FIVRA_CPU1  VCCFA_EHV_FIVRA41  @S9S_MB_2U_LIB.S9S_MB_2U(SCH_1):PVCCFA_EHV_FIVRA_CPU1
  CT77  PVCCFA_EHV_FIVRA_CPU1  VCCFA_EHV_FIVRA40  @S9S_MB_2U_LIB.S9S_MB_2U(SCH_1):PVCCFA_EHV_FIVRA_CPU1
  CP73  PVCCFA_EHV_FIVRA_CPU1  VCCFA_EHV_FIVRA39  @S9S_MB_2U_LIB.S9S_MB_2U(SCH_1):PVCCFA_EHV_FIVRA_CPU1
  CN78  PVCCFA_EHV_FIVRA_CPU1  VCCFA_EHV_FIVRA38  @S9S_MB_2U_LIB.S9S_MB_2U(SCH_1):PVCCFA_EHV_FIVRA_CPU1
  CM73  PVCCFA_EHV_FIVRA_CPU1  VCCFA_EHV_FIVRA37  @S9S_MB_2U_LIB.S9S_MB_2U(SCH_1):PVCCFA_EHV_FIVRA_CPU1
  CK79  PVCCFA_EHV_FIVRA_CPU1  VCCFA_EHV_FIVRA36  @S9S_MB_2U_LIB.S9S_MB_2U(SCH_1):PVCCFA_EHV_FIVRA_CPU1
  CK73  PVCCFA_EHV_FIVRA_CPU1  VCCFA_EHV_FIVRA35  @S9S_MB_2U_LIB.S9S_MB_2U(SCH_1):PVCCFA_EHV_FIVRA_CPU1
  CE74  PVCCFA_EHV_FIVRA_CPU1  VCCFA_EHV_FIVRA34  @S9S_MB_2U_LIB.S9S_MB_2U(SCH_1):PVCCFA_EHV_FIVRA_CPU1
  C88  PVCCFA_EHV_FIVRA_CPU1  VCCFA_EHV_FIVRA33  @S9S_MB_2U_LIB.S9S_MB_2U(SCH_1):PVCCFA_EHV_FIVRA_CPU1
  C84  PVCCFA_EHV_FIVRA_CPU1  VCCFA_EHV_FIVRA32  @S9S_MB_2U_LIB.S9S_MB_2U(SCH_1):PVCCFA_EHV_FIVRA_CPU1
  BJ78  PVCCFA_EHV_FIVRA_CPU1  VCCFA_EHV_FIVRA31  @S9S_MB_2U_LIB.S9S_MB_2U(SCH_1):PVCCFA_EHV_FIVRA_CPU1
  BJ72  PVCCFA_EHV_FIVRA_CPU1  VCCFA_EHV_FIVRA30  @S9S_MB_2U_LIB.S9S_MB_2U(SCH_1):PVCCFA_EHV_FIVRA_CPU1
  BH79  PVCCFA_EHV_FIVRA_CPU1  VCCFA_EHV_FIVRA29  @S9S_MB_2U_LIB.S9S_MB_2U(SCH_1):PVCCFA_EHV_FIVRA_CPU1
  BF77  PVCCFA_EHV_FIVRA_CPU1  VCCFA_EHV_FIVRA28  @S9S_MB_2U_LIB.S9S_MB_2U(SCH_1):PVCCFA_EHV_FIVRA_CPU1
  BE72  PVCCFA_EHV_FIVRA_CPU1  VCCFA_EHV_FIVRA27  @S9S_MB_2U_LIB.S9S_MB_2U(SCH_1):PVCCFA_EHV_FIVRA_CPU1
  AY89  PVCCFA_EHV_FIVRA_CPU1  VCCFA_EHV_FIVRA26  @S9S_MB_2U_LIB.S9S_MB_2U(SCH_1):PVCCFA_EHV_FIVRA_CPU1
  AW76  PVCCFA_EHV_FIVRA_CPU1  VCCFA_EHV_FIVRA25  @S9S_MB_2U_LIB.S9S_MB_2U(SCH_1):PVCCFA_EHV_FIVRA_CPU1
  AU15  PVCCFA_EHV_FIVRA_CPU1  VCCFA_EHV_FIVRA24  @S9S_MB_2U_LIB.S9S_MB_2U(SCH_1):PVCCFA_EHV_FIVRA_CPU1
  AT89  PVCCFA_EHV_FIVRA_CPU1  VCCFA_EHV_FIVRA23  @S9S_MB_2U_LIB.S9S_MB_2U(SCH_1):PVCCFA_EHV_FIVRA_CPU1
  AT73  PVCCFA_EHV_FIVRA_CPU1  VCCFA_EHV_FIVRA22  @S9S_MB_2U_LIB.S9S_MB_2U(SCH_1):PVCCFA_EHV_FIVRA_CPU1
  AN80  PVCCFA_EHV_FIVRA_CPU1  VCCFA_EHV_FIVRA21  @S9S_MB_2U_LIB.S9S_MB_2U(SCH_1):PVCCFA_EHV_FIVRA_CPU1
  AN7  PVCCFA_EHV_FIVRA_CPU1  VCCFA_EHV_FIVRA20  @S9S_MB_2U_LIB.S9S_MB_2U(SCH_1):PVCCFA_EHV_FIVRA_CPU1
  AN15  PVCCFA_EHV_FIVRA_CPU1  VCCFA_EHV_FIVRA19  @S9S_MB_2U_LIB.S9S_MB_2U(SCH_1):PVCCFA_EHV_FIVRA_CPU1
  AN11  PVCCFA_EHV_FIVRA_CPU1  VCCFA_EHV_FIVRA18  @S9S_MB_2U_LIB.S9S_MB_2U(SCH_1):PVCCFA_EHV_FIVRA_CPU1
  AM89  PVCCFA_EHV_FIVRA_CPU1  VCCFA_EHV_FIVRA17  @S9S_MB_2U_LIB.S9S_MB_2U(SCH_1):PVCCFA_EHV_FIVRA_CPU1
  AM85  PVCCFA_EHV_FIVRA_CPU1  VCCFA_EHV_FIVRA16  @S9S_MB_2U_LIB.S9S_MB_2U(SCH_1):PVCCFA_EHV_FIVRA_CPU1
  AM79  PVCCFA_EHV_FIVRA_CPU1  VCCFA_EHV_FIVRA15  @S9S_MB_2U_LIB.S9S_MB_2U(SCH_1):PVCCFA_EHV_FIVRA_CPU1
  AJ7  PVCCFA_EHV_FIVRA_CPU1  VCCFA_EHV_FIVRA14  @S9S_MB_2U_LIB.S9S_MB_2U(SCH_1):PVCCFA_EHV_FIVRA_CPU1
  AJ15  PVCCFA_EHV_FIVRA_CPU1  VCCFA_EHV_FIVRA13  @S9S_MB_2U_LIB.S9S_MB_2U(SCH_1):PVCCFA_EHV_FIVRA_CPU1
  AJ11  PVCCFA_EHV_FIVRA_CPU1  VCCFA_EHV_FIVRA12  @S9S_MB_2U_LIB.S9S_MB_2U(SCH_1):PVCCFA_EHV_FIVRA_CPU1
  AH89  PVCCFA_EHV_FIVRA_CPU1  VCCFA_EHV_FIVRA11  @S9S_MB_2U_LIB.S9S_MB_2U(SCH_1):PVCCFA_EHV_FIVRA_CPU1
  AH85  PVCCFA_EHV_FIVRA_CPU1  VCCFA_EHV_FIVRA10  @S9S_MB_2U_LIB.S9S_MB_2U(SCH_1):PVCCFA_EHV_FIVRA_CPU1
  AG78  PVCCFA_EHV_FIVRA_CPU1  VCCFA_EHV_FIVRA9  @S9S_MB_2U_LIB.S9S_MB_2U(SCH_1):PVCCFA_EHV_FIVRA_CPU1
  AF77  PVCCFA_EHV_FIVRA_CPU1  VCCFA_EHV_FIVRA8  @S9S_MB_2U_LIB.S9S_MB_2U(SCH_1):PVCCFA_EHV_FIVRA_CPU1
  AE7  PVCCFA_EHV_FIVRA_CPU1  VCCFA_EHV_FIVRA7  @S9S_MB_2U_LIB.S9S_MB_2U(SCH_1):PVCCFA_EHV_FIVRA_CPU1
  AE15  PVCCFA_EHV_FIVRA_CPU1  VCCFA_EHV_FIVRA6  @S9S_MB_2U_LIB.S9S_MB_2U(SCH_1):PVCCFA_EHV_FIVRA_CPU1
  AE11  PVCCFA_EHV_FIVRA_CPU1  VCCFA_EHV_FIVRA5  @S9S_MB_2U_LIB.S9S_MB_2U(SCH_1):PVCCFA_EHV_FIVRA_CPU1
  AD89  PVCCFA_EHV_FIVRA_CPU1  VCCFA_EHV_FIVRA4  @S9S_MB_2U_LIB.S9S_MB_2U(SCH_1):PVCCFA_EHV_FIVRA_CPU1
  AD85  PVCCFA_EHV_FIVRA_CPU1  VCCFA_EHV_FIVRA3  @S9S_MB_2U_LIB.S9S_MB_2U(SCH_1):PVCCFA_EHV_FIVRA_CPU1
  AA7  PVCCFA_EHV_FIVRA_CPU1  VCCFA_EHV_FIVRA2  @S9S_MB_2U_LIB.S9S_MB_2U(SCH_1):PVCCFA_EHV_FIVRA_CPU1
  AA15  PVCCFA_EHV_FIVRA_CPU1  VCCFA_EHV_FIVRA1  @S9S_MB_2U_LIB.S9S_MB_2U(SCH_1):PVCCFA_EHV_FIVRA_CPU1
  AA11  PVCCFA_EHV_FIVRA_CPU1  VCCFA_EHV_FIVRA0  @S9S_MB_2U_LIB.S9S_MB_2U(SCH_1):PVCCFA_EHV_FIVRA_CPU1

SOCKET4677_AZIFS054P001C01  I8   U1     [SOCKET4677_AZIFS054P001C01-SOCA]
  CG68  PVPP_HBM_CPU1  VPP_HBM4  @S9S_MB_2U_LIB.S9S_MB_2U(SCH_1):PVPP_HBM_CPU1
  CF67  PVPP_HBM_CPU1  VPP_HBM3  @S9S_MB_2U_LIB.S9S_MB_2U(SCH_1):PVPP_HBM_CPU1
  CE68  PVPP_HBM_CPU1  VPP_HBM2  @S9S_MB_2U_LIB.S9S_MB_2U(SCH_1):PVPP_HBM_CPU1
  CD67  PVPP_HBM_CPU1  VPP_HBM1  @S9S_MB_2U_LIB.S9S_MB_2U(SCH_1):PVPP_HBM_CPU1
  CC68  PVPP_HBM_CPU1  VPP_HBM0  @S9S_MB_2U_LIB.S9S_MB_2U(SCH_1):PVPP_HBM_CPU1
  BN19  PVNN_MAIN_CPU1  VCCVNN3  @S9S_MB_2U_LIB.S9S_MB_2U(SCH_1):PVNN_MAIN_CPU1
  BJ19  PVNN_MAIN_CPU1  VCCVNN2  @S9S_MB_2U_LIB.S9S_MB_2U(SCH_1):PVNN_MAIN_CPU1
  BE19  PVNN_MAIN_CPU1  VCCVNN1  @S9S_MB_2U_LIB.S9S_MB_2U(SCH_1):PVNN_MAIN_CPU1
  BA19  PVNN_MAIN_CPU1  VCCVNN0  @S9S_MB_2U_LIB.S9S_MB_2U(SCH_1):PVNN_MAIN_CPU1
  DJ11  PVCCINFAON_CPU1  VCCINFAON59  @S9S_MB_2U_LIB.S9S_MB_2U(SCH_1):PVCCINFAON_CPU1
  DE7  PVCCINFAON_CPU1  VCCINFAON58  @S9S_MB_2U_LIB.S9S_MB_2U(SCH_1):PVCCINFAON_CPU1
  DA7  PVCCINFAON_CPU1  VCCINFAON57  @S9S_MB_2U_LIB.S9S_MB_2U(SCH_1):PVCCINFAON_CPU1
  DA3  PVCCINFAON_CPU1  VCCINFAON56  @S9S_MB_2U_LIB.S9S_MB_2U(SCH_1):PVCCINFAON_CPU1
  CW64  PVCCINFAON_CPU1  VCCINFAON55  @S9S_MB_2U_LIB.S9S_MB_2U(SCH_1):PVCCINFAON_CPU1
  CR66  PVCCINFAON_CPU1  VCCINFAON54  @S9S_MB_2U_LIB.S9S_MB_2U(SCH_1):PVCCINFAON_CPU1
  DJ7  PVCCINFAON_CPU1  VCCINFAON32  @S9S_MB_2U_LIB.S9S_MB_2U(SCH_1):PVCCINFAON_CPU1
  DJ3  PVCCINFAON_CPU1  VCCINFAON31  @S9S_MB_2U_LIB.S9S_MB_2U(SCH_1):PVCCINFAON_CPU1
  DJ15  PVCCINFAON_CPU1  VCCINFAON30  @S9S_MB_2U_LIB.S9S_MB_2U(SCH_1):PVCCINFAON_CPU1
  DE3  PVCCINFAON_CPU1  VCCINFAON29  @S9S_MB_2U_LIB.S9S_MB_2U(SCH_1):PVCCINFAON_CPU1
  DE15  PVCCINFAON_CPU1  VCCINFAON28  @S9S_MB_2U_LIB.S9S_MB_2U(SCH_1):PVCCINFAON_CPU1
  DE11  PVCCINFAON_CPU1  VCCINFAON27  @S9S_MB_2U_LIB.S9S_MB_2U(SCH_1):PVCCINFAON_CPU1
  DA64  PVCCINFAON_CPU1  VCCINFAON26  @S9S_MB_2U_LIB.S9S_MB_2U(SCH_1):PVCCINFAON_CPU1
  DA15  PVCCINFAON_CPU1  VCCINFAON25  @S9S_MB_2U_LIB.S9S_MB_2U(SCH_1):PVCCINFAON_CPU1
  DA11  PVCCINFAON_CPU1  VCCINFAON24  @S9S_MB_2U_LIB.S9S_MB_2U(SCH_1):PVCCINFAON_CPU1
  CY67  PVCCINFAON_CPU1  VCCINFAON23  @S9S_MB_2U_LIB.S9S_MB_2U(SCH_1):PVCCINFAON_CPU1
  CY65  PVCCINFAON_CPU1  VCCINFAON22  @S9S_MB_2U_LIB.S9S_MB_2U(SCH_1):PVCCINFAON_CPU1
  CW66  PVCCINFAON_CPU1  VCCINFAON21  @S9S_MB_2U_LIB.S9S_MB_2U(SCH_1):PVCCINFAON_CPU1
  CV67  PVCCINFAON_CPU1  VCCINFAON20  @S9S_MB_2U_LIB.S9S_MB_2U(SCH_1):PVCCINFAON_CPU1
  CV65  PVCCINFAON_CPU1  VCCINFAON19  @S9S_MB_2U_LIB.S9S_MB_2U(SCH_1):PVCCINFAON_CPU1
  CU7  PVCCINFAON_CPU1  VCCINFAON18  @S9S_MB_2U_LIB.S9S_MB_2U(SCH_1):PVCCINFAON_CPU1
  CU64  PVCCINFAON_CPU1  VCCINFAON17  @S9S_MB_2U_LIB.S9S_MB_2U(SCH_1):PVCCINFAON_CPU1
  CU3  PVCCINFAON_CPU1  VCCINFAON16  @S9S_MB_2U_LIB.S9S_MB_2U(SCH_1):PVCCINFAON_CPU1
  CU15  PVCCINFAON_CPU1  VCCINFAON15  @S9S_MB_2U_LIB.S9S_MB_2U(SCH_1):PVCCINFAON_CPU1
  CU11  PVCCINFAON_CPU1  VCCINFAON14  @S9S_MB_2U_LIB.S9S_MB_2U(SCH_1):PVCCINFAON_CPU1
  CT67  PVCCINFAON_CPU1  VCCINFAON13  @S9S_MB_2U_LIB.S9S_MB_2U(SCH_1):PVCCINFAON_CPU1
  CT65  PVCCINFAON_CPU1  VCCINFAON12  @S9S_MB_2U_LIB.S9S_MB_2U(SCH_1):PVCCINFAON_CPU1
  CP67  PVCCINFAON_CPU1  VCCINFAON11  @S9S_MB_2U_LIB.S9S_MB_2U(SCH_1):PVCCINFAON_CPU1
  CP65  PVCCINFAON_CPU1  VCCINFAON10  @S9S_MB_2U_LIB.S9S_MB_2U(SCH_1):PVCCINFAON_CPU1
  CN7  PVCCINFAON_CPU1  VCCINFAON9  @S9S_MB_2U_LIB.S9S_MB_2U(SCH_1):PVCCINFAON_CPU1
  CN66  PVCCINFAON_CPU1  VCCINFAON8  @S9S_MB_2U_LIB.S9S_MB_2U(SCH_1):PVCCINFAON_CPU1
  CN64  PVCCINFAON_CPU1  VCCINFAON7  @S9S_MB_2U_LIB.S9S_MB_2U(SCH_1):PVCCINFAON_CPU1
  CN3  PVCCINFAON_CPU1  VCCINFAON6  @S9S_MB_2U_LIB.S9S_MB_2U(SCH_1):PVCCINFAON_CPU1
  CN15  PVCCINFAON_CPU1  VCCINFAON5  @S9S_MB_2U_LIB.S9S_MB_2U(SCH_1):PVCCINFAON_CPU1
  CN11  PVCCINFAON_CPU1  VCCINFAON4  @S9S_MB_2U_LIB.S9S_MB_2U(SCH_1):PVCCINFAON_CPU1
  CJ7  PVCCINFAON_CPU1  VCCINFAON3  @S9S_MB_2U_LIB.S9S_MB_2U(SCH_1):PVCCINFAON_CPU1
  CJ3  PVCCINFAON_CPU1  VCCINFAON2  @S9S_MB_2U_LIB.S9S_MB_2U(SCH_1):PVCCINFAON_CPU1
  CJ15  PVCCINFAON_CPU1  VCCINFAON1  @S9S_MB_2U_LIB.S9S_MB_2U(SCH_1):PVCCINFAON_CPU1
  CE15  PVCCINFAON_CPU1  VCCINFAON0  @S9S_MB_2U_LIB.S9S_MB_2U(SCH_1):PVCCINFAON_CPU1
   N3  PVCCFA_EHV_CPU1  VCCFA_EHV9  @S9S_MB_2U_LIB.S9S_MB_2U(SCH_1):PVCCFA_EHV_CPU1
   U3  PVCCFA_EHV_CPU1  VCCFA_EHV8  @S9S_MB_2U_LIB.S9S_MB_2U(SCH_1):PVCCFA_EHV_CPU1
  AW60  PVCCFA_EHV_CPU1  VCCFA_EHV7  @S9S_MB_2U_LIB.S9S_MB_2U(SCH_1):PVCCFA_EHV_CPU1
  AV61  PVCCFA_EHV_CPU1  VCCFA_EHV6  @S9S_MB_2U_LIB.S9S_MB_2U(SCH_1):PVCCFA_EHV_CPU1
  AU60  PVCCFA_EHV_CPU1  VCCFA_EHV5  @S9S_MB_2U_LIB.S9S_MB_2U(SCH_1):PVCCFA_EHV_CPU1
  AT61  PVCCFA_EHV_CPU1  VCCFA_EHV4  @S9S_MB_2U_LIB.S9S_MB_2U(SCH_1):PVCCFA_EHV_CPU1
  AN3  PVCCFA_EHV_CPU1  VCCFA_EHV3  @S9S_MB_2U_LIB.S9S_MB_2U(SCH_1):PVCCFA_EHV_CPU1
  AJ3  PVCCFA_EHV_CPU1  VCCFA_EHV2  @S9S_MB_2U_LIB.S9S_MB_2U(SCH_1):PVCCFA_EHV_CPU1
  AE3  PVCCFA_EHV_CPU1  VCCFA_EHV1  @S9S_MB_2U_LIB.S9S_MB_2U(SCH_1):PVCCFA_EHV_CPU1
  AA3  PVCCFA_EHV_CPU1  VCCFA_EHV0  @S9S_MB_2U_LIB.S9S_MB_2U(SCH_1):PVCCFA_EHV_CPU1
  CY53  PVCCD_HV_CPU1  VCCD_HV28  @S9S_MB_2U_LIB.S9S_MB_2U(SCH_1):PVCCD_HV_CPU1
  CY36  PVCCD_HV_CPU1  VCCD_HV27  @S9S_MB_2U_LIB.S9S_MB_2U(SCH_1):PVCCD_HV_CPU1
  CW54  PVCCD_HV_CPU1  VCCD_HV26  @S9S_MB_2U_LIB.S9S_MB_2U(SCH_1):PVCCD_HV_CPU1
  CY34  PVCCD_HV_CPU1  VCCD_HV25  @S9S_MB_2U_LIB.S9S_MB_2U(SCH_1):PVCCD_HV_CPU1
  CW56  PVCCD_HV_CPU1  VCCD_HV24  @S9S_MB_2U_LIB.S9S_MB_2U(SCH_1):PVCCD_HV_CPU1
  CW52  PVCCD_HV_CPU1  VCCD_HV23  @S9S_MB_2U_LIB.S9S_MB_2U(SCH_1):PVCCD_HV_CPU1
  CW37  PVCCD_HV_CPU1  VCCD_HV22  @S9S_MB_2U_LIB.S9S_MB_2U(SCH_1):PVCCD_HV_CPU1
  CW35  PVCCD_HV_CPU1  VCCD_HV21  @S9S_MB_2U_LIB.S9S_MB_2U(SCH_1):PVCCD_HV_CPU1
  CE7  PVCCD_HV_CPU1  VCCD_HV20  @S9S_MB_2U_LIB.S9S_MB_2U(SCH_1):PVCCD_HV_CPU1
  CA7  PVCCD_HV_CPU1  VCCD_HV19  @S9S_MB_2U_LIB.S9S_MB_2U(SCH_1):PVCCD_HV_CPU1
  BN7  PVCCD_HV_CPU1  VCCD_HV18  @S9S_MB_2U_LIB.S9S_MB_2U(SCH_1):PVCCD_HV_CPU1
  BJ7  PVCCD_HV_CPU1  VCCD_HV17  @S9S_MB_2U_LIB.S9S_MB_2U(SCH_1):PVCCD_HV_CPU1
  BJ3  PVCCD_HV_CPU1  VCCD_HV16  @S9S_MB_2U_LIB.S9S_MB_2U(SCH_1):PVCCD_HV_CPU1
  BJ11  PVCCD_HV_CPU1  VCCD_HV15  @S9S_MB_2U_LIB.S9S_MB_2U(SCH_1):PVCCD_HV_CPU1
  BE7  PVCCD_HV_CPU1  VCCD_HV14  @S9S_MB_2U_LIB.S9S_MB_2U(SCH_1):PVCCD_HV_CPU1
  BE3  PVCCD_HV_CPU1  VCCD_HV13  @S9S_MB_2U_LIB.S9S_MB_2U(SCH_1):PVCCD_HV_CPU1
  BE11  PVCCD_HV_CPU1  VCCD_HV12  @S9S_MB_2U_LIB.S9S_MB_2U(SCH_1):PVCCD_HV_CPU1
  BA7  PVCCD_HV_CPU1  VCCD_HV11  @S9S_MB_2U_LIB.S9S_MB_2U(SCH_1):PVCCD_HV_CPU1
  BA3  PVCCD_HV_CPU1  VCCD_HV10  @S9S_MB_2U_LIB.S9S_MB_2U(SCH_1):PVCCD_HV_CPU1
  AV55  PVCCD_HV_CPU1  VCCD_HV9  @S9S_MB_2U_LIB.S9S_MB_2U(SCH_1):PVCCD_HV_CPU1
  AV53  PVCCD_HV_CPU1  VCCD_HV8  @S9S_MB_2U_LIB.S9S_MB_2U(SCH_1):PVCCD_HV_CPU1
  AV36  PVCCD_HV_CPU1  VCCD_HV7  @S9S_MB_2U_LIB.S9S_MB_2U(SCH_1):PVCCD_HV_CPU1
  AV34  PVCCD_HV_CPU1  VCCD_HV6  @S9S_MB_2U_LIB.S9S_MB_2U(SCH_1):PVCCD_HV_CPU1
  AU7  PVCCD_HV_CPU1  VCCD_HV5  @S9S_MB_2U_LIB.S9S_MB_2U(SCH_1):PVCCD_HV_CPU1
  AU54  PVCCD_HV_CPU1  VCCD_HV4  @S9S_MB_2U_LIB.S9S_MB_2U(SCH_1):PVCCD_HV_CPU1
  AU35  PVCCD_HV_CPU1  VCCD_HV3  @S9S_MB_2U_LIB.S9S_MB_2U(SCH_1):PVCCD_HV_CPU1
  AU3  PVCCD_HV_CPU1  VCCD_HV2  @S9S_MB_2U_LIB.S9S_MB_2U(SCH_1):PVCCD_HV_CPU1
  AT55  PVCCD_HV_CPU1  VCCD_HV1  @S9S_MB_2U_LIB.S9S_MB_2U(SCH_1):PVCCD_HV_CPU1
  AT36  PVCCD_HV_CPU1  VCCD_HV0  @S9S_MB_2U_LIB.S9S_MB_2U(SCH_1):PVCCD_HV_CPU1
  BC21  P3V3_AUX       VCCCPLD_3P3V1  @S9S_MB_2U_LIB.S9S_MB_2U(SCH_1):P3V3_AUX
  BA21  P3V3_AUX       VCCCPLD_3P3V0  @S9S_MB_2U_LIB.S9S_MB_2U(SCH_1):P3V3_AUX

SOCKET4677_AZIFS054P001C01  I1   U1     [SOCKET4677_AZIFS054P001C01-SOCA]
  BN41  PVCCIN_CPU1    VCCIN39  @S9S_MB_2U_LIB.S9S_MB_2U(SCH_1):PVCCIN_CPU1
  BN39  PVCCIN_CPU1    VCCIN38  @S9S_MB_2U_LIB.S9S_MB_2U(SCH_1):PVCCIN_CPU1
  BN37  PVCCIN_CPU1    VCCIN37  @S9S_MB_2U_LIB.S9S_MB_2U(SCH_1):PVCCIN_CPU1
  BN35  PVCCIN_CPU1    VCCIN36  @S9S_MB_2U_LIB.S9S_MB_2U(SCH_1):PVCCIN_CPU1
  BN33  PVCCIN_CPU1    VCCIN35  @S9S_MB_2U_LIB.S9S_MB_2U(SCH_1):PVCCIN_CPU1
  BM91  PVCCIN_CPU1    VCCIN34  @S9S_MB_2U_LIB.S9S_MB_2U(SCH_1):PVCCIN_CPU1
  BM89  PVCCIN_CPU1    VCCIN33  @S9S_MB_2U_LIB.S9S_MB_2U(SCH_1):PVCCIN_CPU1
  BM87  PVCCIN_CPU1    VCCIN32  @S9S_MB_2U_LIB.S9S_MB_2U(SCH_1):PVCCIN_CPU1
  BM85  PVCCIN_CPU1    VCCIN31  @S9S_MB_2U_LIB.S9S_MB_2U(SCH_1):PVCCIN_CPU1
  BM83  PVCCIN_CPU1    VCCIN30  @S9S_MB_2U_LIB.S9S_MB_2U(SCH_1):PVCCIN_CPU1
  BM81  PVCCIN_CPU1    VCCIN29  @S9S_MB_2U_LIB.S9S_MB_2U(SCH_1):PVCCIN_CPU1
  BM79  PVCCIN_CPU1    VCCIN28  @S9S_MB_2U_LIB.S9S_MB_2U(SCH_1):PVCCIN_CPU1
  BL90  PVCCIN_CPU1    VCCIN27  @S9S_MB_2U_LIB.S9S_MB_2U(SCH_1):PVCCIN_CPU1
  BL88  PVCCIN_CPU1    VCCIN26  @S9S_MB_2U_LIB.S9S_MB_2U(SCH_1):PVCCIN_CPU1
  BL86  PVCCIN_CPU1    VCCIN25  @S9S_MB_2U_LIB.S9S_MB_2U(SCH_1):PVCCIN_CPU1
  BL84  PVCCIN_CPU1    VCCIN24  @S9S_MB_2U_LIB.S9S_MB_2U(SCH_1):PVCCIN_CPU1
  BL82  PVCCIN_CPU1    VCCIN23  @S9S_MB_2U_LIB.S9S_MB_2U(SCH_1):PVCCIN_CPU1
  BL80  PVCCIN_CPU1    VCCIN22  @S9S_MB_2U_LIB.S9S_MB_2U(SCH_1):PVCCIN_CPU1
  BK91  PVCCIN_CPU1    VCCIN21  @S9S_MB_2U_LIB.S9S_MB_2U(SCH_1):PVCCIN_CPU1
  BK89  PVCCIN_CPU1    VCCIN20  @S9S_MB_2U_LIB.S9S_MB_2U(SCH_1):PVCCIN_CPU1
  BK87  PVCCIN_CPU1    VCCIN19  @S9S_MB_2U_LIB.S9S_MB_2U(SCH_1):PVCCIN_CPU1
  BK85  PVCCIN_CPU1    VCCIN18  @S9S_MB_2U_LIB.S9S_MB_2U(SCH_1):PVCCIN_CPU1
  BK83  PVCCIN_CPU1    VCCIN17  @S9S_MB_2U_LIB.S9S_MB_2U(SCH_1):PVCCIN_CPU1
  BK81  PVCCIN_CPU1    VCCIN16  @S9S_MB_2U_LIB.S9S_MB_2U(SCH_1):PVCCIN_CPU1
  BH91  PVCCIN_CPU1    VCCIN15  @S9S_MB_2U_LIB.S9S_MB_2U(SCH_1):PVCCIN_CPU1
  BH89  PVCCIN_CPU1    VCCIN14  @S9S_MB_2U_LIB.S9S_MB_2U(SCH_1):PVCCIN_CPU1
  BH87  PVCCIN_CPU1    VCCIN13  @S9S_MB_2U_LIB.S9S_MB_2U(SCH_1):PVCCIN_CPU1
  BH85  PVCCIN_CPU1    VCCIN12  @S9S_MB_2U_LIB.S9S_MB_2U(SCH_1):PVCCIN_CPU1
  BG90  PVCCIN_CPU1    VCCIN11  @S9S_MB_2U_LIB.S9S_MB_2U(SCH_1):PVCCIN_CPU1
  BG88  PVCCIN_CPU1    VCCIN10  @S9S_MB_2U_LIB.S9S_MB_2U(SCH_1):PVCCIN_CPU1
  BG86  PVCCIN_CPU1    VCCIN9  @S9S_MB_2U_LIB.S9S_MB_2U(SCH_1):PVCCIN_CPU1
  BG84  PVCCIN_CPU1    VCCIN8  @S9S_MB_2U_LIB.S9S_MB_2U(SCH_1):PVCCIN_CPU1
  BF91  PVCCIN_CPU1    VCCIN7  @S9S_MB_2U_LIB.S9S_MB_2U(SCH_1):PVCCIN_CPU1
  BF89  PVCCIN_CPU1    VCCIN6  @S9S_MB_2U_LIB.S9S_MB_2U(SCH_1):PVCCIN_CPU1
  BF87  PVCCIN_CPU1    VCCIN5  @S9S_MB_2U_LIB.S9S_MB_2U(SCH_1):PVCCIN_CPU1
  BF85  PVCCIN_CPU1    VCCIN4  @S9S_MB_2U_LIB.S9S_MB_2U(SCH_1):PVCCIN_CPU1
  BE90  PVCCIN_CPU1    VCCIN3  @S9S_MB_2U_LIB.S9S_MB_2U(SCH_1):PVCCIN_CPU1
  BE88  PVCCIN_CPU1    VCCIN2  @S9S_MB_2U_LIB.S9S_MB_2U(SCH_1):PVCCIN_CPU1
  BE86  PVCCIN_CPU1    VCCIN1  @S9S_MB_2U_LIB.S9S_MB_2U(SCH_1):PVCCIN_CPU1
  BD91  PVCCIN_CPU1    VCCIN0  @S9S_MB_2U_LIB.S9S_MB_2U(SCH_1):PVCCIN_CPU1
  DA21  PVCCINFAON_CPU1  VCCINFAON53  @S9S_MB_2U_LIB.S9S_MB_2U(SCH_1):PVCCINFAON_CPU1
  CW62  PVCCINFAON_CPU1  VCCINFAON52  @S9S_MB_2U_LIB.S9S_MB_2U(SCH_1):PVCCINFAON_CPU1
  CV63  PVCCINFAON_CPU1  VCCINFAON51  @S9S_MB_2U_LIB.S9S_MB_2U(SCH_1):PVCCINFAON_CPU1
  CV61  PVCCINFAON_CPU1  VCCINFAON50  @S9S_MB_2U_LIB.S9S_MB_2U(SCH_1):PVCCINFAON_CPU1
  CT63  PVCCINFAON_CPU1  VCCINFAON49  @S9S_MB_2U_LIB.S9S_MB_2U(SCH_1):PVCCINFAON_CPU1
  CP63  PVCCINFAON_CPU1  VCCINFAON48  @S9S_MB_2U_LIB.S9S_MB_2U(SCH_1):PVCCINFAON_CPU1
  CN19  PVCCINFAON_CPU1  VCCINFAON47  @S9S_MB_2U_LIB.S9S_MB_2U(SCH_1):PVCCINFAON_CPU1
  CJ19  PVCCINFAON_CPU1  VCCINFAON46  @S9S_MB_2U_LIB.S9S_MB_2U(SCH_1):PVCCINFAON_CPU1
  CJ11  PVCCINFAON_CPU1  VCCINFAON45  @S9S_MB_2U_LIB.S9S_MB_2U(SCH_1):PVCCINFAON_CPU1
  CE19  PVCCINFAON_CPU1  VCCINFAON44  @S9S_MB_2U_LIB.S9S_MB_2U(SCH_1):PVCCINFAON_CPU1
  CA15  PVCCINFAON_CPU1  VCCINFAON43  @S9S_MB_2U_LIB.S9S_MB_2U(SCH_1):PVCCINFAON_CPU1
  BN15  PVCCINFAON_CPU1  VCCINFAON42  @S9S_MB_2U_LIB.S9S_MB_2U(SCH_1):PVCCINFAON_CPU1
  BK61  PVCCINFAON_CPU1  VCCINFAON41  @S9S_MB_2U_LIB.S9S_MB_2U(SCH_1):PVCCINFAON_CPU1
  BJ60  PVCCINFAON_CPU1  VCCINFAON40  @S9S_MB_2U_LIB.S9S_MB_2U(SCH_1):PVCCINFAON_CPU1
  BJ15  PVCCINFAON_CPU1  VCCINFAON39  @S9S_MB_2U_LIB.S9S_MB_2U(SCH_1):PVCCINFAON_CPU1
  BG60  PVCCINFAON_CPU1  VCCINFAON38  @S9S_MB_2U_LIB.S9S_MB_2U(SCH_1):PVCCINFAON_CPU1
  BE60  PVCCINFAON_CPU1  VCCINFAON37  @S9S_MB_2U_LIB.S9S_MB_2U(SCH_1):PVCCINFAON_CPU1
  BE15  PVCCINFAON_CPU1  VCCINFAON36  @S9S_MB_2U_LIB.S9S_MB_2U(SCH_1):PVCCINFAON_CPU1
  BC60  PVCCINFAON_CPU1  VCCINFAON35  @S9S_MB_2U_LIB.S9S_MB_2U(SCH_1):PVCCINFAON_CPU1
  BA15  PVCCINFAON_CPU1  VCCINFAON34  @S9S_MB_2U_LIB.S9S_MB_2U(SCH_1):PVCCINFAON_CPU1
  AY18  PVCCINFAON_CPU1  VCCINFAON33  @S9S_MB_2U_LIB.S9S_MB_2U(SCH_1):PVCCINFAON_CPU1

SOCKET4677_AZIFS054P001C01  I3   U1     [SOCKET4677_AZIFS054P001C01-SOCA]
  BW78  PVCCIN_CPU1    VCCIN189  @S9S_MB_2U_LIB.S9S_MB_2U(SCH_1):PVCCIN_CPU1
  BW76  PVCCIN_CPU1    VCCIN188  @S9S_MB_2U_LIB.S9S_MB_2U(SCH_1):PVCCIN_CPU1
  BW74  PVCCIN_CPU1    VCCIN187  @S9S_MB_2U_LIB.S9S_MB_2U(SCH_1):PVCCIN_CPU1
  BW72  PVCCIN_CPU1    VCCIN186  @S9S_MB_2U_LIB.S9S_MB_2U(SCH_1):PVCCIN_CPU1
  BW70  PVCCIN_CPU1    VCCIN185  @S9S_MB_2U_LIB.S9S_MB_2U(SCH_1):PVCCIN_CPU1
  BW68  PVCCIN_CPU1    VCCIN184  @S9S_MB_2U_LIB.S9S_MB_2U(SCH_1):PVCCIN_CPU1
  BW66  PVCCIN_CPU1    VCCIN183  @S9S_MB_2U_LIB.S9S_MB_2U(SCH_1):PVCCIN_CPU1
  BW64  PVCCIN_CPU1    VCCIN182  @S9S_MB_2U_LIB.S9S_MB_2U(SCH_1):PVCCIN_CPU1
  BW62  PVCCIN_CPU1    VCCIN181  @S9S_MB_2U_LIB.S9S_MB_2U(SCH_1):PVCCIN_CPU1
  BW60  PVCCIN_CPU1    VCCIN180  @S9S_MB_2U_LIB.S9S_MB_2U(SCH_1):PVCCIN_CPU1
  BW58  PVCCIN_CPU1    VCCIN179  @S9S_MB_2U_LIB.S9S_MB_2U(SCH_1):PVCCIN_CPU1
  BW56  PVCCIN_CPU1    VCCIN178  @S9S_MB_2U_LIB.S9S_MB_2U(SCH_1):PVCCIN_CPU1
  BW54  PVCCIN_CPU1    VCCIN177  @S9S_MB_2U_LIB.S9S_MB_2U(SCH_1):PVCCIN_CPU1
  BW52  PVCCIN_CPU1    VCCIN176  @S9S_MB_2U_LIB.S9S_MB_2U(SCH_1):PVCCIN_CPU1
  BW50  PVCCIN_CPU1    VCCIN175  @S9S_MB_2U_LIB.S9S_MB_2U(SCH_1):PVCCIN_CPU1
  BW48  PVCCIN_CPU1    VCCIN174  @S9S_MB_2U_LIB.S9S_MB_2U(SCH_1):PVCCIN_CPU1
  BW45  PVCCIN_CPU1    VCCIN173  @S9S_MB_2U_LIB.S9S_MB_2U(SCH_1):PVCCIN_CPU1
  BW43  PVCCIN_CPU1    VCCIN172  @S9S_MB_2U_LIB.S9S_MB_2U(SCH_1):PVCCIN_CPU1
  BW41  PVCCIN_CPU1    VCCIN171  @S9S_MB_2U_LIB.S9S_MB_2U(SCH_1):PVCCIN_CPU1
  BW39  PVCCIN_CPU1    VCCIN170  @S9S_MB_2U_LIB.S9S_MB_2U(SCH_1):PVCCIN_CPU1
  BW37  PVCCIN_CPU1    VCCIN169  @S9S_MB_2U_LIB.S9S_MB_2U(SCH_1):PVCCIN_CPU1
  BW35  PVCCIN_CPU1    VCCIN168  @S9S_MB_2U_LIB.S9S_MB_2U(SCH_1):PVCCIN_CPU1
  BW33  PVCCIN_CPU1    VCCIN167  @S9S_MB_2U_LIB.S9S_MB_2U(SCH_1):PVCCIN_CPU1
  BV89  PVCCIN_CPU1    VCCIN166  @S9S_MB_2U_LIB.S9S_MB_2U(SCH_1):PVCCIN_CPU1
  BV87  PVCCIN_CPU1    VCCIN165  @S9S_MB_2U_LIB.S9S_MB_2U(SCH_1):PVCCIN_CPU1
  BV85  PVCCIN_CPU1    VCCIN164  @S9S_MB_2U_LIB.S9S_MB_2U(SCH_1):PVCCIN_CPU1
  BV83  PVCCIN_CPU1    VCCIN163  @S9S_MB_2U_LIB.S9S_MB_2U(SCH_1):PVCCIN_CPU1
  BV81  PVCCIN_CPU1    VCCIN162  @S9S_MB_2U_LIB.S9S_MB_2U(SCH_1):PVCCIN_CPU1
  BV79  PVCCIN_CPU1    VCCIN161  @S9S_MB_2U_LIB.S9S_MB_2U(SCH_1):PVCCIN_CPU1
  BV77  PVCCIN_CPU1    VCCIN160  @S9S_MB_2U_LIB.S9S_MB_2U(SCH_1):PVCCIN_CPU1
  BV75  PVCCIN_CPU1    VCCIN159  @S9S_MB_2U_LIB.S9S_MB_2U(SCH_1):PVCCIN_CPU1
  BV73  PVCCIN_CPU1    VCCIN158  @S9S_MB_2U_LIB.S9S_MB_2U(SCH_1):PVCCIN_CPU1
  BV71  PVCCIN_CPU1    VCCIN157  @S9S_MB_2U_LIB.S9S_MB_2U(SCH_1):PVCCIN_CPU1
  BV69  PVCCIN_CPU1    VCCIN156  @S9S_MB_2U_LIB.S9S_MB_2U(SCH_1):PVCCIN_CPU1
  BV67  PVCCIN_CPU1    VCCIN155  @S9S_MB_2U_LIB.S9S_MB_2U(SCH_1):PVCCIN_CPU1
  BV65  PVCCIN_CPU1    VCCIN154  @S9S_MB_2U_LIB.S9S_MB_2U(SCH_1):PVCCIN_CPU1
  BV63  PVCCIN_CPU1    VCCIN153  @S9S_MB_2U_LIB.S9S_MB_2U(SCH_1):PVCCIN_CPU1
  BV61  PVCCIN_CPU1    VCCIN152  @S9S_MB_2U_LIB.S9S_MB_2U(SCH_1):PVCCIN_CPU1
  BV59  PVCCIN_CPU1    VCCIN151  @S9S_MB_2U_LIB.S9S_MB_2U(SCH_1):PVCCIN_CPU1
  BV57  PVCCIN_CPU1    VCCIN150  @S9S_MB_2U_LIB.S9S_MB_2U(SCH_1):PVCCIN_CPU1
  BV55  PVCCIN_CPU1    VCCIN149  @S9S_MB_2U_LIB.S9S_MB_2U(SCH_1):PVCCIN_CPU1
  BV53  PVCCIN_CPU1    VCCIN148  @S9S_MB_2U_LIB.S9S_MB_2U(SCH_1):PVCCIN_CPU1
  BV51  PVCCIN_CPU1    VCCIN147  @S9S_MB_2U_LIB.S9S_MB_2U(SCH_1):PVCCIN_CPU1
  BV49  PVCCIN_CPU1    VCCIN146  @S9S_MB_2U_LIB.S9S_MB_2U(SCH_1):PVCCIN_CPU1
  BV47  PVCCIN_CPU1    VCCIN145  @S9S_MB_2U_LIB.S9S_MB_2U(SCH_1):PVCCIN_CPU1
  BV44  PVCCIN_CPU1    VCCIN144  @S9S_MB_2U_LIB.S9S_MB_2U(SCH_1):PVCCIN_CPU1
  BV42  PVCCIN_CPU1    VCCIN143  @S9S_MB_2U_LIB.S9S_MB_2U(SCH_1):PVCCIN_CPU1
  BV40  PVCCIN_CPU1    VCCIN142  @S9S_MB_2U_LIB.S9S_MB_2U(SCH_1):PVCCIN_CPU1
  BV38  PVCCIN_CPU1    VCCIN141  @S9S_MB_2U_LIB.S9S_MB_2U(SCH_1):PVCCIN_CPU1
  BV36  PVCCIN_CPU1    VCCIN140  @S9S_MB_2U_LIB.S9S_MB_2U(SCH_1):PVCCIN_CPU1
  BV34  PVCCIN_CPU1    VCCIN139  @S9S_MB_2U_LIB.S9S_MB_2U(SCH_1):PVCCIN_CPU1
  BV32  PVCCIN_CPU1    VCCIN138  @S9S_MB_2U_LIB.S9S_MB_2U(SCH_1):PVCCIN_CPU1
  BU90  PVCCIN_CPU1    VCCIN137  @S9S_MB_2U_LIB.S9S_MB_2U(SCH_1):PVCCIN_CPU1
  BU88  PVCCIN_CPU1    VCCIN136  @S9S_MB_2U_LIB.S9S_MB_2U(SCH_1):PVCCIN_CPU1
  BU86  PVCCIN_CPU1    VCCIN135  @S9S_MB_2U_LIB.S9S_MB_2U(SCH_1):PVCCIN_CPU1
  BU84  PVCCIN_CPU1    VCCIN134  @S9S_MB_2U_LIB.S9S_MB_2U(SCH_1):PVCCIN_CPU1
  BU82  PVCCIN_CPU1    VCCIN133  @S9S_MB_2U_LIB.S9S_MB_2U(SCH_1):PVCCIN_CPU1
  BU80  PVCCIN_CPU1    VCCIN132  @S9S_MB_2U_LIB.S9S_MB_2U(SCH_1):PVCCIN_CPU1
  BU78  PVCCIN_CPU1    VCCIN131  @S9S_MB_2U_LIB.S9S_MB_2U(SCH_1):PVCCIN_CPU1
  BU76  PVCCIN_CPU1    VCCIN130  @S9S_MB_2U_LIB.S9S_MB_2U(SCH_1):PVCCIN_CPU1
  BU74  PVCCIN_CPU1    VCCIN129  @S9S_MB_2U_LIB.S9S_MB_2U(SCH_1):PVCCIN_CPU1
  BU72  PVCCIN_CPU1    VCCIN128  @S9S_MB_2U_LIB.S9S_MB_2U(SCH_1):PVCCIN_CPU1
  BU70  PVCCIN_CPU1    VCCIN127  @S9S_MB_2U_LIB.S9S_MB_2U(SCH_1):PVCCIN_CPU1
  BU68  PVCCIN_CPU1    VCCIN126  @S9S_MB_2U_LIB.S9S_MB_2U(SCH_1):PVCCIN_CPU1
  BU66  PVCCIN_CPU1    VCCIN125  @S9S_MB_2U_LIB.S9S_MB_2U(SCH_1):PVCCIN_CPU1
  BU64  PVCCIN_CPU1    VCCIN124  @S9S_MB_2U_LIB.S9S_MB_2U(SCH_1):PVCCIN_CPU1
  BU62  PVCCIN_CPU1    VCCIN123  @S9S_MB_2U_LIB.S9S_MB_2U(SCH_1):PVCCIN_CPU1
  BU60  PVCCIN_CPU1    VCCIN122  @S9S_MB_2U_LIB.S9S_MB_2U(SCH_1):PVCCIN_CPU1
  BU58  PVCCIN_CPU1    VCCIN121  @S9S_MB_2U_LIB.S9S_MB_2U(SCH_1):PVCCIN_CPU1
  BU56  PVCCIN_CPU1    VCCIN120  @S9S_MB_2U_LIB.S9S_MB_2U(SCH_1):PVCCIN_CPU1
  BU54  PVCCIN_CPU1    VCCIN119  @S9S_MB_2U_LIB.S9S_MB_2U(SCH_1):PVCCIN_CPU1
  BU52  PVCCIN_CPU1    VCCIN118  @S9S_MB_2U_LIB.S9S_MB_2U(SCH_1):PVCCIN_CPU1
  BU50  PVCCIN_CPU1    VCCIN117  @S9S_MB_2U_LIB.S9S_MB_2U(SCH_1):PVCCIN_CPU1
  BU48  PVCCIN_CPU1    VCCIN116  @S9S_MB_2U_LIB.S9S_MB_2U(SCH_1):PVCCIN_CPU1
  BU45  PVCCIN_CPU1    VCCIN115  @S9S_MB_2U_LIB.S9S_MB_2U(SCH_1):PVCCIN_CPU1
  BU43  PVCCIN_CPU1    VCCIN114  @S9S_MB_2U_LIB.S9S_MB_2U(SCH_1):PVCCIN_CPU1
  BU41  PVCCIN_CPU1    VCCIN113  @S9S_MB_2U_LIB.S9S_MB_2U(SCH_1):PVCCIN_CPU1
  BU39  PVCCIN_CPU1    VCCIN112  @S9S_MB_2U_LIB.S9S_MB_2U(SCH_1):PVCCIN_CPU1
  BU37  PVCCIN_CPU1    VCCIN111  @S9S_MB_2U_LIB.S9S_MB_2U(SCH_1):PVCCIN_CPU1
  BU35  PVCCIN_CPU1    VCCIN110  @S9S_MB_2U_LIB.S9S_MB_2U(SCH_1):PVCCIN_CPU1
  BU33  PVCCIN_CPU1    VCCIN109  @S9S_MB_2U_LIB.S9S_MB_2U(SCH_1):PVCCIN_CPU1
  BT89  PVCCIN_CPU1    VCCIN108  @S9S_MB_2U_LIB.S9S_MB_2U(SCH_1):PVCCIN_CPU1
  BT87  PVCCIN_CPU1    VCCIN107  @S9S_MB_2U_LIB.S9S_MB_2U(SCH_1):PVCCIN_CPU1
  BT85  PVCCIN_CPU1    VCCIN106  @S9S_MB_2U_LIB.S9S_MB_2U(SCH_1):PVCCIN_CPU1
  BT83  PVCCIN_CPU1    VCCIN105  @S9S_MB_2U_LIB.S9S_MB_2U(SCH_1):PVCCIN_CPU1
  BT81  PVCCIN_CPU1    VCCIN104  @S9S_MB_2U_LIB.S9S_MB_2U(SCH_1):PVCCIN_CPU1
  BT79  PVCCIN_CPU1    VCCIN103  @S9S_MB_2U_LIB.S9S_MB_2U(SCH_1):PVCCIN_CPU1
  BT77  PVCCIN_CPU1    VCCIN102  @S9S_MB_2U_LIB.S9S_MB_2U(SCH_1):PVCCIN_CPU1
  BT75  PVCCIN_CPU1    VCCIN101  @S9S_MB_2U_LIB.S9S_MB_2U(SCH_1):PVCCIN_CPU1
  BT73  PVCCIN_CPU1    VCCIN100  @S9S_MB_2U_LIB.S9S_MB_2U(SCH_1):PVCCIN_CPU1
  BT71  PVCCIN_CPU1    VCCIN99  @S9S_MB_2U_LIB.S9S_MB_2U(SCH_1):PVCCIN_CPU1
  BT69  PVCCIN_CPU1    VCCIN98  @S9S_MB_2U_LIB.S9S_MB_2U(SCH_1):PVCCIN_CPU1
  BT67  PVCCIN_CPU1    VCCIN97  @S9S_MB_2U_LIB.S9S_MB_2U(SCH_1):PVCCIN_CPU1
  BT65  PVCCIN_CPU1    VCCIN96  @S9S_MB_2U_LIB.S9S_MB_2U(SCH_1):PVCCIN_CPU1
  BT63  PVCCIN_CPU1    VCCIN95  @S9S_MB_2U_LIB.S9S_MB_2U(SCH_1):PVCCIN_CPU1
  BT61  PVCCIN_CPU1    VCCIN94  @S9S_MB_2U_LIB.S9S_MB_2U(SCH_1):PVCCIN_CPU1
  BT59  PVCCIN_CPU1    VCCIN93  @S9S_MB_2U_LIB.S9S_MB_2U(SCH_1):PVCCIN_CPU1
  BT57  PVCCIN_CPU1    VCCIN92  @S9S_MB_2U_LIB.S9S_MB_2U(SCH_1):PVCCIN_CPU1
  BT55  PVCCIN_CPU1    VCCIN91  @S9S_MB_2U_LIB.S9S_MB_2U(SCH_1):PVCCIN_CPU1
  BT53  PVCCIN_CPU1    VCCIN90  @S9S_MB_2U_LIB.S9S_MB_2U(SCH_1):PVCCIN_CPU1
  BT51  PVCCIN_CPU1    VCCIN89  @S9S_MB_2U_LIB.S9S_MB_2U(SCH_1):PVCCIN_CPU1
  BT49  PVCCIN_CPU1    VCCIN88  @S9S_MB_2U_LIB.S9S_MB_2U(SCH_1):PVCCIN_CPU1
  BT47  PVCCIN_CPU1    VCCIN87  @S9S_MB_2U_LIB.S9S_MB_2U(SCH_1):PVCCIN_CPU1
  BT44  PVCCIN_CPU1    VCCIN86  @S9S_MB_2U_LIB.S9S_MB_2U(SCH_1):PVCCIN_CPU1
  BT42  PVCCIN_CPU1    VCCIN85  @S9S_MB_2U_LIB.S9S_MB_2U(SCH_1):PVCCIN_CPU1
  BT40  PVCCIN_CPU1    VCCIN84  @S9S_MB_2U_LIB.S9S_MB_2U(SCH_1):PVCCIN_CPU1
  BT38  PVCCIN_CPU1    VCCIN83  @S9S_MB_2U_LIB.S9S_MB_2U(SCH_1):PVCCIN_CPU1
  BT36  PVCCIN_CPU1    VCCIN82  @S9S_MB_2U_LIB.S9S_MB_2U(SCH_1):PVCCIN_CPU1
  BT34  PVCCIN_CPU1    VCCIN81  @S9S_MB_2U_LIB.S9S_MB_2U(SCH_1):PVCCIN_CPU1
  BT32  PVCCIN_CPU1    VCCIN80  @S9S_MB_2U_LIB.S9S_MB_2U(SCH_1):PVCCIN_CPU1
  BR78  PVCCIN_CPU1    VCCIN79  @S9S_MB_2U_LIB.S9S_MB_2U(SCH_1):PVCCIN_CPU1
  BR62  PVCCIN_CPU1    VCCIN78  @S9S_MB_2U_LIB.S9S_MB_2U(SCH_1):PVCCIN_CPU1
  BR60  PVCCIN_CPU1    VCCIN77  @S9S_MB_2U_LIB.S9S_MB_2U(SCH_1):PVCCIN_CPU1
  BP89  PVCCIN_CPU1    VCCIN76  @S9S_MB_2U_LIB.S9S_MB_2U(SCH_1):PVCCIN_CPU1
  BP87  PVCCIN_CPU1    VCCIN75  @S9S_MB_2U_LIB.S9S_MB_2U(SCH_1):PVCCIN_CPU1
  BP85  PVCCIN_CPU1    VCCIN74  @S9S_MB_2U_LIB.S9S_MB_2U(SCH_1):PVCCIN_CPU1
  BP83  PVCCIN_CPU1    VCCIN73  @S9S_MB_2U_LIB.S9S_MB_2U(SCH_1):PVCCIN_CPU1
  BP81  PVCCIN_CPU1    VCCIN72  @S9S_MB_2U_LIB.S9S_MB_2U(SCH_1):PVCCIN_CPU1
  BP79  PVCCIN_CPU1    VCCIN71  @S9S_MB_2U_LIB.S9S_MB_2U(SCH_1):PVCCIN_CPU1
  BP61  PVCCIN_CPU1    VCCIN70  @S9S_MB_2U_LIB.S9S_MB_2U(SCH_1):PVCCIN_CPU1
  BP59  PVCCIN_CPU1    VCCIN69  @S9S_MB_2U_LIB.S9S_MB_2U(SCH_1):PVCCIN_CPU1
  BP57  PVCCIN_CPU1    VCCIN68  @S9S_MB_2U_LIB.S9S_MB_2U(SCH_1):PVCCIN_CPU1
  BP55  PVCCIN_CPU1    VCCIN67  @S9S_MB_2U_LIB.S9S_MB_2U(SCH_1):PVCCIN_CPU1
  BP53  PVCCIN_CPU1    VCCIN66  @S9S_MB_2U_LIB.S9S_MB_2U(SCH_1):PVCCIN_CPU1
  BP51  PVCCIN_CPU1    VCCIN65  @S9S_MB_2U_LIB.S9S_MB_2U(SCH_1):PVCCIN_CPU1
  BP49  PVCCIN_CPU1    VCCIN64  @S9S_MB_2U_LIB.S9S_MB_2U(SCH_1):PVCCIN_CPU1
  BP47  PVCCIN_CPU1    VCCIN63  @S9S_MB_2U_LIB.S9S_MB_2U(SCH_1):PVCCIN_CPU1
  BP44  PVCCIN_CPU1    VCCIN62  @S9S_MB_2U_LIB.S9S_MB_2U(SCH_1):PVCCIN_CPU1
  BP42  PVCCIN_CPU1    VCCIN61  @S9S_MB_2U_LIB.S9S_MB_2U(SCH_1):PVCCIN_CPU1
  BP40  PVCCIN_CPU1    VCCIN60  @S9S_MB_2U_LIB.S9S_MB_2U(SCH_1):PVCCIN_CPU1
  BP38  PVCCIN_CPU1    VCCIN59  @S9S_MB_2U_LIB.S9S_MB_2U(SCH_1):PVCCIN_CPU1
  BP36  PVCCIN_CPU1    VCCIN58  @S9S_MB_2U_LIB.S9S_MB_2U(SCH_1):PVCCIN_CPU1
  BP34  PVCCIN_CPU1    VCCIN57  @S9S_MB_2U_LIB.S9S_MB_2U(SCH_1):PVCCIN_CPU1
  BP32  PVCCIN_CPU1    VCCIN56  @S9S_MB_2U_LIB.S9S_MB_2U(SCH_1):PVCCIN_CPU1
  BN90  PVCCIN_CPU1    VCCIN55  @S9S_MB_2U_LIB.S9S_MB_2U(SCH_1):PVCCIN_CPU1
  BN88  PVCCIN_CPU1    VCCIN54  @S9S_MB_2U_LIB.S9S_MB_2U(SCH_1):PVCCIN_CPU1
  BN86  PVCCIN_CPU1    VCCIN53  @S9S_MB_2U_LIB.S9S_MB_2U(SCH_1):PVCCIN_CPU1
  BN84  PVCCIN_CPU1    VCCIN52  @S9S_MB_2U_LIB.S9S_MB_2U(SCH_1):PVCCIN_CPU1
  BN82  PVCCIN_CPU1    VCCIN51  @S9S_MB_2U_LIB.S9S_MB_2U(SCH_1):PVCCIN_CPU1
  BN80  PVCCIN_CPU1    VCCIN50  @S9S_MB_2U_LIB.S9S_MB_2U(SCH_1):PVCCIN_CPU1
  BN78  PVCCIN_CPU1    VCCIN49  @S9S_MB_2U_LIB.S9S_MB_2U(SCH_1):PVCCIN_CPU1
  BN60  PVCCIN_CPU1    VCCIN48  @S9S_MB_2U_LIB.S9S_MB_2U(SCH_1):PVCCIN_CPU1
  BN58  PVCCIN_CPU1    VCCIN47  @S9S_MB_2U_LIB.S9S_MB_2U(SCH_1):PVCCIN_CPU1
  BN56  PVCCIN_CPU1    VCCIN46  @S9S_MB_2U_LIB.S9S_MB_2U(SCH_1):PVCCIN_CPU1
  BN54  PVCCIN_CPU1    VCCIN45  @S9S_MB_2U_LIB.S9S_MB_2U(SCH_1):PVCCIN_CPU1
  BN52  PVCCIN_CPU1    VCCIN44  @S9S_MB_2U_LIB.S9S_MB_2U(SCH_1):PVCCIN_CPU1
  BN50  PVCCIN_CPU1    VCCIN43  @S9S_MB_2U_LIB.S9S_MB_2U(SCH_1):PVCCIN_CPU1
  BN48  PVCCIN_CPU1    VCCIN42  @S9S_MB_2U_LIB.S9S_MB_2U(SCH_1):PVCCIN_CPU1
  BN45  PVCCIN_CPU1    VCCIN41  @S9S_MB_2U_LIB.S9S_MB_2U(SCH_1):PVCCIN_CPU1
  BN43  PVCCIN_CPU1    VCCIN40  @S9S_MB_2U_LIB.S9S_MB_2U(SCH_1):PVCCIN_CPU1

SOCKET4677_AZIFS054P001C01  I1   U1     [SOCKET4677_AZIFS054P001C01-SOCA]
  CM89  PVCCIN_CPU1    VCCIN339  @S9S_MB_2U_LIB.S9S_MB_2U(SCH_1):PVCCIN_CPU1
  CP89  PVCCIN_CPU1    VCCIN338  @S9S_MB_2U_LIB.S9S_MB_2U(SCH_1):PVCCIN_CPU1
  CN90  PVCCIN_CPU1    VCCIN337  @S9S_MB_2U_LIB.S9S_MB_2U(SCH_1):PVCCIN_CPU1
  CN88  PVCCIN_CPU1    VCCIN336  @S9S_MB_2U_LIB.S9S_MB_2U(SCH_1):PVCCIN_CPU1
  CM91  PVCCIN_CPU1    VCCIN335  @S9S_MB_2U_LIB.S9S_MB_2U(SCH_1):PVCCIN_CPU1
  CM87  PVCCIN_CPU1    VCCIN334  @S9S_MB_2U_LIB.S9S_MB_2U(SCH_1):PVCCIN_CPU1
  CL90  PVCCIN_CPU1    VCCIN333  @S9S_MB_2U_LIB.S9S_MB_2U(SCH_1):PVCCIN_CPU1
  CL88  PVCCIN_CPU1    VCCIN332  @S9S_MB_2U_LIB.S9S_MB_2U(SCH_1):PVCCIN_CPU1
  CL86  PVCCIN_CPU1    VCCIN331  @S9S_MB_2U_LIB.S9S_MB_2U(SCH_1):PVCCIN_CPU1
  CL84  PVCCIN_CPU1    VCCIN330  @S9S_MB_2U_LIB.S9S_MB_2U(SCH_1):PVCCIN_CPU1
  CK91  PVCCIN_CPU1    VCCIN329  @S9S_MB_2U_LIB.S9S_MB_2U(SCH_1):PVCCIN_CPU1
  CK89  PVCCIN_CPU1    VCCIN328  @S9S_MB_2U_LIB.S9S_MB_2U(SCH_1):PVCCIN_CPU1
  CK87  PVCCIN_CPU1    VCCIN327  @S9S_MB_2U_LIB.S9S_MB_2U(SCH_1):PVCCIN_CPU1
  CK85  PVCCIN_CPU1    VCCIN326  @S9S_MB_2U_LIB.S9S_MB_2U(SCH_1):PVCCIN_CPU1
  CK83  PVCCIN_CPU1    VCCIN325  @S9S_MB_2U_LIB.S9S_MB_2U(SCH_1):PVCCIN_CPU1
  CJ90  PVCCIN_CPU1    VCCIN324  @S9S_MB_2U_LIB.S9S_MB_2U(SCH_1):PVCCIN_CPU1
  CJ88  PVCCIN_CPU1    VCCIN323  @S9S_MB_2U_LIB.S9S_MB_2U(SCH_1):PVCCIN_CPU1
  CJ86  PVCCIN_CPU1    VCCIN322  @S9S_MB_2U_LIB.S9S_MB_2U(SCH_1):PVCCIN_CPU1
  CJ84  PVCCIN_CPU1    VCCIN321  @S9S_MB_2U_LIB.S9S_MB_2U(SCH_1):PVCCIN_CPU1
  CJ82  PVCCIN_CPU1    VCCIN320  @S9S_MB_2U_LIB.S9S_MB_2U(SCH_1):PVCCIN_CPU1
  CH91  PVCCIN_CPU1    VCCIN319  @S9S_MB_2U_LIB.S9S_MB_2U(SCH_1):PVCCIN_CPU1
  CH81  PVCCIN_CPU1    VCCIN318  @S9S_MB_2U_LIB.S9S_MB_2U(SCH_1):PVCCIN_CPU1
  CG90  PVCCIN_CPU1    VCCIN317  @S9S_MB_2U_LIB.S9S_MB_2U(SCH_1):PVCCIN_CPU1
  CG88  PVCCIN_CPU1    VCCIN316  @S9S_MB_2U_LIB.S9S_MB_2U(SCH_1):PVCCIN_CPU1
  CG86  PVCCIN_CPU1    VCCIN315  @S9S_MB_2U_LIB.S9S_MB_2U(SCH_1):PVCCIN_CPU1
  CG84  PVCCIN_CPU1    VCCIN314  @S9S_MB_2U_LIB.S9S_MB_2U(SCH_1):PVCCIN_CPU1
  CG82  PVCCIN_CPU1    VCCIN313  @S9S_MB_2U_LIB.S9S_MB_2U(SCH_1):PVCCIN_CPU1
  CG80  PVCCIN_CPU1    VCCIN312  @S9S_MB_2U_LIB.S9S_MB_2U(SCH_1):PVCCIN_CPU1
  CF91  PVCCIN_CPU1    VCCIN311  @S9S_MB_2U_LIB.S9S_MB_2U(SCH_1):PVCCIN_CPU1
  CF89  PVCCIN_CPU1    VCCIN310  @S9S_MB_2U_LIB.S9S_MB_2U(SCH_1):PVCCIN_CPU1
  CF87  PVCCIN_CPU1    VCCIN309  @S9S_MB_2U_LIB.S9S_MB_2U(SCH_1):PVCCIN_CPU1
  CF85  PVCCIN_CPU1    VCCIN308  @S9S_MB_2U_LIB.S9S_MB_2U(SCH_1):PVCCIN_CPU1
  CF83  PVCCIN_CPU1    VCCIN307  @S9S_MB_2U_LIB.S9S_MB_2U(SCH_1):PVCCIN_CPU1
  CF81  PVCCIN_CPU1    VCCIN306  @S9S_MB_2U_LIB.S9S_MB_2U(SCH_1):PVCCIN_CPU1
  CF79  PVCCIN_CPU1    VCCIN305  @S9S_MB_2U_LIB.S9S_MB_2U(SCH_1):PVCCIN_CPU1
  CE90  PVCCIN_CPU1    VCCIN304  @S9S_MB_2U_LIB.S9S_MB_2U(SCH_1):PVCCIN_CPU1
  CE88  PVCCIN_CPU1    VCCIN303  @S9S_MB_2U_LIB.S9S_MB_2U(SCH_1):PVCCIN_CPU1
  CE86  PVCCIN_CPU1    VCCIN302  @S9S_MB_2U_LIB.S9S_MB_2U(SCH_1):PVCCIN_CPU1
  CE84  PVCCIN_CPU1    VCCIN301  @S9S_MB_2U_LIB.S9S_MB_2U(SCH_1):PVCCIN_CPU1
  CE82  PVCCIN_CPU1    VCCIN300  @S9S_MB_2U_LIB.S9S_MB_2U(SCH_1):PVCCIN_CPU1
  CE80  PVCCIN_CPU1    VCCIN299  @S9S_MB_2U_LIB.S9S_MB_2U(SCH_1):PVCCIN_CPU1
  CD89  PVCCIN_CPU1    VCCIN298  @S9S_MB_2U_LIB.S9S_MB_2U(SCH_1):PVCCIN_CPU1
  CD87  PVCCIN_CPU1    VCCIN297  @S9S_MB_2U_LIB.S9S_MB_2U(SCH_1):PVCCIN_CPU1
  CD85  PVCCIN_CPU1    VCCIN296  @S9S_MB_2U_LIB.S9S_MB_2U(SCH_1):PVCCIN_CPU1
  CD83  PVCCIN_CPU1    VCCIN295  @S9S_MB_2U_LIB.S9S_MB_2U(SCH_1):PVCCIN_CPU1
  CD81  PVCCIN_CPU1    VCCIN294  @S9S_MB_2U_LIB.S9S_MB_2U(SCH_1):PVCCIN_CPU1
  CD79  PVCCIN_CPU1    VCCIN293  @S9S_MB_2U_LIB.S9S_MB_2U(SCH_1):PVCCIN_CPU1
  CD59  PVCCIN_CPU1    VCCIN292  @S9S_MB_2U_LIB.S9S_MB_2U(SCH_1):PVCCIN_CPU1
  CD57  PVCCIN_CPU1    VCCIN291  @S9S_MB_2U_LIB.S9S_MB_2U(SCH_1):PVCCIN_CPU1
  CD55  PVCCIN_CPU1    VCCIN290  @S9S_MB_2U_LIB.S9S_MB_2U(SCH_1):PVCCIN_CPU1
  CD53  PVCCIN_CPU1    VCCIN289  @S9S_MB_2U_LIB.S9S_MB_2U(SCH_1):PVCCIN_CPU1
  CD51  PVCCIN_CPU1    VCCIN288  @S9S_MB_2U_LIB.S9S_MB_2U(SCH_1):PVCCIN_CPU1
  CD49  PVCCIN_CPU1    VCCIN287  @S9S_MB_2U_LIB.S9S_MB_2U(SCH_1):PVCCIN_CPU1
  CD47  PVCCIN_CPU1    VCCIN286  @S9S_MB_2U_LIB.S9S_MB_2U(SCH_1):PVCCIN_CPU1
  CD44  PVCCIN_CPU1    VCCIN285  @S9S_MB_2U_LIB.S9S_MB_2U(SCH_1):PVCCIN_CPU1
  CD42  PVCCIN_CPU1    VCCIN284  @S9S_MB_2U_LIB.S9S_MB_2U(SCH_1):PVCCIN_CPU1
  CD40  PVCCIN_CPU1    VCCIN283  @S9S_MB_2U_LIB.S9S_MB_2U(SCH_1):PVCCIN_CPU1
  CD38  PVCCIN_CPU1    VCCIN282  @S9S_MB_2U_LIB.S9S_MB_2U(SCH_1):PVCCIN_CPU1
  CD36  PVCCIN_CPU1    VCCIN281  @S9S_MB_2U_LIB.S9S_MB_2U(SCH_1):PVCCIN_CPU1
  CD34  PVCCIN_CPU1    VCCIN280  @S9S_MB_2U_LIB.S9S_MB_2U(SCH_1):PVCCIN_CPU1
  CD32  PVCCIN_CPU1    VCCIN279  @S9S_MB_2U_LIB.S9S_MB_2U(SCH_1):PVCCIN_CPU1
  CC90  PVCCIN_CPU1    VCCIN278  @S9S_MB_2U_LIB.S9S_MB_2U(SCH_1):PVCCIN_CPU1
  CC88  PVCCIN_CPU1    VCCIN277  @S9S_MB_2U_LIB.S9S_MB_2U(SCH_1):PVCCIN_CPU1
  CC86  PVCCIN_CPU1    VCCIN276  @S9S_MB_2U_LIB.S9S_MB_2U(SCH_1):PVCCIN_CPU1
  CC84  PVCCIN_CPU1    VCCIN275  @S9S_MB_2U_LIB.S9S_MB_2U(SCH_1):PVCCIN_CPU1
  CC82  PVCCIN_CPU1    VCCIN274  @S9S_MB_2U_LIB.S9S_MB_2U(SCH_1):PVCCIN_CPU1
  CC80  PVCCIN_CPU1    VCCIN273  @S9S_MB_2U_LIB.S9S_MB_2U(SCH_1):PVCCIN_CPU1
  CC78  PVCCIN_CPU1    VCCIN272  @S9S_MB_2U_LIB.S9S_MB_2U(SCH_1):PVCCIN_CPU1
  CC76  PVCCIN_CPU1    VCCIN271  @S9S_MB_2U_LIB.S9S_MB_2U(SCH_1):PVCCIN_CPU1
  CC60  PVCCIN_CPU1    VCCIN270  @S9S_MB_2U_LIB.S9S_MB_2U(SCH_1):PVCCIN_CPU1
  CC58  PVCCIN_CPU1    VCCIN269  @S9S_MB_2U_LIB.S9S_MB_2U(SCH_1):PVCCIN_CPU1
  CC56  PVCCIN_CPU1    VCCIN268  @S9S_MB_2U_LIB.S9S_MB_2U(SCH_1):PVCCIN_CPU1
  CC54  PVCCIN_CPU1    VCCIN267  @S9S_MB_2U_LIB.S9S_MB_2U(SCH_1):PVCCIN_CPU1
  CC52  PVCCIN_CPU1    VCCIN266  @S9S_MB_2U_LIB.S9S_MB_2U(SCH_1):PVCCIN_CPU1
  CC50  PVCCIN_CPU1    VCCIN265  @S9S_MB_2U_LIB.S9S_MB_2U(SCH_1):PVCCIN_CPU1
  CC48  PVCCIN_CPU1    VCCIN264  @S9S_MB_2U_LIB.S9S_MB_2U(SCH_1):PVCCIN_CPU1
  CC45  PVCCIN_CPU1    VCCIN263  @S9S_MB_2U_LIB.S9S_MB_2U(SCH_1):PVCCIN_CPU1
  CC43  PVCCIN_CPU1    VCCIN262  @S9S_MB_2U_LIB.S9S_MB_2U(SCH_1):PVCCIN_CPU1
  CC41  PVCCIN_CPU1    VCCIN261  @S9S_MB_2U_LIB.S9S_MB_2U(SCH_1):PVCCIN_CPU1
  CC39  PVCCIN_CPU1    VCCIN260  @S9S_MB_2U_LIB.S9S_MB_2U(SCH_1):PVCCIN_CPU1
  CC37  PVCCIN_CPU1    VCCIN259  @S9S_MB_2U_LIB.S9S_MB_2U(SCH_1):PVCCIN_CPU1
  CC35  PVCCIN_CPU1    VCCIN258  @S9S_MB_2U_LIB.S9S_MB_2U(SCH_1):PVCCIN_CPU1
  CC33  PVCCIN_CPU1    VCCIN257  @S9S_MB_2U_LIB.S9S_MB_2U(SCH_1):PVCCIN_CPU1
  CB77  PVCCIN_CPU1    VCCIN256  @S9S_MB_2U_LIB.S9S_MB_2U(SCH_1):PVCCIN_CPU1
  CB75  PVCCIN_CPU1    VCCIN255  @S9S_MB_2U_LIB.S9S_MB_2U(SCH_1):PVCCIN_CPU1
  CB61  PVCCIN_CPU1    VCCIN254  @S9S_MB_2U_LIB.S9S_MB_2U(SCH_1):PVCCIN_CPU1
  CA90  PVCCIN_CPU1    VCCIN253  @S9S_MB_2U_LIB.S9S_MB_2U(SCH_1):PVCCIN_CPU1
  CA88  PVCCIN_CPU1    VCCIN252  @S9S_MB_2U_LIB.S9S_MB_2U(SCH_1):PVCCIN_CPU1
  CA86  PVCCIN_CPU1    VCCIN251  @S9S_MB_2U_LIB.S9S_MB_2U(SCH_1):PVCCIN_CPU1
  CA84  PVCCIN_CPU1    VCCIN250  @S9S_MB_2U_LIB.S9S_MB_2U(SCH_1):PVCCIN_CPU1
  CA82  PVCCIN_CPU1    VCCIN249  @S9S_MB_2U_LIB.S9S_MB_2U(SCH_1):PVCCIN_CPU1
  CA80  PVCCIN_CPU1    VCCIN248  @S9S_MB_2U_LIB.S9S_MB_2U(SCH_1):PVCCIN_CPU1
  CA78  PVCCIN_CPU1    VCCIN247  @S9S_MB_2U_LIB.S9S_MB_2U(SCH_1):PVCCIN_CPU1
  CA76  PVCCIN_CPU1    VCCIN246  @S9S_MB_2U_LIB.S9S_MB_2U(SCH_1):PVCCIN_CPU1
  CA74  PVCCIN_CPU1    VCCIN245  @S9S_MB_2U_LIB.S9S_MB_2U(SCH_1):PVCCIN_CPU1
  CA72  PVCCIN_CPU1    VCCIN244  @S9S_MB_2U_LIB.S9S_MB_2U(SCH_1):PVCCIN_CPU1
  CA70  PVCCIN_CPU1    VCCIN243  @S9S_MB_2U_LIB.S9S_MB_2U(SCH_1):PVCCIN_CPU1
  CA68  PVCCIN_CPU1    VCCIN242  @S9S_MB_2U_LIB.S9S_MB_2U(SCH_1):PVCCIN_CPU1
  CA66  PVCCIN_CPU1    VCCIN241  @S9S_MB_2U_LIB.S9S_MB_2U(SCH_1):PVCCIN_CPU1
  CA64  PVCCIN_CPU1    VCCIN240  @S9S_MB_2U_LIB.S9S_MB_2U(SCH_1):PVCCIN_CPU1
  CA62  PVCCIN_CPU1    VCCIN239  @S9S_MB_2U_LIB.S9S_MB_2U(SCH_1):PVCCIN_CPU1
  CA60  PVCCIN_CPU1    VCCIN238  @S9S_MB_2U_LIB.S9S_MB_2U(SCH_1):PVCCIN_CPU1
  CA58  PVCCIN_CPU1    VCCIN237  @S9S_MB_2U_LIB.S9S_MB_2U(SCH_1):PVCCIN_CPU1
  CA56  PVCCIN_CPU1    VCCIN236  @S9S_MB_2U_LIB.S9S_MB_2U(SCH_1):PVCCIN_CPU1
  CA54  PVCCIN_CPU1    VCCIN235  @S9S_MB_2U_LIB.S9S_MB_2U(SCH_1):PVCCIN_CPU1
  CA52  PVCCIN_CPU1    VCCIN234  @S9S_MB_2U_LIB.S9S_MB_2U(SCH_1):PVCCIN_CPU1
  CA50  PVCCIN_CPU1    VCCIN233  @S9S_MB_2U_LIB.S9S_MB_2U(SCH_1):PVCCIN_CPU1
  CA48  PVCCIN_CPU1    VCCIN232  @S9S_MB_2U_LIB.S9S_MB_2U(SCH_1):PVCCIN_CPU1
  CA45  PVCCIN_CPU1    VCCIN231  @S9S_MB_2U_LIB.S9S_MB_2U(SCH_1):PVCCIN_CPU1
  CA43  PVCCIN_CPU1    VCCIN230  @S9S_MB_2U_LIB.S9S_MB_2U(SCH_1):PVCCIN_CPU1
  CA41  PVCCIN_CPU1    VCCIN229  @S9S_MB_2U_LIB.S9S_MB_2U(SCH_1):PVCCIN_CPU1
  CA39  PVCCIN_CPU1    VCCIN228  @S9S_MB_2U_LIB.S9S_MB_2U(SCH_1):PVCCIN_CPU1
  CA37  PVCCIN_CPU1    VCCIN227  @S9S_MB_2U_LIB.S9S_MB_2U(SCH_1):PVCCIN_CPU1
  CA35  PVCCIN_CPU1    VCCIN226  @S9S_MB_2U_LIB.S9S_MB_2U(SCH_1):PVCCIN_CPU1
  CA33  PVCCIN_CPU1    VCCIN225  @S9S_MB_2U_LIB.S9S_MB_2U(SCH_1):PVCCIN_CPU1
  BY89  PVCCIN_CPU1    VCCIN224  @S9S_MB_2U_LIB.S9S_MB_2U(SCH_1):PVCCIN_CPU1
  BY87  PVCCIN_CPU1    VCCIN223  @S9S_MB_2U_LIB.S9S_MB_2U(SCH_1):PVCCIN_CPU1
  BY85  PVCCIN_CPU1    VCCIN222  @S9S_MB_2U_LIB.S9S_MB_2U(SCH_1):PVCCIN_CPU1
  BY83  PVCCIN_CPU1    VCCIN221  @S9S_MB_2U_LIB.S9S_MB_2U(SCH_1):PVCCIN_CPU1
  BY81  PVCCIN_CPU1    VCCIN220  @S9S_MB_2U_LIB.S9S_MB_2U(SCH_1):PVCCIN_CPU1
  BY79  PVCCIN_CPU1    VCCIN219  @S9S_MB_2U_LIB.S9S_MB_2U(SCH_1):PVCCIN_CPU1
  BY77  PVCCIN_CPU1    VCCIN218  @S9S_MB_2U_LIB.S9S_MB_2U(SCH_1):PVCCIN_CPU1
  BY75  PVCCIN_CPU1    VCCIN217  @S9S_MB_2U_LIB.S9S_MB_2U(SCH_1):PVCCIN_CPU1
  BY73  PVCCIN_CPU1    VCCIN216  @S9S_MB_2U_LIB.S9S_MB_2U(SCH_1):PVCCIN_CPU1
  BY71  PVCCIN_CPU1    VCCIN215  @S9S_MB_2U_LIB.S9S_MB_2U(SCH_1):PVCCIN_CPU1
  BY69  PVCCIN_CPU1    VCCIN214  @S9S_MB_2U_LIB.S9S_MB_2U(SCH_1):PVCCIN_CPU1
  BY67  PVCCIN_CPU1    VCCIN213  @S9S_MB_2U_LIB.S9S_MB_2U(SCH_1):PVCCIN_CPU1
  BY65  PVCCIN_CPU1    VCCIN212  @S9S_MB_2U_LIB.S9S_MB_2U(SCH_1):PVCCIN_CPU1
  BY63  PVCCIN_CPU1    VCCIN211  @S9S_MB_2U_LIB.S9S_MB_2U(SCH_1):PVCCIN_CPU1
  BY61  PVCCIN_CPU1    VCCIN210  @S9S_MB_2U_LIB.S9S_MB_2U(SCH_1):PVCCIN_CPU1
  BY59  PVCCIN_CPU1    VCCIN209  @S9S_MB_2U_LIB.S9S_MB_2U(SCH_1):PVCCIN_CPU1
  BY57  PVCCIN_CPU1    VCCIN208  @S9S_MB_2U_LIB.S9S_MB_2U(SCH_1):PVCCIN_CPU1
  BY55  PVCCIN_CPU1    VCCIN207  @S9S_MB_2U_LIB.S9S_MB_2U(SCH_1):PVCCIN_CPU1
  BY53  PVCCIN_CPU1    VCCIN206  @S9S_MB_2U_LIB.S9S_MB_2U(SCH_1):PVCCIN_CPU1
  BY51  PVCCIN_CPU1    VCCIN205  @S9S_MB_2U_LIB.S9S_MB_2U(SCH_1):PVCCIN_CPU1
  BY49  PVCCIN_CPU1    VCCIN204  @S9S_MB_2U_LIB.S9S_MB_2U(SCH_1):PVCCIN_CPU1
  BY47  PVCCIN_CPU1    VCCIN203  @S9S_MB_2U_LIB.S9S_MB_2U(SCH_1):PVCCIN_CPU1
  BY44  PVCCIN_CPU1    VCCIN202  @S9S_MB_2U_LIB.S9S_MB_2U(SCH_1):PVCCIN_CPU1
  BY42  PVCCIN_CPU1    VCCIN201  @S9S_MB_2U_LIB.S9S_MB_2U(SCH_1):PVCCIN_CPU1
  BY40  PVCCIN_CPU1    VCCIN200  @S9S_MB_2U_LIB.S9S_MB_2U(SCH_1):PVCCIN_CPU1
  BY38  PVCCIN_CPU1    VCCIN199  @S9S_MB_2U_LIB.S9S_MB_2U(SCH_1):PVCCIN_CPU1
  BY36  PVCCIN_CPU1    VCCIN198  @S9S_MB_2U_LIB.S9S_MB_2U(SCH_1):PVCCIN_CPU1
  BY34  PVCCIN_CPU1    VCCIN197  @S9S_MB_2U_LIB.S9S_MB_2U(SCH_1):PVCCIN_CPU1
  BY32  PVCCIN_CPU1    VCCIN196  @S9S_MB_2U_LIB.S9S_MB_2U(SCH_1):PVCCIN_CPU1
  BW90  PVCCIN_CPU1    VCCIN195  @S9S_MB_2U_LIB.S9S_MB_2U(SCH_1):PVCCIN_CPU1
  BW88  PVCCIN_CPU1    VCCIN194  @S9S_MB_2U_LIB.S9S_MB_2U(SCH_1):PVCCIN_CPU1
  BW86  PVCCIN_CPU1    VCCIN193  @S9S_MB_2U_LIB.S9S_MB_2U(SCH_1):PVCCIN_CPU1
  BW84  PVCCIN_CPU1    VCCIN192  @S9S_MB_2U_LIB.S9S_MB_2U(SCH_1):PVCCIN_CPU1
  BW82  PVCCIN_CPU1    VCCIN191  @S9S_MB_2U_LIB.S9S_MB_2U(SCH_1):PVCCIN_CPU1
  BW80  PVCCIN_CPU1    VCCIN190  @S9S_MB_2U_LIB.S9S_MB_2U(SCH_1):PVCCIN_CPU1

SOCKET4677_AZIFS054P001C01  I16  U1     [SOCKET4677_AZIFS054P001C01-SOCA]
  DP83  UPI_CPU1_CPU0_P3P3_DP<9>  UPI3_TX_DP9  @S9S_MB_2U_LIB.S9S_MB_2U(SCH_1):UPI_CPU1_CPU0_P3P3_DP<9>
  DR80  UPI_CPU1_CPU0_P3P3_DP<8>  UPI3_TX_DP8  @S9S_MB_2U_LIB.S9S_MB_2U(SCH_1):UPI_CPU1_CPU0_P3P3_DP<8>
  DU82  UPI_CPU1_CPU0_P3P3_DP<7>  UPI3_TX_DP7  @S9S_MB_2U_LIB.S9S_MB_2U(SCH_1):UPI_CPU1_CPU0_P3P3_DP<7>
  DT81  UPI_CPU1_CPU0_P3P3_DP<6>  UPI3_TX_DP6  @S9S_MB_2U_LIB.S9S_MB_2U(SCH_1):UPI_CPU1_CPU0_P3P3_DP<6>
  EL88  UPI_CPU1_CPU0_P3P3_DP<5>  UPI3_TX_DP5  @S9S_MB_2U_LIB.S9S_MB_2U(SCH_1):UPI_CPU1_CPU0_P3P3_DP<5>
  EH87  UPI_CPU1_CPU0_P3P3_DP<4>  UPI3_TX_DP4  @S9S_MB_2U_LIB.S9S_MB_2U(SCH_1):UPI_CPU1_CPU0_P3P3_DP<4>
  EM87  UPI_CPU1_CPU0_P3P3_DP<3>  UPI3_TX_DN3  @S9S_MB_2U_LIB.S9S_MB_2U(SCH_1):UPI_CPU1_CPU0_P3P3_DP<3>
  EN86  UPI_CPU1_CPU0_P3P3_DP<2>  UPI3_TX_DP2  @S9S_MB_2U_LIB.S9S_MB_2U(SCH_1):UPI_CPU1_CPU0_P3P3_DP<2>
  CF73  UPI_CPU1_CPU0_P3P3_DP<23>  UPI3_TX_DN23  @S9S_MB_2U_LIB.S9S_MB_2U(SCH_1):UPI_CPU1_CPU0_P3P3_DP<23>
  CV73  UPI_CPU1_CPU0_P3P3_DP<22>  UPI3_TX_DN22  @S9S_MB_2U_LIB.S9S_MB_2U(SCH_1):UPI_CPU1_CPU0_P3P3_DP<22>
  CJ74  UPI_CPU1_CPU0_P3P3_DP<21>  UPI3_TX_DN21  @S9S_MB_2U_LIB.S9S_MB_2U(SCH_1):UPI_CPU1_CPU0_P3P3_DP<21>
  CH75  UPI_CPU1_CPU0_P3P3_DP<20>  UPI3_TX_DP20  @S9S_MB_2U_LIB.S9S_MB_2U(SCH_1):UPI_CPU1_CPU0_P3P3_DP<20>
  EM85  UPI_CPU1_CPU0_P3P3_DP<1>  UPI3_TX_DP1  @S9S_MB_2U_LIB.S9S_MB_2U(SCH_1):UPI_CPU1_CPU0_P3P3_DP<1>
  CF77  UPI_CPU1_CPU0_P3P3_DP<19>  UPI3_TX_DP19  @S9S_MB_2U_LIB.S9S_MB_2U(SCH_1):UPI_CPU1_CPU0_P3P3_DP<19>
  CM75  UPI_CPU1_CPU0_P3P3_DP<18>  UPI3_TX_DN18  @S9S_MB_2U_LIB.S9S_MB_2U(SCH_1):UPI_CPU1_CPU0_P3P3_DP<18>
  CJ78  UPI_CPU1_CPU0_P3P3_DP<17>  UPI3_TX_DP17  @S9S_MB_2U_LIB.S9S_MB_2U(SCH_1):UPI_CPU1_CPU0_P3P3_DP<17>
  CK77  UPI_CPU1_CPU0_P3P3_DP<16>  UPI3_TX_DN16  @S9S_MB_2U_LIB.S9S_MB_2U(SCH_1):UPI_CPU1_CPU0_P3P3_DP<16>
  CR74  UPI_CPU1_CPU0_P3P3_DP<15>  UPI3_TX_DN15  @S9S_MB_2U_LIB.S9S_MB_2U(SCH_1):UPI_CPU1_CPU0_P3P3_DP<15>
  CR76  UPI_CPU1_CPU0_P3P3_DP<14>  UPI3_TX_DP14  @S9S_MB_2U_LIB.S9S_MB_2U(SCH_1):UPI_CPU1_CPU0_P3P3_DP<14>
  CV77  UPI_CPU1_CPU0_P3P3_DP<13>  UPI3_TX_DP13  @S9S_MB_2U_LIB.S9S_MB_2U(SCH_1):UPI_CPU1_CPU0_P3P3_DP<13>
  DA76  UPI_CPU1_CPU0_P3P3_DP<12>  UPI3_TX_DP12  @S9S_MB_2U_LIB.S9S_MB_2U(SCH_1):UPI_CPU1_CPU0_P3P3_DP<12>
  DL80  UPI_CPU1_CPU0_P3P3_DP<11>  UPI3_TX_DN11  @S9S_MB_2U_LIB.S9S_MB_2U(SCH_1):UPI_CPU1_CPU0_P3P3_DP<11>
  DL82  UPI_CPU1_CPU0_P3P3_DP<10>  UPI3_TX_DP10  @S9S_MB_2U_LIB.S9S_MB_2U(SCH_1):UPI_CPU1_CPU0_P3P3_DP<10>
  EK85  UPI_CPU1_CPU0_P3P3_DP<0>  UPI3_TX_DP0  @S9S_MB_2U_LIB.S9S_MB_2U(SCH_1):UPI_CPU1_CPU0_P3P3_DP<0>
  DN82  UPI_CPU1_CPU0_P3P3_DN<9>  UPI3_TX_DN9  @S9S_MB_2U_LIB.S9S_MB_2U(SCH_1):UPI_CPU1_CPU0_P3P3_DN<9>
  DP79  UPI_CPU1_CPU0_P3P3_DN<8>  UPI3_TX_DN8  @S9S_MB_2U_LIB.S9S_MB_2U(SCH_1):UPI_CPU1_CPU0_P3P3_DN<8>
  DR82  UPI_CPU1_CPU0_P3P3_DN<7>  UPI3_TX_DN7  @S9S_MB_2U_LIB.S9S_MB_2U(SCH_1):UPI_CPU1_CPU0_P3P3_DN<7>
  DU80  UPI_CPU1_CPU0_P3P3_DN<6>  UPI3_TX_DN6  @S9S_MB_2U_LIB.S9S_MB_2U(SCH_1):UPI_CPU1_CPU0_P3P3_DN<6>
  EK87  UPI_CPU1_CPU0_P3P3_DN<5>  UPI3_TX_DN5  @S9S_MB_2U_LIB.S9S_MB_2U(SCH_1):UPI_CPU1_CPU0_P3P3_DN<5>
  EJ86  UPI_CPU1_CPU0_P3P3_DN<4>  UPI3_TX_DN4  @S9S_MB_2U_LIB.S9S_MB_2U(SCH_1):UPI_CPU1_CPU0_P3P3_DN<4>
  EP87  UPI_CPU1_CPU0_P3P3_DN<3>  UPI3_TX_DP3  @S9S_MB_2U_LIB.S9S_MB_2U(SCH_1):UPI_CPU1_CPU0_P3P3_DN<3>
  EP85  UPI_CPU1_CPU0_P3P3_DN<2>  UPI3_TX_DN2  @S9S_MB_2U_LIB.S9S_MB_2U(SCH_1):UPI_CPU1_CPU0_P3P3_DN<2>
  CD73  UPI_CPU1_CPU0_P3P3_DN<23>  UPI3_TX_DP23  @S9S_MB_2U_LIB.S9S_MB_2U(SCH_1):UPI_CPU1_CPU0_P3P3_DN<23>
  CW74  UPI_CPU1_CPU0_P3P3_DN<22>  UPI3_TX_DP22  @S9S_MB_2U_LIB.S9S_MB_2U(SCH_1):UPI_CPU1_CPU0_P3P3_DN<22>
  CK75  UPI_CPU1_CPU0_P3P3_DN<21>  UPI3_TX_DP21  @S9S_MB_2U_LIB.S9S_MB_2U(SCH_1):UPI_CPU1_CPU0_P3P3_DN<21>
  CF75  UPI_CPU1_CPU0_P3P3_DN<20>  UPI3_TX_DN20  @S9S_MB_2U_LIB.S9S_MB_2U(SCH_1):UPI_CPU1_CPU0_P3P3_DN<20>
  EL84  UPI_CPU1_CPU0_P3P3_DN<1>  UPI3_TX_DN1  @S9S_MB_2U_LIB.S9S_MB_2U(SCH_1):UPI_CPU1_CPU0_P3P3_DN<1>
  CG76  UPI_CPU1_CPU0_P3P3_DN<19>  UPI3_TX_DN19  @S9S_MB_2U_LIB.S9S_MB_2U(SCH_1):UPI_CPU1_CPU0_P3P3_DN<19>
  CL76  UPI_CPU1_CPU0_P3P3_DN<18>  UPI3_TX_DP18  @S9S_MB_2U_LIB.S9S_MB_2U(SCH_1):UPI_CPU1_CPU0_P3P3_DN<18>
  CH77  UPI_CPU1_CPU0_P3P3_DN<17>  UPI3_TX_DN17  @S9S_MB_2U_LIB.S9S_MB_2U(SCH_1):UPI_CPU1_CPU0_P3P3_DN<17>
  CM77  UPI_CPU1_CPU0_P3P3_DN<16>  UPI3_TX_DP16  @S9S_MB_2U_LIB.S9S_MB_2U(SCH_1):UPI_CPU1_CPU0_P3P3_DN<16>
  CU74  UPI_CPU1_CPU0_P3P3_DN<15>  UPI3_TX_DP15  @S9S_MB_2U_LIB.S9S_MB_2U(SCH_1):UPI_CPU1_CPU0_P3P3_DN<15>
  CT75  UPI_CPU1_CPU0_P3P3_DN<14>  UPI3_TX_DN14  @S9S_MB_2U_LIB.S9S_MB_2U(SCH_1):UPI_CPU1_CPU0_P3P3_DN<14>
  CU76  UPI_CPU1_CPU0_P3P3_DN<13>  UPI3_TX_DN13  @S9S_MB_2U_LIB.S9S_MB_2U(SCH_1):UPI_CPU1_CPU0_P3P3_DN<13>
  CW76  UPI_CPU1_CPU0_P3P3_DN<12>  UPI3_TX_DN12  @S9S_MB_2U_LIB.S9S_MB_2U(SCH_1):UPI_CPU1_CPU0_P3P3_DN<12>
  DN80  UPI_CPU1_CPU0_P3P3_DN<11>  UPI3_TX_DP11  @S9S_MB_2U_LIB.S9S_MB_2U(SCH_1):UPI_CPU1_CPU0_P3P3_DN<11>
  DM81  UPI_CPU1_CPU0_P3P3_DN<10>  UPI3_TX_DN10  @S9S_MB_2U_LIB.S9S_MB_2U(SCH_1):UPI_CPU1_CPU0_P3P3_DN<10>
  EH85  UPI_CPU1_CPU0_P3P3_DN<0>  UPI3_TX_DN0  @S9S_MB_2U_LIB.S9S_MB_2U(SCH_1):UPI_CPU1_CPU0_P3P3_DN<0>
  DL78  UPI_CPU0_CPU1_P3P3_DP<9>  UPI3_RX_DP9  @S9S_MB_2U_LIB.S9S_MB_2U(SCH_1):UPI_CPU0_CPU1_P3P3_DP<9>
  EB81  UPI_CPU0_CPU1_P3P3_DP<8>  UPI3_RX_DP8  @S9S_MB_2U_LIB.S9S_MB_2U(SCH_1):UPI_CPU0_CPU1_P3P3_DP<8>
  DY83  UPI_CPU0_CPU1_P3P3_DP<7>  UPI3_RX_DP7  @S9S_MB_2U_LIB.S9S_MB_2U(SCH_1):UPI_CPU0_CPU1_P3P3_DP<7>
  ED81  UPI_CPU0_CPU1_P3P3_DP<6>  UPI3_RX_DP6  @S9S_MB_2U_LIB.S9S_MB_2U(SCH_1):UPI_CPU0_CPU1_P3P3_DP<6>
  EF83  UPI_CPU0_CPU1_P3P3_DP<5>  UPI3_RX_DP5  @S9S_MB_2U_LIB.S9S_MB_2U(SCH_1):UPI_CPU0_CPU1_P3P3_DP<5>
  EE82  UPI_CPU0_CPU1_P3P3_DP<4>  UPI3_RX_DP4  @S9S_MB_2U_LIB.S9S_MB_2U(SCH_1):UPI_CPU0_CPU1_P3P3_DP<4>
  EJ82  UPI_CPU0_CPU1_P3P3_DP<3>  UPI3_RX_DP3  @S9S_MB_2U_LIB.S9S_MB_2U(SCH_1):UPI_CPU0_CPU1_P3P3_DP<3>
  EN82  UPI_CPU0_CPU1_P3P3_DP<2>  UPI3_RX_DP2  @S9S_MB_2U_LIB.S9S_MB_2U(SCH_1):UPI_CPU0_CPU1_P3P3_DP<2>
  DB79  UPI_CPU0_CPU1_P3P3_DP<23>  UPI3_RX_DP23  @S9S_MB_2U_LIB.S9S_MB_2U(SCH_1):UPI_CPU0_CPU1_P3P3_DP<23>
  CU80  UPI_CPU0_CPU1_P3P3_DP<22>  UPI3_RX_DP22  @S9S_MB_2U_LIB.S9S_MB_2U(SCH_1):UPI_CPU0_CPU1_P3P3_DP<22>
  CR80  UPI_CPU0_CPU1_P3P3_DP<21>  UPI3_RX_DP21  @S9S_MB_2U_LIB.S9S_MB_2U(SCH_1):UPI_CPU0_CPU1_P3P3_DP<21>
  CN82  UPI_CPU0_CPU1_P3P3_DP<20>  UPI3_RX_DP20  @S9S_MB_2U_LIB.S9S_MB_2U(SCH_1):UPI_CPU0_CPU1_P3P3_DP<20>
  ER82  UPI_CPU0_CPU1_P3P3_DP<1>  UPI3_RX_DP1  @S9S_MB_2U_LIB.S9S_MB_2U(SCH_1):UPI_CPU0_CPU1_P3P3_DP<1>
  CV81  UPI_CPU0_CPU1_P3P3_DP<19>  UPI3_RX_DP19  @S9S_MB_2U_LIB.S9S_MB_2U(SCH_1):UPI_CPU0_CPU1_P3P3_DP<19>
  CT83  UPI_CPU0_CPU1_P3P3_DP<18>  UPI3_RX_DP18  @S9S_MB_2U_LIB.S9S_MB_2U(SCH_1):UPI_CPU0_CPU1_P3P3_DP<18>
  CW82  UPI_CPU0_CPU1_P3P3_DP<17>  UPI3_RX_DP17  @S9S_MB_2U_LIB.S9S_MB_2U(SCH_1):UPI_CPU0_CPU1_P3P3_DP<17>
  DE78  UPI_CPU0_CPU1_P3P3_DP<16>  UPI3_RX_DP16  @S9S_MB_2U_LIB.S9S_MB_2U(SCH_1):UPI_CPU0_CPU1_P3P3_DP<16>
  DD81  UPI_CPU0_CPU1_P3P3_DP<15>  UPI3_RX_DP15  @S9S_MB_2U_LIB.S9S_MB_2U(SCH_1):UPI_CPU0_CPU1_P3P3_DP<15>
  DB83  UPI_CPU0_CPU1_P3P3_DP<14>  UPI3_RX_DP14  @S9S_MB_2U_LIB.S9S_MB_2U(SCH_1):UPI_CPU0_CPU1_P3P3_DP<14>
  DF81  UPI_CPU0_CPU1_P3P3_DP<13>  UPI3_RX_DP13  @S9S_MB_2U_LIB.S9S_MB_2U(SCH_1):UPI_CPU0_CPU1_P3P3_DP<13>
  DH83  UPI_CPU0_CPU1_P3P3_DP<12>  UPI3_RX_DP12  @S9S_MB_2U_LIB.S9S_MB_2U(SCH_1):UPI_CPU0_CPU1_P3P3_DP<12>
  DG82  UPI_CPU0_CPU1_P3P3_DP<11>  UPI3_RX_DP11  @S9S_MB_2U_LIB.S9S_MB_2U(SCH_1):UPI_CPU0_CPU1_P3P3_DP<11>
  DH79  UPI_CPU0_CPU1_P3P3_DP<10>  UPI3_RX_DP10  @S9S_MB_2U_LIB.S9S_MB_2U(SCH_1):UPI_CPU0_CPU1_P3P3_DP<10>
  EL80  UPI_CPU0_CPU1_P3P3_DP<0>  UPI3_RX_DP0  @S9S_MB_2U_LIB.S9S_MB_2U(SCH_1):UPI_CPU0_CPU1_P3P3_DP<0>
  DJ78  UPI_CPU0_CPU1_P3P3_DN<9>  UPI3_RX_DN9  @S9S_MB_2U_LIB.S9S_MB_2U(SCH_1):UPI_CPU0_CPU1_P3P3_DN<9>
  DY81  UPI_CPU0_CPU1_P3P3_DN<8>  UPI3_RX_DN8  @S9S_MB_2U_LIB.S9S_MB_2U(SCH_1):UPI_CPU0_CPU1_P3P3_DN<8>
  EA82  UPI_CPU0_CPU1_P3P3_DN<7>  UPI3_RX_DN7  @S9S_MB_2U_LIB.S9S_MB_2U(SCH_1):UPI_CPU0_CPU1_P3P3_DN<7>
  EC80  UPI_CPU0_CPU1_P3P3_DN<6>  UPI3_RX_DN6  @S9S_MB_2U_LIB.S9S_MB_2U(SCH_1):UPI_CPU0_CPU1_P3P3_DN<6>
  ED83  UPI_CPU0_CPU1_P3P3_DN<5>  UPI3_RX_DN5  @S9S_MB_2U_LIB.S9S_MB_2U(SCH_1):UPI_CPU0_CPU1_P3P3_DN<5>
  EF81  UPI_CPU0_CPU1_P3P3_DN<4>  UPI3_RX_DN4  @S9S_MB_2U_LIB.S9S_MB_2U(SCH_1):UPI_CPU0_CPU1_P3P3_DN<4>
  EK81  UPI_CPU0_CPU1_P3P3_DN<3>  UPI3_RX_DN3  @S9S_MB_2U_LIB.S9S_MB_2U(SCH_1):UPI_CPU0_CPU1_P3P3_DN<3>
  EL82  UPI_CPU0_CPU1_P3P3_DN<2>  UPI3_RX_DN2  @S9S_MB_2U_LIB.S9S_MB_2U(SCH_1):UPI_CPU0_CPU1_P3P3_DN<2>
  DA78  UPI_CPU0_CPU1_P3P3_DN<23>  UPI3_RX_DN23  @S9S_MB_2U_LIB.S9S_MB_2U(SCH_1):UPI_CPU0_CPU1_P3P3_DN<23>
  CT79  UPI_CPU0_CPU1_P3P3_DN<22>  UPI3_RX_DN22  @S9S_MB_2U_LIB.S9S_MB_2U(SCH_1):UPI_CPU0_CPU1_P3P3_DN<22>
  CN80  UPI_CPU0_CPU1_P3P3_DN<21>  UPI3_RX_DN21  @S9S_MB_2U_LIB.S9S_MB_2U(SCH_1):UPI_CPU0_CPU1_P3P3_DN<21>
  CP81  UPI_CPU0_CPU1_P3P3_DN<20>  UPI3_RX_DN20  @S9S_MB_2U_LIB.S9S_MB_2U(SCH_1):UPI_CPU0_CPU1_P3P3_DN<20>
  EP81  UPI_CPU0_CPU1_P3P3_DN<1>  UPI3_RX_DN1  @S9S_MB_2U_LIB.S9S_MB_2U(SCH_1):UPI_CPU0_CPU1_P3P3_DN<1>
  CW80  UPI_CPU0_CPU1_P3P3_DN<19>  UPI3_RX_DN19  @S9S_MB_2U_LIB.S9S_MB_2U(SCH_1):UPI_CPU0_CPU1_P3P3_DN<19>
  CR82  UPI_CPU0_CPU1_P3P3_DN<18>  UPI3_RX_DN18  @S9S_MB_2U_LIB.S9S_MB_2U(SCH_1):UPI_CPU0_CPU1_P3P3_DN<18>
  CU82  UPI_CPU0_CPU1_P3P3_DN<17>  UPI3_RX_DN17  @S9S_MB_2U_LIB.S9S_MB_2U(SCH_1):UPI_CPU0_CPU1_P3P3_DN<17>
  DF77  UPI_CPU0_CPU1_P3P3_DN<16>  UPI3_RX_DN16  @S9S_MB_2U_LIB.S9S_MB_2U(SCH_1):UPI_CPU0_CPU1_P3P3_DN<16>
  DB81  UPI_CPU0_CPU1_P3P3_DN<15>  UPI3_RX_DN15  @S9S_MB_2U_LIB.S9S_MB_2U(SCH_1):UPI_CPU0_CPU1_P3P3_DN<15>
  DC82  UPI_CPU0_CPU1_P3P3_DN<14>  UPI3_RX_DN14  @S9S_MB_2U_LIB.S9S_MB_2U(SCH_1):UPI_CPU0_CPU1_P3P3_DN<14>
  DE80  UPI_CPU0_CPU1_P3P3_DN<13>  UPI3_RX_DN13  @S9S_MB_2U_LIB.S9S_MB_2U(SCH_1):UPI_CPU0_CPU1_P3P3_DN<13>
  DF83  UPI_CPU0_CPU1_P3P3_DN<12>  UPI3_RX_DN12  @S9S_MB_2U_LIB.S9S_MB_2U(SCH_1):UPI_CPU0_CPU1_P3P3_DN<12>
  DH81  UPI_CPU0_CPU1_P3P3_DN<11>  UPI3_RX_DN11  @S9S_MB_2U_LIB.S9S_MB_2U(SCH_1):UPI_CPU0_CPU1_P3P3_DN<11>
  DG78  UPI_CPU0_CPU1_P3P3_DN<10>  UPI3_RX_DN10  @S9S_MB_2U_LIB.S9S_MB_2U(SCH_1):UPI_CPU0_CPU1_P3P3_DN<10>
  EJ80  UPI_CPU0_CPU1_P3P3_DN<0>  UPI3_RX_DN0  @S9S_MB_2U_LIB.S9S_MB_2U(SCH_1):UPI_CPU0_CPU1_P3P3_DN<0>

SOCKET4677_AZIFS054P001C01  I16  U1     [SOCKET4677_AZIFS054P001C01-SOCA]
  W82  UPI_CPU1_CPU0_P2P2_DP<9>  UPI2_TX_DP9  @S9S_MB_2U_LIB.S9S_MB_2U(SCH_1):UPI_CPU1_CPU0_P2P2_DP<9>
  Y83  UPI_CPU1_CPU0_P2P2_DP<8>  UPI2_TX_DP8  @S9S_MB_2U_LIB.S9S_MB_2U(SCH_1):UPI_CPU1_CPU0_P2P2_DP<8>
  V81  UPI_CPU1_CPU0_P2P2_DP<7>  UPI2_TX_DP7  @S9S_MB_2U_LIB.S9S_MB_2U(SCH_1):UPI_CPU1_CPU0_P2P2_DP<7>
  P83  UPI_CPU1_CPU0_P2P2_DP<6>  UPI2_TX_DP6  @S9S_MB_2U_LIB.S9S_MB_2U(SCH_1):UPI_CPU1_CPU0_P2P2_DP<6>
  T81  UPI_CPU1_CPU0_P2P2_DP<5>  UPI2_TX_DP5  @S9S_MB_2U_LIB.S9S_MB_2U(SCH_1):UPI_CPU1_CPU0_P2P2_DP<5>
  G86  UPI_CPU1_CPU0_P2P2_DP<4>  UPI2_TX_DP4  @S9S_MB_2U_LIB.S9S_MB_2U(SCH_1):UPI_CPU1_CPU0_P2P2_DP<4>
  H87  UPI_CPU1_CPU0_P2P2_DP<3>  UPI2_TX_DP3  @S9S_MB_2U_LIB.S9S_MB_2U(SCH_1):UPI_CPU1_CPU0_P2P2_DP<3>
  E88  UPI_CPU1_CPU0_P2P2_DP<2>  UPI2_TX_DP2  @S9S_MB_2U_LIB.S9S_MB_2U(SCH_1):UPI_CPU1_CPU0_P2P2_DP<2>
  BN72  UPI_CPU1_CPU0_P2P2_DP<23>  UPI2_TX_DP23  @S9S_MB_2U_LIB.S9S_MB_2U(SCH_1):UPI_CPU1_CPU0_P2P2_DP<23>
  BE80  UPI_CPU1_CPU0_P2P2_DP<22>  UPI2_TX_DP22  @S9S_MB_2U_LIB.S9S_MB_2U(SCH_1):UPI_CPU1_CPU0_P2P2_DP<22>
  BG82  UPI_CPU1_CPU0_P2P2_DP<21>  UPI2_TX_DP21  @S9S_MB_2U_LIB.S9S_MB_2U(SCH_1):UPI_CPU1_CPU0_P2P2_DP<21>
  BC80  UPI_CPU1_CPU0_P2P2_DP<20>  UPI2_TX_DP20  @S9S_MB_2U_LIB.S9S_MB_2U(SCH_1):UPI_CPU1_CPU0_P2P2_DP<20>
  F85  UPI_CPU1_CPU0_P2P2_DP<1>  UPI2_TX_DP1  @S9S_MB_2U_LIB.S9S_MB_2U(SCH_1):UPI_CPU1_CPU0_P2P2_DP<1>
  BD83  UPI_CPU1_CPU0_P2P2_DP<19>  UPI2_TX_DP19  @S9S_MB_2U_LIB.S9S_MB_2U(SCH_1):UPI_CPU1_CPU0_P2P2_DP<19>
  BA82  UPI_CPU1_CPU0_P2P2_DP<18>  UPI2_TX_DP18  @S9S_MB_2U_LIB.S9S_MB_2U(SCH_1):UPI_CPU1_CPU0_P2P2_DP<18>
  BB81  UPI_CPU1_CPU0_P2P2_DP<17>  UPI2_TX_DP17  @S9S_MB_2U_LIB.S9S_MB_2U(SCH_1):UPI_CPU1_CPU0_P2P2_DP<17>
  AU82  UPI_CPU1_CPU0_P2P2_DP<16>  UPI2_TX_DP16  @S9S_MB_2U_LIB.S9S_MB_2U(SCH_1):UPI_CPU1_CPU0_P2P2_DP<16>
  AV83  UPI_CPU1_CPU0_P2P2_DP<15>  UPI2_TX_DP15  @S9S_MB_2U_LIB.S9S_MB_2U(SCH_1):UPI_CPU1_CPU0_P2P2_DP<15>
  AT81  UPI_CPU1_CPU0_P2P2_DP<14>  UPI2_TX_DP14  @S9S_MB_2U_LIB.S9S_MB_2U(SCH_1):UPI_CPU1_CPU0_P2P2_DP<14>
  AM83  UPI_CPU1_CPU0_P2P2_DP<13>  UPI2_TX_DP13  @S9S_MB_2U_LIB.S9S_MB_2U(SCH_1):UPI_CPU1_CPU0_P2P2_DP<13>
  AP81  UPI_CPU1_CPU0_P2P2_DP<12>  UPI2_TX_DP12  @S9S_MB_2U_LIB.S9S_MB_2U(SCH_1):UPI_CPU1_CPU0_P2P2_DP<12>
  AV79  UPI_CPU1_CPU0_P2P2_DP<11>  UPI2_TX_DP11  @S9S_MB_2U_LIB.S9S_MB_2U(SCH_1):UPI_CPU1_CPU0_P2P2_DP<11>
  BA78  UPI_CPU1_CPU0_P2P2_DP<10>  UPI2_TX_DP10  @S9S_MB_2U_LIB.S9S_MB_2U(SCH_1):UPI_CPU1_CPU0_P2P2_DP<10>
  D85  UPI_CPU1_CPU0_P2P2_DP<0>  UPI2_TX_DP0  @S9S_MB_2U_LIB.S9S_MB_2U(SCH_1):UPI_CPU1_CPU0_P2P2_DP<0>
  Y81  UPI_CPU1_CPU0_P2P2_DN<9>  UPI2_TX_DN9  @S9S_MB_2U_LIB.S9S_MB_2U(SCH_1):UPI_CPU1_CPU0_P2P2_DN<9>
  V83  UPI_CPU1_CPU0_P2P2_DN<8>  UPI2_TX_DN8  @S9S_MB_2U_LIB.S9S_MB_2U(SCH_1):UPI_CPU1_CPU0_P2P2_DN<8>
  U80  UPI_CPU1_CPU0_P2P2_DN<7>  UPI2_TX_DN7  @S9S_MB_2U_LIB.S9S_MB_2U(SCH_1):UPI_CPU1_CPU0_P2P2_DN<7>
  R82  UPI_CPU1_CPU0_P2P2_DN<6>  UPI2_TX_DN6  @S9S_MB_2U_LIB.S9S_MB_2U(SCH_1):UPI_CPU1_CPU0_P2P2_DN<6>
  P81  UPI_CPU1_CPU0_P2P2_DN<5>  UPI2_TX_DN5  @S9S_MB_2U_LIB.S9S_MB_2U(SCH_1):UPI_CPU1_CPU0_P2P2_DN<5>
  H85  UPI_CPU1_CPU0_P2P2_DN<4>  UPI2_TX_DN4  @S9S_MB_2U_LIB.S9S_MB_2U(SCH_1):UPI_CPU1_CPU0_P2P2_DN<4>
  F87  UPI_CPU1_CPU0_P2P2_DN<3>  UPI2_TX_DN3  @S9S_MB_2U_LIB.S9S_MB_2U(SCH_1):UPI_CPU1_CPU0_P2P2_DN<3>
  D87  UPI_CPU1_CPU0_P2P2_DN<2>  UPI2_TX_DN2  @S9S_MB_2U_LIB.S9S_MB_2U(SCH_1):UPI_CPU1_CPU0_P2P2_DN<2>
  BM71  UPI_CPU1_CPU0_P2P2_DN<23>  UPI2_TX_DN23  @S9S_MB_2U_LIB.S9S_MB_2U(SCH_1):UPI_CPU1_CPU0_P2P2_DN<23>
  BG80  UPI_CPU1_CPU0_P2P2_DN<22>  UPI2_TX_DN22  @S9S_MB_2U_LIB.S9S_MB_2U(SCH_1):UPI_CPU1_CPU0_P2P2_DN<22>
  BF81  UPI_CPU1_CPU0_P2P2_DN<21>  UPI2_TX_DN21  @S9S_MB_2U_LIB.S9S_MB_2U(SCH_1):UPI_CPU1_CPU0_P2P2_DN<21>
  BD79  UPI_CPU1_CPU0_P2P2_DN<20>  UPI2_TX_DN20  @S9S_MB_2U_LIB.S9S_MB_2U(SCH_1):UPI_CPU1_CPU0_P2P2_DN<20>
  E84  UPI_CPU1_CPU0_P2P2_DN<1>  UPI2_TX_DN1  @S9S_MB_2U_LIB.S9S_MB_2U(SCH_1):UPI_CPU1_CPU0_P2P2_DN<1>
  BE82  UPI_CPU1_CPU0_P2P2_DN<19>  UPI2_TX_DN19  @S9S_MB_2U_LIB.S9S_MB_2U(SCH_1):UPI_CPU1_CPU0_P2P2_DN<19>
  BC82  UPI_CPU1_CPU0_P2P2_DN<18>  UPI2_TX_DN18  @S9S_MB_2U_LIB.S9S_MB_2U(SCH_1):UPI_CPU1_CPU0_P2P2_DN<18>
  BA80  UPI_CPU1_CPU0_P2P2_DN<17>  UPI2_TX_DN17  @S9S_MB_2U_LIB.S9S_MB_2U(SCH_1):UPI_CPU1_CPU0_P2P2_DN<17>
  AV81  UPI_CPU1_CPU0_P2P2_DN<16>  UPI2_TX_DN16  @S9S_MB_2U_LIB.S9S_MB_2U(SCH_1):UPI_CPU1_CPU0_P2P2_DN<16>
  AT83  UPI_CPU1_CPU0_P2P2_DN<15>  UPI2_TX_DN15  @S9S_MB_2U_LIB.S9S_MB_2U(SCH_1):UPI_CPU1_CPU0_P2P2_DN<15>
  AR80  UPI_CPU1_CPU0_P2P2_DN<14>  UPI2_TX_DN14  @S9S_MB_2U_LIB.S9S_MB_2U(SCH_1):UPI_CPU1_CPU0_P2P2_DN<14>
  AN82  UPI_CPU1_CPU0_P2P2_DN<13>  UPI2_TX_DN13  @S9S_MB_2U_LIB.S9S_MB_2U(SCH_1):UPI_CPU1_CPU0_P2P2_DN<13>
  AM81  UPI_CPU1_CPU0_P2P2_DN<12>  UPI2_TX_DN12  @S9S_MB_2U_LIB.S9S_MB_2U(SCH_1):UPI_CPU1_CPU0_P2P2_DN<12>
  AU78  UPI_CPU1_CPU0_P2P2_DN<11>  UPI2_TX_DN11  @S9S_MB_2U_LIB.S9S_MB_2U(SCH_1):UPI_CPU1_CPU0_P2P2_DN<11>
  AW78  UPI_CPU1_CPU0_P2P2_DN<10>  UPI2_TX_DN10  @S9S_MB_2U_LIB.S9S_MB_2U(SCH_1):UPI_CPU1_CPU0_P2P2_DN<10>
  B85  UPI_CPU1_CPU0_P2P2_DN<0>  UPI2_TX_DN0  @S9S_MB_2U_LIB.S9S_MB_2U(SCH_1):UPI_CPU1_CPU0_P2P2_DN<0>
  AF83  UPI_CPU0_CPU1_P2P2_DP<9>  UPI2_RX_DP9  @S9S_MB_2U_LIB.S9S_MB_2U(SCH_1):UPI_CPU0_CPU1_P2P2_DP<9>
  AG80  UPI_CPU0_CPU1_P2P2_DP<8>  UPI2_RX_DP8  @S9S_MB_2U_LIB.S9S_MB_2U(SCH_1):UPI_CPU0_CPU1_P2P2_DP<8>
  AC82  UPI_CPU0_CPU1_P2P2_DP<7>  UPI2_RX_DP7  @S9S_MB_2U_LIB.S9S_MB_2U(SCH_1):UPI_CPU0_CPU1_P2P2_DP<7>
  AE80  UPI_CPU0_CPU1_P2P2_DP<6>  UPI2_RX_DP6  @S9S_MB_2U_LIB.S9S_MB_2U(SCH_1):UPI_CPU0_CPU1_P2P2_DP<6>
  K81  UPI_CPU0_CPU1_P2P2_DP<5>  UPI2_RX_DP5  @S9S_MB_2U_LIB.S9S_MB_2U(SCH_1):UPI_CPU0_CPU1_P2P2_DP<5>
  L82  UPI_CPU0_CPU1_P2P2_DP<4>  UPI2_RX_DP4  @S9S_MB_2U_LIB.S9S_MB_2U(SCH_1):UPI_CPU0_CPU1_P2P2_DP<4>
  M79  UPI_CPU0_CPU1_P2P2_DP<3>  UPI2_RX_DP3  @S9S_MB_2U_LIB.S9S_MB_2U(SCH_1):UPI_CPU0_CPU1_P2P2_DP<3>
  H83  UPI_CPU0_CPU1_P2P2_DP<2>  UPI2_RX_DP2  @S9S_MB_2U_LIB.S9S_MB_2U(SCH_1):UPI_CPU0_CPU1_P2P2_DP<2>
  BC74  UPI_CPU0_CPU1_P2P2_DP<23>  UPI2_RX_DP23  @S9S_MB_2U_LIB.S9S_MB_2U(SCH_1):UPI_CPU0_CPU1_P2P2_DP<23>
  BL74  UPI_CPU0_CPU1_P2P2_DP<22>  UPI2_RX_DP22  @S9S_MB_2U_LIB.S9S_MB_2U(SCH_1):UPI_CPU0_CPU1_P2P2_DP<22>
  BM75  UPI_CPU0_CPU1_P2P2_DP<21>  UPI2_RX_DP21  @S9S_MB_2U_LIB.S9S_MB_2U(SCH_1):UPI_CPU0_CPU1_P2P2_DP<21>
  BJ74  UPI_CPU0_CPU1_P2P2_DP<20>  UPI2_RX_DP20  @S9S_MB_2U_LIB.S9S_MB_2U(SCH_1):UPI_CPU0_CPU1_P2P2_DP<20>
  E82  UPI_CPU0_CPU1_P2P2_DP<1>  UPI2_RX_DP1  @S9S_MB_2U_LIB.S9S_MB_2U(SCH_1):UPI_CPU0_CPU1_P2P2_DP<1>
  BN76  UPI_CPU0_CPU1_P2P2_DP<19>  UPI2_RX_DP19  @S9S_MB_2U_LIB.S9S_MB_2U(SCH_1):UPI_CPU0_CPU1_P2P2_DP<19>
  BK77  UPI_CPU0_CPU1_P2P2_DP<18>  UPI2_RX_DP18  @S9S_MB_2U_LIB.S9S_MB_2U(SCH_1):UPI_CPU0_CPU1_P2P2_DP<18>
  BG76  UPI_CPU0_CPU1_P2P2_DP<17>  UPI2_RX_DP17  @S9S_MB_2U_LIB.S9S_MB_2U(SCH_1):UPI_CPU0_CPU1_P2P2_DP<17>
  AV75  UPI_CPU0_CPU1_P2P2_DP<16>  UPI2_RX_DP16  @S9S_MB_2U_LIB.S9S_MB_2U(SCH_1):UPI_CPU0_CPU1_P2P2_DP<16>
  BD75  UPI_CPU0_CPU1_P2P2_DP<15>  UPI2_RX_DP15  @S9S_MB_2U_LIB.S9S_MB_2U(SCH_1):UPI_CPU0_CPU1_P2P2_DP<15>
  BA76  UPI_CPU0_CPU1_P2P2_DP<14>  UPI2_RX_DP14  @S9S_MB_2U_LIB.S9S_MB_2U(SCH_1):UPI_CPU0_CPU1_P2P2_DP<14>
  AY73  UPI_CPU0_CPU1_P2P2_DP<13>  UPI2_RX_DP13  @S9S_MB_2U_LIB.S9S_MB_2U(SCH_1):UPI_CPU0_CPU1_P2P2_DP<13>
  BB73  UPI_CPU0_CPU1_P2P2_DP<12>  UPI2_RX_DP12  @S9S_MB_2U_LIB.S9S_MB_2U(SCH_1):UPI_CPU0_CPU1_P2P2_DP<12>
  AJ82  UPI_CPU0_CPU1_P2P2_DP<11>  UPI2_RX_DP11  @S9S_MB_2U_LIB.S9S_MB_2U(SCH_1):UPI_CPU0_CPU1_P2P2_DP<11>
  AH81  UPI_CPU0_CPU1_P2P2_DP<10>  UPI2_RX_DP10  @S9S_MB_2U_LIB.S9S_MB_2U(SCH_1):UPI_CPU0_CPU1_P2P2_DP<10>
  G80  UPI_CPU0_CPU1_P2P2_DP<0>  UPI2_RX_DP0  @S9S_MB_2U_LIB.S9S_MB_2U(SCH_1):UPI_CPU0_CPU1_P2P2_DP<0>
  AE82  UPI_CPU0_CPU1_P2P2_DN<9>  UPI2_RX_DN9  @S9S_MB_2U_LIB.S9S_MB_2U(SCH_1):UPI_CPU0_CPU1_P2P2_DN<9>
  AF79  UPI_CPU0_CPU1_P2P2_DN<8>  UPI2_RX_DN8  @S9S_MB_2U_LIB.S9S_MB_2U(SCH_1):UPI_CPU0_CPU1_P2P2_DN<8>
  AD81  UPI_CPU0_CPU1_P2P2_DN<7>  UPI2_RX_DN7  @S9S_MB_2U_LIB.S9S_MB_2U(SCH_1):UPI_CPU0_CPU1_P2P2_DN<7>
  AC80  UPI_CPU0_CPU1_P2P2_DN<6>  UPI2_RX_DN6  @S9S_MB_2U_LIB.S9S_MB_2U(SCH_1):UPI_CPU0_CPU1_P2P2_DN<6>
  L80  UPI_CPU0_CPU1_P2P2_DN<5>  UPI2_RX_DN5  @S9S_MB_2U_LIB.S9S_MB_2U(SCH_1):UPI_CPU0_CPU1_P2P2_DN<5>
  J82  UPI_CPU0_CPU1_P2P2_DN<4>  UPI2_RX_DN4  @S9S_MB_2U_LIB.S9S_MB_2U(SCH_1):UPI_CPU0_CPU1_P2P2_DN<4>
  K79  UPI_CPU0_CPU1_P2P2_DN<3>  UPI2_RX_DN3  @S9S_MB_2U_LIB.S9S_MB_2U(SCH_1):UPI_CPU0_CPU1_P2P2_DN<3>
  G82  UPI_CPU0_CPU1_P2P2_DN<2>  UPI2_RX_DN2  @S9S_MB_2U_LIB.S9S_MB_2U(SCH_1):UPI_CPU0_CPU1_P2P2_DN<2>
  BD73  UPI_CPU0_CPU1_P2P2_DN<23>  UPI2_RX_DN23  @S9S_MB_2U_LIB.S9S_MB_2U(SCH_1):UPI_CPU0_CPU1_P2P2_DN<23>
  BK73  UPI_CPU0_CPU1_P2P2_DN<22>  UPI2_RX_DN22  @S9S_MB_2U_LIB.S9S_MB_2U(SCH_1):UPI_CPU0_CPU1_P2P2_DN<22>
  BN74  UPI_CPU0_CPU1_P2P2_DN<21>  UPI2_RX_DN21  @S9S_MB_2U_LIB.S9S_MB_2U(SCH_1):UPI_CPU0_CPU1_P2P2_DN<21>
  BG74  UPI_CPU0_CPU1_P2P2_DN<20>  UPI2_RX_DN20  @S9S_MB_2U_LIB.S9S_MB_2U(SCH_1):UPI_CPU0_CPU1_P2P2_DN<20>
  F81  UPI_CPU0_CPU1_P2P2_DN<1>  UPI2_RX_DN1  @S9S_MB_2U_LIB.S9S_MB_2U(SCH_1):UPI_CPU0_CPU1_P2P2_DN<1>
  BL76  UPI_CPU0_CPU1_P2P2_DN<19>  UPI2_RX_DN19  @S9S_MB_2U_LIB.S9S_MB_2U(SCH_1):UPI_CPU0_CPU1_P2P2_DN<19>
  BJ76  UPI_CPU0_CPU1_P2P2_DN<18>  UPI2_RX_DN18  @S9S_MB_2U_LIB.S9S_MB_2U(SCH_1):UPI_CPU0_CPU1_P2P2_DN<18>
  BH75  UPI_CPU0_CPU1_P2P2_DN<17>  UPI2_RX_DN17  @S9S_MB_2U_LIB.S9S_MB_2U(SCH_1):UPI_CPU0_CPU1_P2P2_DN<17>
  AW74  UPI_CPU0_CPU1_P2P2_DN<16>  UPI2_RX_DN16  @S9S_MB_2U_LIB.S9S_MB_2U(SCH_1):UPI_CPU0_CPU1_P2P2_DN<16>
  BB75  UPI_CPU0_CPU1_P2P2_DN<15>  UPI2_RX_DN15  @S9S_MB_2U_LIB.S9S_MB_2U(SCH_1):UPI_CPU0_CPU1_P2P2_DN<15>
  AY75  UPI_CPU0_CPU1_P2P2_DN<14>  UPI2_RX_DN14  @S9S_MB_2U_LIB.S9S_MB_2U(SCH_1):UPI_CPU0_CPU1_P2P2_DN<14>
  AV73  UPI_CPU0_CPU1_P2P2_DN<13>  UPI2_RX_DN13  @S9S_MB_2U_LIB.S9S_MB_2U(SCH_1):UPI_CPU0_CPU1_P2P2_DN<13>
  BA72  UPI_CPU0_CPU1_P2P2_DN<12>  UPI2_RX_DN12  @S9S_MB_2U_LIB.S9S_MB_2U(SCH_1):UPI_CPU0_CPU1_P2P2_DN<12>
  AG82  UPI_CPU0_CPU1_P2P2_DN<11>  UPI2_RX_DN11  @S9S_MB_2U_LIB.S9S_MB_2U(SCH_1):UPI_CPU0_CPU1_P2P2_DN<11>
  AJ80  UPI_CPU0_CPU1_P2P2_DN<10>  UPI2_RX_DN10  @S9S_MB_2U_LIB.S9S_MB_2U(SCH_1):UPI_CPU0_CPU1_P2P2_DN<10>
  E80  UPI_CPU0_CPU1_P2P2_DN<0>  UPI2_RX_DN0  @S9S_MB_2U_LIB.S9S_MB_2U(SCH_1):UPI_CPU0_CPU1_P2P2_DN<0>

SOCKET4677_AZIFS054P001C01  I21  U1     [SOCKET4677_AZIFS054P001C01-SOCA]
  DG7  UPI_CPU1_CPU0_P1P0_DP<9>  UPI1_TX_DP9  @S9S_MB_2U_LIB.S9S_MB_2U(SCH_1):UPI_CPU1_CPU0_P1P0_DP<9>
  DJ5  UPI_CPU1_CPU0_P1P0_DP<8>  UPI1_TX_DP8  @S9S_MB_2U_LIB.S9S_MB_2U(SCH_1):UPI_CPU1_CPU0_P1P0_DP<8>
  DM6  UPI_CPU1_CPU0_P1P0_DP<7>  UPI1_TX_DP7  @S9S_MB_2U_LIB.S9S_MB_2U(SCH_1):UPI_CPU1_CPU0_P1P0_DP<7>
  DN5  UPI_CPU1_CPU0_P1P0_DP<6>  UPI1_TX_DP6  @S9S_MB_2U_LIB.S9S_MB_2U(SCH_1):UPI_CPU1_CPU0_P1P0_DP<6>
  DR7  UPI_CPU1_CPU0_P1P0_DP<5>  UPI1_TX_DP5  @S9S_MB_2U_LIB.S9S_MB_2U(SCH_1):UPI_CPU1_CPU0_P1P0_DP<5>
  DU5  UPI_CPU1_CPU0_P1P0_DP<4>  UPI1_TX_DP4  @S9S_MB_2U_LIB.S9S_MB_2U(SCH_1):UPI_CPU1_CPU0_P1P0_DP<4>
  DW7  UPI_CPU1_CPU0_P1P0_DP<3>  UPI1_TX_DP3  @S9S_MB_2U_LIB.S9S_MB_2U(SCH_1):UPI_CPU1_CPU0_P1P0_DP<3>
  EA5  UPI_CPU1_CPU0_P1P0_DP<2>  UPI1_TX_DP2  @S9S_MB_2U_LIB.S9S_MB_2U(SCH_1):UPI_CPU1_CPU0_P1P0_DP<2>
  BW7  UPI_CPU1_CPU0_P1P0_DP<23>  UPI1_TX_DP23  @S9S_MB_2U_LIB.S9S_MB_2U(SCH_1):UPI_CPU1_CPU0_P1P0_DP<23>
  CB6  UPI_CPU1_CPU0_P1P0_DP<22>  UPI1_TX_DP22  @S9S_MB_2U_LIB.S9S_MB_2U(SCH_1):UPI_CPU1_CPU0_P1P0_DP<22>
  CC7  UPI_CPU1_CPU0_P1P0_DP<21>  UPI1_TX_DP21  @S9S_MB_2U_LIB.S9S_MB_2U(SCH_1):UPI_CPU1_CPU0_P1P0_DP<21>
  CF6  UPI_CPU1_CPU0_P1P0_DP<20>  UPI1_TX_DP20  @S9S_MB_2U_LIB.S9S_MB_2U(SCH_1):UPI_CPU1_CPU0_P1P0_DP<20>
  ED6  UPI_CPU1_CPU0_P1P0_DP<1>  UPI1_TX_DP1  @S9S_MB_2U_LIB.S9S_MB_2U(SCH_1):UPI_CPU1_CPU0_P1P0_DP<1>
  CG7  UPI_CPU1_CPU0_P1P0_DP<19>  UPI1_TX_DP19  @S9S_MB_2U_LIB.S9S_MB_2U(SCH_1):UPI_CPU1_CPU0_P1P0_DP<19>
  CK6  UPI_CPU1_CPU0_P1P0_DP<18>  UPI1_TX_DP18  @S9S_MB_2U_LIB.S9S_MB_2U(SCH_1):UPI_CPU1_CPU0_P1P0_DP<18>
  CL7  UPI_CPU1_CPU0_P1P0_DP<17>  UPI1_TX_DP17  @S9S_MB_2U_LIB.S9S_MB_2U(SCH_1):UPI_CPU1_CPU0_P1P0_DP<17>
  CP6  UPI_CPU1_CPU0_P1P0_DP<16>  UPI1_TX_DP16  @S9S_MB_2U_LIB.S9S_MB_2U(SCH_1):UPI_CPU1_CPU0_P1P0_DP<16>
  CR7  UPI_CPU1_CPU0_P1P0_DP<15>  UPI1_TX_DP15  @S9S_MB_2U_LIB.S9S_MB_2U(SCH_1):UPI_CPU1_CPU0_P1P0_DP<15>
  CV6  UPI_CPU1_CPU0_P1P0_DP<14>  UPI1_TX_DP14  @S9S_MB_2U_LIB.S9S_MB_2U(SCH_1):UPI_CPU1_CPU0_P1P0_DP<14>
  CW7  UPI_CPU1_CPU0_P1P0_DP<13>  UPI1_TX_DP13  @S9S_MB_2U_LIB.S9S_MB_2U(SCH_1):UPI_CPU1_CPU0_P1P0_DP<13>
  DB6  UPI_CPU1_CPU0_P1P0_DP<12>  UPI1_TX_DP12  @S9S_MB_2U_LIB.S9S_MB_2U(SCH_1):UPI_CPU1_CPU0_P1P0_DP<12>
  DC7  UPI_CPU1_CPU0_P1P0_DP<11>  UPI1_TX_DP11  @S9S_MB_2U_LIB.S9S_MB_2U(SCH_1):UPI_CPU1_CPU0_P1P0_DP<11>
  DF6  UPI_CPU1_CPU0_P1P0_DP<10>  UPI1_TX_DP10  @S9S_MB_2U_LIB.S9S_MB_2U(SCH_1):UPI_CPU1_CPU0_P1P0_DP<10>
  EE5  UPI_CPU1_CPU0_P1P0_DP<0>  UPI1_TX_DP0  @S9S_MB_2U_LIB.S9S_MB_2U(SCH_1):UPI_CPU1_CPU0_P1P0_DP<0>
  DH6  UPI_CPU1_CPU0_P1P0_DN<9>  UPI1_TX_DN9  @S9S_MB_2U_LIB.S9S_MB_2U(SCH_1):UPI_CPU1_CPU0_P1P0_DN<9>
  DK6  UPI_CPU1_CPU0_P1P0_DN<8>  UPI1_TX_DN8  @S9S_MB_2U_LIB.S9S_MB_2U(SCH_1):UPI_CPU1_CPU0_P1P0_DN<8>
  DL7  UPI_CPU1_CPU0_P1P0_DN<7>  UPI1_TX_DN7  @S9S_MB_2U_LIB.S9S_MB_2U(SCH_1):UPI_CPU1_CPU0_P1P0_DN<7>
  DP6  UPI_CPU1_CPU0_P1P0_DN<6>  UPI1_TX_DN6  @S9S_MB_2U_LIB.S9S_MB_2U(SCH_1):UPI_CPU1_CPU0_P1P0_DN<6>
  DT6  UPI_CPU1_CPU0_P1P0_DN<5>  UPI1_TX_DN5  @S9S_MB_2U_LIB.S9S_MB_2U(SCH_1):UPI_CPU1_CPU0_P1P0_DN<5>
  DV6  UPI_CPU1_CPU0_P1P0_DN<4>  UPI1_TX_DN4  @S9S_MB_2U_LIB.S9S_MB_2U(SCH_1):UPI_CPU1_CPU0_P1P0_DN<4>
  DY6  UPI_CPU1_CPU0_P1P0_DN<3>  UPI1_TX_DN3  @S9S_MB_2U_LIB.S9S_MB_2U(SCH_1):UPI_CPU1_CPU0_P1P0_DN<3>
  EB6  UPI_CPU1_CPU0_P1P0_DN<2>  UPI1_TX_DN2  @S9S_MB_2U_LIB.S9S_MB_2U(SCH_1):UPI_CPU1_CPU0_P1P0_DN<2>
  BY6  UPI_CPU1_CPU0_P1P0_DN<23>  UPI1_TX_DN23  @S9S_MB_2U_LIB.S9S_MB_2U(SCH_1):UPI_CPU1_CPU0_P1P0_DN<23>
  CA5  UPI_CPU1_CPU0_P1P0_DN<22>  UPI1_TX_DN22  @S9S_MB_2U_LIB.S9S_MB_2U(SCH_1):UPI_CPU1_CPU0_P1P0_DN<22>
  CD6  UPI_CPU1_CPU0_P1P0_DN<21>  UPI1_TX_DN21  @S9S_MB_2U_LIB.S9S_MB_2U(SCH_1):UPI_CPU1_CPU0_P1P0_DN<21>
  CE5  UPI_CPU1_CPU0_P1P0_DN<20>  UPI1_TX_DN20  @S9S_MB_2U_LIB.S9S_MB_2U(SCH_1):UPI_CPU1_CPU0_P1P0_DN<20>
  EC7  UPI_CPU1_CPU0_P1P0_DN<1>  UPI1_TX_DN1  @S9S_MB_2U_LIB.S9S_MB_2U(SCH_1):UPI_CPU1_CPU0_P1P0_DN<1>
  CH6  UPI_CPU1_CPU0_P1P0_DN<19>  UPI1_TX_DN19  @S9S_MB_2U_LIB.S9S_MB_2U(SCH_1):UPI_CPU1_CPU0_P1P0_DN<19>
  CJ5  UPI_CPU1_CPU0_P1P0_DN<18>  UPI1_TX_DN18  @S9S_MB_2U_LIB.S9S_MB_2U(SCH_1):UPI_CPU1_CPU0_P1P0_DN<18>
  CM6  UPI_CPU1_CPU0_P1P0_DN<17>  UPI1_TX_DN17  @S9S_MB_2U_LIB.S9S_MB_2U(SCH_1):UPI_CPU1_CPU0_P1P0_DN<17>
  CN5  UPI_CPU1_CPU0_P1P0_DN<16>  UPI1_TX_DN16  @S9S_MB_2U_LIB.S9S_MB_2U(SCH_1):UPI_CPU1_CPU0_P1P0_DN<16>
  CT6  UPI_CPU1_CPU0_P1P0_DN<15>  UPI1_TX_DN15  @S9S_MB_2U_LIB.S9S_MB_2U(SCH_1):UPI_CPU1_CPU0_P1P0_DN<15>
  CU5  UPI_CPU1_CPU0_P1P0_DN<14>  UPI1_TX_DN14  @S9S_MB_2U_LIB.S9S_MB_2U(SCH_1):UPI_CPU1_CPU0_P1P0_DN<14>
  CY6  UPI_CPU1_CPU0_P1P0_DN<13>  UPI1_TX_DN13  @S9S_MB_2U_LIB.S9S_MB_2U(SCH_1):UPI_CPU1_CPU0_P1P0_DN<13>
  DA5  UPI_CPU1_CPU0_P1P0_DN<12>  UPI1_TX_DN12  @S9S_MB_2U_LIB.S9S_MB_2U(SCH_1):UPI_CPU1_CPU0_P1P0_DN<12>
  DD6  UPI_CPU1_CPU0_P1P0_DN<11>  UPI1_TX_DN11  @S9S_MB_2U_LIB.S9S_MB_2U(SCH_1):UPI_CPU1_CPU0_P1P0_DN<11>
  DE5  UPI_CPU1_CPU0_P1P0_DN<10>  UPI1_TX_DN10  @S9S_MB_2U_LIB.S9S_MB_2U(SCH_1):UPI_CPU1_CPU0_P1P0_DN<10>
  EF6  UPI_CPU1_CPU0_P1P0_DN<0>  UPI1_TX_DN0  @S9S_MB_2U_LIB.S9S_MB_2U(SCH_1):UPI_CPU1_CPU0_P1P0_DN<0>
  DK2  UPI_CPU0_CPU1_P0P1_DP<9>  UPI1_RX_DP9  @S9S_MB_2U_LIB.S9S_MB_2U(SCH_1):UPI_CPU0_CPU1_P0P1_DP<9>
  DM2  UPI_CPU0_CPU1_P0P1_DP<8>  UPI1_RX_DP8  @S9S_MB_2U_LIB.S9S_MB_2U(SCH_1):UPI_CPU0_CPU1_P0P1_DP<8>
  DP2  UPI_CPU0_CPU1_P0P1_DP<7>  UPI1_RX_DP7  @S9S_MB_2U_LIB.S9S_MB_2U(SCH_1):UPI_CPU0_CPU1_P0P1_DP<7>
  DR3  UPI_CPU0_CPU1_P0P1_DP<6>  UPI1_RX_DP6  @S9S_MB_2U_LIB.S9S_MB_2U(SCH_1):UPI_CPU0_CPU1_P0P1_DP<6>
  DV2  UPI_CPU0_CPU1_P0P1_DP<5>  UPI1_RX_DP5  @S9S_MB_2U_LIB.S9S_MB_2U(SCH_1):UPI_CPU0_CPU1_P0P1_DP<5>
  DW3  UPI_CPU0_CPU1_P0P1_DP<4>  UPI1_RX_DP4  @S9S_MB_2U_LIB.S9S_MB_2U(SCH_1):UPI_CPU0_CPU1_P0P1_DP<4>
  EB2  UPI_CPU0_CPU1_P0P1_DP<3>  UPI1_RX_DP3  @S9S_MB_2U_LIB.S9S_MB_2U(SCH_1):UPI_CPU0_CPU1_P0P1_DP<3>
  EC3  UPI_CPU0_CPU1_P0P1_DP<2>  UPI1_RX_DP2  @S9S_MB_2U_LIB.S9S_MB_2U(SCH_1):UPI_CPU0_CPU1_P0P1_DP<2>
  BY2  UPI_CPU0_CPU1_P0P1_DP<23>  UPI1_RX_DP23  @S9S_MB_2U_LIB.S9S_MB_2U(SCH_1):UPI_CPU0_CPU1_P0P1_DP<23>
  CC3  UPI_CPU0_CPU1_P0P1_DP<22>  UPI1_RX_DP22  @S9S_MB_2U_LIB.S9S_MB_2U(SCH_1):UPI_CPU0_CPU1_P0P1_DP<22>
  CE1  UPI_CPU0_CPU1_P0P1_DP<21>  UPI1_RX_DP21  @S9S_MB_2U_LIB.S9S_MB_2U(SCH_1):UPI_CPU0_CPU1_P0P1_DP<21>
  CG3  UPI_CPU0_CPU1_P0P1_DP<20>  UPI1_RX_DP20  @S9S_MB_2U_LIB.S9S_MB_2U(SCH_1):UPI_CPU0_CPU1_P0P1_DP<20>
  EG3  UPI_CPU0_CPU1_P0P1_DP<1>  UPI1_RX_DP1  @S9S_MB_2U_LIB.S9S_MB_2U(SCH_1):UPI_CPU0_CPU1_P0P1_DP<1>
  CK2  UPI_CPU0_CPU1_P0P1_DP<19>  UPI1_RX_DP19  @S9S_MB_2U_LIB.S9S_MB_2U(SCH_1):UPI_CPU0_CPU1_P0P1_DP<19>
  CM2  UPI_CPU0_CPU1_P0P1_DP<18>  UPI1_RX_DP18  @S9S_MB_2U_LIB.S9S_MB_2U(SCH_1):UPI_CPU0_CPU1_P0P1_DP<18>
  CP2  UPI_CPU0_CPU1_P0P1_DP<17>  UPI1_RX_DP17  @S9S_MB_2U_LIB.S9S_MB_2U(SCH_1):UPI_CPU0_CPU1_P0P1_DP<17>
  CT2  UPI_CPU0_CPU1_P0P1_DP<16>  UPI1_RX_DP16  @S9S_MB_2U_LIB.S9S_MB_2U(SCH_1):UPI_CPU0_CPU1_P0P1_DP<16>
  CU1  UPI_CPU0_CPU1_P0P1_DP<15>  UPI1_RX_DP15  @S9S_MB_2U_LIB.S9S_MB_2U(SCH_1):UPI_CPU0_CPU1_P0P1_DP<15>
  CW3  UPI_CPU0_CPU1_P0P1_DP<14>  UPI1_RX_DP14  @S9S_MB_2U_LIB.S9S_MB_2U(SCH_1):UPI_CPU0_CPU1_P0P1_DP<14>
  DA1  UPI_CPU0_CPU1_P0P1_DP<13>  UPI1_RX_DP13  @S9S_MB_2U_LIB.S9S_MB_2U(SCH_1):UPI_CPU0_CPU1_P0P1_DP<13>
  DC3  UPI_CPU0_CPU1_P0P1_DP<12>  UPI1_RX_DP12  @S9S_MB_2U_LIB.S9S_MB_2U(SCH_1):UPI_CPU0_CPU1_P0P1_DP<12>
  DF2  UPI_CPU0_CPU1_P0P1_DP<11>  UPI1_RX_DP11  @S9S_MB_2U_LIB.S9S_MB_2U(SCH_1):UPI_CPU0_CPU1_P0P1_DP<11>
  DH2  UPI_CPU0_CPU1_P0P1_DP<10>  UPI1_RX_DP10  @S9S_MB_2U_LIB.S9S_MB_2U(SCH_1):UPI_CPU0_CPU1_P0P1_DP<10>
  EJ3  UPI_CPU0_CPU1_P0P1_DP<0>  UPI1_RX_DP0  @S9S_MB_2U_LIB.S9S_MB_2U(SCH_1):UPI_CPU0_CPU1_P0P1_DP<0>
  DJ1  UPI_CPU0_CPU1_P0P1_DN<9>  UPI1_RX_DN9  @S9S_MB_2U_LIB.S9S_MB_2U(SCH_1):UPI_CPU0_CPU1_P0P1_DN<9>
  DL3  UPI_CPU0_CPU1_P0P1_DN<8>  UPI1_RX_DN8  @S9S_MB_2U_LIB.S9S_MB_2U(SCH_1):UPI_CPU0_CPU1_P0P1_DN<8>
  DN1  UPI_CPU0_CPU1_P0P1_DN<7>  UPI1_RX_DN7  @S9S_MB_2U_LIB.S9S_MB_2U(SCH_1):UPI_CPU0_CPU1_P0P1_DN<7>
  DT2  UPI_CPU0_CPU1_P0P1_DN<6>  UPI1_RX_DN6  @S9S_MB_2U_LIB.S9S_MB_2U(SCH_1):UPI_CPU0_CPU1_P0P1_DN<6>
  DU1  UPI_CPU0_CPU1_P0P1_DN<5>  UPI1_RX_DN5  @S9S_MB_2U_LIB.S9S_MB_2U(SCH_1):UPI_CPU0_CPU1_P0P1_DN<5>
  DY2  UPI_CPU0_CPU1_P0P1_DN<4>  UPI1_RX_DN4  @S9S_MB_2U_LIB.S9S_MB_2U(SCH_1):UPI_CPU0_CPU1_P0P1_DN<4>
  EA1  UPI_CPU0_CPU1_P0P1_DN<3>  UPI1_RX_DN3  @S9S_MB_2U_LIB.S9S_MB_2U(SCH_1):UPI_CPU0_CPU1_P0P1_DN<3>
  ED2  UPI_CPU0_CPU1_P0P1_DN<2>  UPI1_RX_DN2  @S9S_MB_2U_LIB.S9S_MB_2U(SCH_1):UPI_CPU0_CPU1_P0P1_DN<2>
  CB2  UPI_CPU0_CPU1_P0P1_DN<23>  UPI1_RX_DN23  @S9S_MB_2U_LIB.S9S_MB_2U(SCH_1):UPI_CPU0_CPU1_P0P1_DN<23>
  CD2  UPI_CPU0_CPU1_P0P1_DN<22>  UPI1_RX_DN22  @S9S_MB_2U_LIB.S9S_MB_2U(SCH_1):UPI_CPU0_CPU1_P0P1_DN<22>
  CF2  UPI_CPU0_CPU1_P0P1_DN<21>  UPI1_RX_DN21  @S9S_MB_2U_LIB.S9S_MB_2U(SCH_1):UPI_CPU0_CPU1_P0P1_DN<21>
  CH2  UPI_CPU0_CPU1_P0P1_DN<20>  UPI1_RX_DN20  @S9S_MB_2U_LIB.S9S_MB_2U(SCH_1):UPI_CPU0_CPU1_P0P1_DN<20>
  EE3  UPI_CPU0_CPU1_P0P1_DN<1>  UPI1_RX_DN1  @S9S_MB_2U_LIB.S9S_MB_2U(SCH_1):UPI_CPU0_CPU1_P0P1_DN<1>
  CJ1  UPI_CPU0_CPU1_P0P1_DN<19>  UPI1_RX_DN19  @S9S_MB_2U_LIB.S9S_MB_2U(SCH_1):UPI_CPU0_CPU1_P0P1_DN<19>
  CL3  UPI_CPU0_CPU1_P0P1_DN<18>  UPI1_RX_DN18  @S9S_MB_2U_LIB.S9S_MB_2U(SCH_1):UPI_CPU0_CPU1_P0P1_DN<18>
  CN1  UPI_CPU0_CPU1_P0P1_DN<17>  UPI1_RX_DN17  @S9S_MB_2U_LIB.S9S_MB_2U(SCH_1):UPI_CPU0_CPU1_P0P1_DN<17>
  CR3  UPI_CPU0_CPU1_P0P1_DN<16>  UPI1_RX_DN16  @S9S_MB_2U_LIB.S9S_MB_2U(SCH_1):UPI_CPU0_CPU1_P0P1_DN<16>
  CV2  UPI_CPU0_CPU1_P0P1_DN<15>  UPI1_RX_DN15  @S9S_MB_2U_LIB.S9S_MB_2U(SCH_1):UPI_CPU0_CPU1_P0P1_DN<15>
  CY2  UPI_CPU0_CPU1_P0P1_DN<14>  UPI1_RX_DN14  @S9S_MB_2U_LIB.S9S_MB_2U(SCH_1):UPI_CPU0_CPU1_P0P1_DN<14>
  DB2  UPI_CPU0_CPU1_P0P1_DN<13>  UPI1_RX_DN13  @S9S_MB_2U_LIB.S9S_MB_2U(SCH_1):UPI_CPU0_CPU1_P0P1_DN<13>
  DD2  UPI_CPU0_CPU1_P0P1_DN<12>  UPI1_RX_DN12  @S9S_MB_2U_LIB.S9S_MB_2U(SCH_1):UPI_CPU0_CPU1_P0P1_DN<12>
  DE1  UPI_CPU0_CPU1_P0P1_DN<11>  UPI1_RX_DN11  @S9S_MB_2U_LIB.S9S_MB_2U(SCH_1):UPI_CPU0_CPU1_P0P1_DN<11>
  DG3  UPI_CPU0_CPU1_P0P1_DN<10>  UPI1_RX_DN10  @S9S_MB_2U_LIB.S9S_MB_2U(SCH_1):UPI_CPU0_CPU1_P0P1_DN<10>
  EH2  UPI_CPU0_CPU1_P0P1_DN<0>  UPI1_RX_DN0  @S9S_MB_2U_LIB.S9S_MB_2U(SCH_1):UPI_CPU0_CPU1_P0P1_DN<0>

SOCKET4677_AZIFS054P001C01  I51  U1     [SOCKET4677_AZIFS054P001C01-SOCA]
  AG3  UPI_CPU1_CPU0_P0P1_DP<9>  UPI0_TX_DP9  @S9S_MB_2U_LIB.S9S_MB_2U(SCH_1):UPI_CPU1_CPU0_P0P1_DP<9>
  AE1  UPI_CPU1_CPU0_P0P1_DP<8>  UPI0_TX_DP8  @S9S_MB_2U_LIB.S9S_MB_2U(SCH_1):UPI_CPU1_CPU0_P0P1_DP<8>
  AC3  UPI_CPU1_CPU0_P0P1_DP<7>  UPI0_TX_DP7  @S9S_MB_2U_LIB.S9S_MB_2U(SCH_1):UPI_CPU1_CPU0_P0P1_DP<7>
  AB2  UPI_CPU1_CPU0_P0P1_DP<6>  UPI0_TX_DP6  @S9S_MB_2U_LIB.S9S_MB_2U(SCH_1):UPI_CPU1_CPU0_P0P1_DP<6>
   W3  UPI_CPU1_CPU0_P0P1_DP<5>  UPI0_TX_DP5  @S9S_MB_2U_LIB.S9S_MB_2U(SCH_1):UPI_CPU1_CPU0_P0P1_DP<5>
   V2  UPI_CPU1_CPU0_P0P1_DP<4>  UPI0_TX_DP4  @S9S_MB_2U_LIB.S9S_MB_2U(SCH_1):UPI_CPU1_CPU0_P0P1_DP<4>
   R3  UPI_CPU1_CPU0_P0P1_DP<3>  UPI0_TX_DP3  @S9S_MB_2U_LIB.S9S_MB_2U(SCH_1):UPI_CPU1_CPU0_P0P1_DP<3>
   P2  UPI_CPU1_CPU0_P0P1_DP<2>  UPI0_TX_DP2  @S9S_MB_2U_LIB.S9S_MB_2U(SCH_1):UPI_CPU1_CPU0_P0P1_DP<2>
  BU3  UPI_CPU1_CPU0_P0P1_DP<23>  UPI0_TX_DP23  @S9S_MB_2U_LIB.S9S_MB_2U(SCH_1):UPI_CPU1_CPU0_P0P1_DP<23>
  BN3  UPI_CPU1_CPU0_P0P1_DP<22>  UPI0_TX_DP22  @S9S_MB_2U_LIB.S9S_MB_2U(SCH_1):UPI_CPU1_CPU0_P0P1_DP<22>
  BL3  UPI_CPU1_CPU0_P0P1_DP<21>  UPI0_TX_DP21  @S9S_MB_2U_LIB.S9S_MB_2U(SCH_1):UPI_CPU1_CPU0_P0P1_DP<21>
  BJ1  UPI_CPU1_CPU0_P0P1_DP<20>  UPI0_TX_DP20  @S9S_MB_2U_LIB.S9S_MB_2U(SCH_1):UPI_CPU1_CPU0_P0P1_DP<20>
   L3  UPI_CPU1_CPU0_P0P1_DP<1>  UPI0_TX_DP1  @S9S_MB_2U_LIB.S9S_MB_2U(SCH_1):UPI_CPU1_CPU0_P0P1_DP<1>
  BG3  UPI_CPU1_CPU0_P0P1_DP<19>  UPI0_TX_DP19  @S9S_MB_2U_LIB.S9S_MB_2U(SCH_1):UPI_CPU1_CPU0_P0P1_DP<19>
  BE1  UPI_CPU1_CPU0_P0P1_DP<18>  UPI0_TX_DP18  @S9S_MB_2U_LIB.S9S_MB_2U(SCH_1):UPI_CPU1_CPU0_P0P1_DP<18>
  BC3  UPI_CPU1_CPU0_P0P1_DP<17>  UPI0_TX_DP17  @S9S_MB_2U_LIB.S9S_MB_2U(SCH_1):UPI_CPU1_CPU0_P0P1_DP<17>
  BA1  UPI_CPU1_CPU0_P0P1_DP<16>  UPI0_TX_DP16  @S9S_MB_2U_LIB.S9S_MB_2U(SCH_1):UPI_CPU1_CPU0_P0P1_DP<16>
  AW3  UPI_CPU1_CPU0_P0P1_DP<15>  UPI0_TX_DP15  @S9S_MB_2U_LIB.S9S_MB_2U(SCH_1):UPI_CPU1_CPU0_P0P1_DP<15>
  AV2  UPI_CPU1_CPU0_P0P1_DP<14>  UPI0_TX_DP14  @S9S_MB_2U_LIB.S9S_MB_2U(SCH_1):UPI_CPU1_CPU0_P0P1_DP<14>
  AR3  UPI_CPU1_CPU0_P0P1_DP<13>  UPI0_TX_DP13  @S9S_MB_2U_LIB.S9S_MB_2U(SCH_1):UPI_CPU1_CPU0_P0P1_DP<13>
  AN1  UPI_CPU1_CPU0_P0P1_DP<12>  UPI0_TX_DP12  @S9S_MB_2U_LIB.S9S_MB_2U(SCH_1):UPI_CPU1_CPU0_P0P1_DP<12>
  AL3  UPI_CPU1_CPU0_P0P1_DP<11>  UPI0_TX_DP11  @S9S_MB_2U_LIB.S9S_MB_2U(SCH_1):UPI_CPU1_CPU0_P0P1_DP<11>
  AJ1  UPI_CPU1_CPU0_P0P1_DP<10>  UPI0_TX_DP10  @S9S_MB_2U_LIB.S9S_MB_2U(SCH_1):UPI_CPU1_CPU0_P0P1_DP<10>
   J3  UPI_CPU1_CPU0_P0P1_DP<0>  UPI0_TX_DP0  @S9S_MB_2U_LIB.S9S_MB_2U(SCH_1):UPI_CPU1_CPU0_P0P1_DP<0>
  AH2  UPI_CPU1_CPU0_P0P1_DN<9>  UPI0_TX_DN9  @S9S_MB_2U_LIB.S9S_MB_2U(SCH_1):UPI_CPU1_CPU0_P0P1_DN<9>
  AF2  UPI_CPU1_CPU0_P0P1_DN<8>  UPI0_TX_DN8  @S9S_MB_2U_LIB.S9S_MB_2U(SCH_1):UPI_CPU1_CPU0_P0P1_DN<8>
  AD2  UPI_CPU1_CPU0_P0P1_DN<7>  UPI0_TX_DN7  @S9S_MB_2U_LIB.S9S_MB_2U(SCH_1):UPI_CPU1_CPU0_P0P1_DN<7>
  AA1  UPI_CPU1_CPU0_P0P1_DN<6>  UPI0_TX_DN6  @S9S_MB_2U_LIB.S9S_MB_2U(SCH_1):UPI_CPU1_CPU0_P0P1_DN<6>
   Y2  UPI_CPU1_CPU0_P0P1_DN<5>  UPI0_TX_DN5  @S9S_MB_2U_LIB.S9S_MB_2U(SCH_1):UPI_CPU1_CPU0_P0P1_DN<5>
   U1  UPI_CPU1_CPU0_P0P1_DN<4>  UPI0_TX_DN4  @S9S_MB_2U_LIB.S9S_MB_2U(SCH_1):UPI_CPU1_CPU0_P0P1_DN<4>
   T2  UPI_CPU1_CPU0_P0P1_DN<3>  UPI0_TX_DN3  @S9S_MB_2U_LIB.S9S_MB_2U(SCH_1):UPI_CPU1_CPU0_P0P1_DN<3>
   N1  UPI_CPU1_CPU0_P0P1_DN<2>  UPI0_TX_DN2  @S9S_MB_2U_LIB.S9S_MB_2U(SCH_1):UPI_CPU1_CPU0_P0P1_DN<2>
  BT2  UPI_CPU1_CPU0_P0P1_DN<23>  UPI0_TX_DN23  @S9S_MB_2U_LIB.S9S_MB_2U(SCH_1):UPI_CPU1_CPU0_P0P1_DN<23>
  BR3  UPI_CPU1_CPU0_P0P1_DN<22>  UPI0_TX_DN22  @S9S_MB_2U_LIB.S9S_MB_2U(SCH_1):UPI_CPU1_CPU0_P0P1_DN<22>
  BM2  UPI_CPU1_CPU0_P0P1_DN<21>  UPI0_TX_DN21  @S9S_MB_2U_LIB.S9S_MB_2U(SCH_1):UPI_CPU1_CPU0_P0P1_DN<21>
  BK2  UPI_CPU1_CPU0_P0P1_DN<20>  UPI0_TX_DN20  @S9S_MB_2U_LIB.S9S_MB_2U(SCH_1):UPI_CPU1_CPU0_P0P1_DN<20>
   M2  UPI_CPU1_CPU0_P0P1_DN<1>  UPI0_TX_DN1  @S9S_MB_2U_LIB.S9S_MB_2U(SCH_1):UPI_CPU1_CPU0_P0P1_DN<1>
  BH2  UPI_CPU1_CPU0_P0P1_DN<19>  UPI0_TX_DN19  @S9S_MB_2U_LIB.S9S_MB_2U(SCH_1):UPI_CPU1_CPU0_P0P1_DN<19>
  BF2  UPI_CPU1_CPU0_P0P1_DN<18>  UPI0_TX_DN18  @S9S_MB_2U_LIB.S9S_MB_2U(SCH_1):UPI_CPU1_CPU0_P0P1_DN<18>
  BD2  UPI_CPU1_CPU0_P0P1_DN<17>  UPI0_TX_DN17  @S9S_MB_2U_LIB.S9S_MB_2U(SCH_1):UPI_CPU1_CPU0_P0P1_DN<17>
  BB2  UPI_CPU1_CPU0_P0P1_DN<16>  UPI0_TX_DN16  @S9S_MB_2U_LIB.S9S_MB_2U(SCH_1):UPI_CPU1_CPU0_P0P1_DN<16>
  AY2  UPI_CPU1_CPU0_P0P1_DN<15>  UPI0_TX_DN15  @S9S_MB_2U_LIB.S9S_MB_2U(SCH_1):UPI_CPU1_CPU0_P0P1_DN<15>
  AU1  UPI_CPU1_CPU0_P0P1_DN<14>  UPI0_TX_DN14  @S9S_MB_2U_LIB.S9S_MB_2U(SCH_1):UPI_CPU1_CPU0_P0P1_DN<14>
  AT2  UPI_CPU1_CPU0_P0P1_DN<13>  UPI0_TX_DN13  @S9S_MB_2U_LIB.S9S_MB_2U(SCH_1):UPI_CPU1_CPU0_P0P1_DN<13>
  AP2  UPI_CPU1_CPU0_P0P1_DN<12>  UPI0_TX_DN12  @S9S_MB_2U_LIB.S9S_MB_2U(SCH_1):UPI_CPU1_CPU0_P0P1_DN<12>
  AM2  UPI_CPU1_CPU0_P0P1_DN<11>  UPI0_TX_DN11  @S9S_MB_2U_LIB.S9S_MB_2U(SCH_1):UPI_CPU1_CPU0_P0P1_DN<11>
  AK2  UPI_CPU1_CPU0_P0P1_DN<10>  UPI0_TX_DN10  @S9S_MB_2U_LIB.S9S_MB_2U(SCH_1):UPI_CPU1_CPU0_P0P1_DN<10>
   K4  UPI_CPU1_CPU0_P0P1_DN<0>  UPI0_TX_DN0  @S9S_MB_2U_LIB.S9S_MB_2U(SCH_1):UPI_CPU1_CPU0_P0P1_DN<0>
  AJ5  UPI_CPU0_CPU1_P1P0_DP<9>  UPI0_RX_DP9  @S9S_MB_2U_LIB.S9S_MB_2U(SCH_1):UPI_CPU0_CPU1_P1P0_DP<9>
  AG7  UPI_CPU0_CPU1_P1P0_DP<8>  UPI0_RX_DP8  @S9S_MB_2U_LIB.S9S_MB_2U(SCH_1):UPI_CPU0_CPU1_P1P0_DP<8>
  AD6  UPI_CPU0_CPU1_P1P0_DP<7>  UPI0_RX_DP7  @S9S_MB_2U_LIB.S9S_MB_2U(SCH_1):UPI_CPU0_CPU1_P1P0_DP<7>
  AC7  UPI_CPU0_CPU1_P1P0_DP<6>  UPI0_RX_DP6  @S9S_MB_2U_LIB.S9S_MB_2U(SCH_1):UPI_CPU0_CPU1_P1P0_DP<6>
   Y6  UPI_CPU0_CPU1_P1P0_DP<5>  UPI0_RX_DP5  @S9S_MB_2U_LIB.S9S_MB_2U(SCH_1):UPI_CPU0_CPU1_P1P0_DP<5>
   W7  UPI_CPU0_CPU1_P1P0_DP<4>  UPI0_RX_DP4  @S9S_MB_2U_LIB.S9S_MB_2U(SCH_1):UPI_CPU0_CPU1_P1P0_DP<4>
   T6  UPI_CPU0_CPU1_P1P0_DP<3>  UPI0_RX_DP3  @S9S_MB_2U_LIB.S9S_MB_2U(SCH_1):UPI_CPU0_CPU1_P1P0_DP<3>
   R7  UPI_CPU0_CPU1_P1P0_DP<2>  UPI0_RX_DP2  @S9S_MB_2U_LIB.S9S_MB_2U(SCH_1):UPI_CPU0_CPU1_P1P0_DP<2>
  BT6  UPI_CPU0_CPU1_P1P0_DP<23>  UPI0_RX_DP23  @S9S_MB_2U_LIB.S9S_MB_2U(SCH_1):UPI_CPU0_CPU1_P1P0_DP<23>
  BP6  UPI_CPU0_CPU1_P1P0_DP<22>  UPI0_RX_DP22  @S9S_MB_2U_LIB.S9S_MB_2U(SCH_1):UPI_CPU0_CPU1_P1P0_DP<22>
  BM6  UPI_CPU0_CPU1_P1P0_DP<21>  UPI0_RX_DP21  @S9S_MB_2U_LIB.S9S_MB_2U(SCH_1):UPI_CPU0_CPU1_P1P0_DP<21>
  BL7  UPI_CPU0_CPU1_P1P0_DP<20>  UPI0_RX_DP20  @S9S_MB_2U_LIB.S9S_MB_2U(SCH_1):UPI_CPU0_CPU1_P1P0_DP<20>
   M6  UPI_CPU0_CPU1_P1P0_DP<1>  UPI0_RX_DP1  @S9S_MB_2U_LIB.S9S_MB_2U(SCH_1):UPI_CPU0_CPU1_P1P0_DP<1>
  BH6  UPI_CPU0_CPU1_P1P0_DP<19>  UPI0_RX_DP19  @S9S_MB_2U_LIB.S9S_MB_2U(SCH_1):UPI_CPU0_CPU1_P1P0_DP<19>
  BG7  UPI_CPU0_CPU1_P1P0_DP<18>  UPI0_RX_DP18  @S9S_MB_2U_LIB.S9S_MB_2U(SCH_1):UPI_CPU0_CPU1_P1P0_DP<18>
  BD6  UPI_CPU0_CPU1_P1P0_DP<17>  UPI0_RX_DP17  @S9S_MB_2U_LIB.S9S_MB_2U(SCH_1):UPI_CPU0_CPU1_P1P0_DP<17>
  BC7  UPI_CPU0_CPU1_P1P0_DP<16>  UPI0_RX_DP16  @S9S_MB_2U_LIB.S9S_MB_2U(SCH_1):UPI_CPU0_CPU1_P1P0_DP<16>
  AY6  UPI_CPU0_CPU1_P1P0_DP<15>  UPI0_RX_DP15  @S9S_MB_2U_LIB.S9S_MB_2U(SCH_1):UPI_CPU0_CPU1_P1P0_DP<15>
  AW7  UPI_CPU0_CPU1_P1P0_DP<14>  UPI0_RX_DP14  @S9S_MB_2U_LIB.S9S_MB_2U(SCH_1):UPI_CPU0_CPU1_P1P0_DP<14>
  AT6  UPI_CPU0_CPU1_P1P0_DP<13>  UPI0_RX_DP13  @S9S_MB_2U_LIB.S9S_MB_2U(SCH_1):UPI_CPU0_CPU1_P1P0_DP<13>
  AR7  UPI_CPU0_CPU1_P1P0_DP<12>  UPI0_RX_DP12  @S9S_MB_2U_LIB.S9S_MB_2U(SCH_1):UPI_CPU0_CPU1_P1P0_DP<12>
  AM6  UPI_CPU0_CPU1_P1P0_DP<11>  UPI0_RX_DP11  @S9S_MB_2U_LIB.S9S_MB_2U(SCH_1):UPI_CPU0_CPU1_P1P0_DP<11>
  AL7  UPI_CPU0_CPU1_P1P0_DP<10>  UPI0_RX_DP10  @S9S_MB_2U_LIB.S9S_MB_2U(SCH_1):UPI_CPU0_CPU1_P1P0_DP<10>
   L7  UPI_CPU0_CPU1_P1P0_DP<0>  UPI0_RX_DP0  @S9S_MB_2U_LIB.S9S_MB_2U(SCH_1):UPI_CPU0_CPU1_P1P0_DP<0>
  AH6  UPI_CPU0_CPU1_P1P0_DN<9>  UPI0_RX_DN9  @S9S_MB_2U_LIB.S9S_MB_2U(SCH_1):UPI_CPU0_CPU1_P1P0_DN<9>
  AF6  UPI_CPU0_CPU1_P1P0_DN<8>  UPI0_RX_DN8  @S9S_MB_2U_LIB.S9S_MB_2U(SCH_1):UPI_CPU0_CPU1_P1P0_DN<8>
  AE5  UPI_CPU0_CPU1_P1P0_DN<7>  UPI0_RX_DN7  @S9S_MB_2U_LIB.S9S_MB_2U(SCH_1):UPI_CPU0_CPU1_P1P0_DN<7>
  AB6  UPI_CPU0_CPU1_P1P0_DN<6>  UPI0_RX_DN6  @S9S_MB_2U_LIB.S9S_MB_2U(SCH_1):UPI_CPU0_CPU1_P1P0_DN<6>
  AA5  UPI_CPU0_CPU1_P1P0_DN<5>  UPI0_RX_DN5  @S9S_MB_2U_LIB.S9S_MB_2U(SCH_1):UPI_CPU0_CPU1_P1P0_DN<5>
   V6  UPI_CPU0_CPU1_P1P0_DN<4>  UPI0_RX_DN4  @S9S_MB_2U_LIB.S9S_MB_2U(SCH_1):UPI_CPU0_CPU1_P1P0_DN<4>
   U5  UPI_CPU0_CPU1_P1P0_DN<3>  UPI0_RX_DN3  @S9S_MB_2U_LIB.S9S_MB_2U(SCH_1):UPI_CPU0_CPU1_P1P0_DN<3>
   P6  UPI_CPU0_CPU1_P1P0_DN<2>  UPI0_RX_DN2  @S9S_MB_2U_LIB.S9S_MB_2U(SCH_1):UPI_CPU0_CPU1_P1P0_DN<2>
  BU5  UPI_CPU0_CPU1_P1P0_DN<23>  UPI0_RX_DN23  @S9S_MB_2U_LIB.S9S_MB_2U(SCH_1):UPI_CPU0_CPU1_P1P0_DN<23>
  BR7  UPI_CPU0_CPU1_P1P0_DN<22>  UPI0_RX_DN22  @S9S_MB_2U_LIB.S9S_MB_2U(SCH_1):UPI_CPU0_CPU1_P1P0_DN<22>
  BN5  UPI_CPU0_CPU1_P1P0_DN<21>  UPI0_RX_DN21  @S9S_MB_2U_LIB.S9S_MB_2U(SCH_1):UPI_CPU0_CPU1_P1P0_DN<21>
  BK6  UPI_CPU0_CPU1_P1P0_DN<20>  UPI0_RX_DN20  @S9S_MB_2U_LIB.S9S_MB_2U(SCH_1):UPI_CPU0_CPU1_P1P0_DN<20>
   N5  UPI_CPU0_CPU1_P1P0_DN<1>  UPI0_RX_DN1  @S9S_MB_2U_LIB.S9S_MB_2U(SCH_1):UPI_CPU0_CPU1_P1P0_DN<1>
  BJ5  UPI_CPU0_CPU1_P1P0_DN<19>  UPI0_RX_DN19  @S9S_MB_2U_LIB.S9S_MB_2U(SCH_1):UPI_CPU0_CPU1_P1P0_DN<19>
  BF6  UPI_CPU0_CPU1_P1P0_DN<18>  UPI0_RX_DN18  @S9S_MB_2U_LIB.S9S_MB_2U(SCH_1):UPI_CPU0_CPU1_P1P0_DN<18>
  BE5  UPI_CPU0_CPU1_P1P0_DN<17>  UPI0_RX_DN17  @S9S_MB_2U_LIB.S9S_MB_2U(SCH_1):UPI_CPU0_CPU1_P1P0_DN<17>
  BB6  UPI_CPU0_CPU1_P1P0_DN<16>  UPI0_RX_DN16  @S9S_MB_2U_LIB.S9S_MB_2U(SCH_1):UPI_CPU0_CPU1_P1P0_DN<16>
  BA5  UPI_CPU0_CPU1_P1P0_DN<15>  UPI0_RX_DN15  @S9S_MB_2U_LIB.S9S_MB_2U(SCH_1):UPI_CPU0_CPU1_P1P0_DN<15>
  AV6  UPI_CPU0_CPU1_P1P0_DN<14>  UPI0_RX_DN14  @S9S_MB_2U_LIB.S9S_MB_2U(SCH_1):UPI_CPU0_CPU1_P1P0_DN<14>
  AU5  UPI_CPU0_CPU1_P1P0_DN<13>  UPI0_RX_DN13  @S9S_MB_2U_LIB.S9S_MB_2U(SCH_1):UPI_CPU0_CPU1_P1P0_DN<13>
  AP6  UPI_CPU0_CPU1_P1P0_DN<12>  UPI0_RX_DN12  @S9S_MB_2U_LIB.S9S_MB_2U(SCH_1):UPI_CPU0_CPU1_P1P0_DN<12>
  AN5  UPI_CPU0_CPU1_P1P0_DN<11>  UPI0_RX_DN11  @S9S_MB_2U_LIB.S9S_MB_2U(SCH_1):UPI_CPU0_CPU1_P1P0_DN<11>
  AK6  UPI_CPU0_CPU1_P1P0_DN<10>  UPI0_RX_DN10  @S9S_MB_2U_LIB.S9S_MB_2U(SCH_1):UPI_CPU0_CPU1_P1P0_DN<10>
   K6  UPI_CPU0_CPU1_P1P0_DN<0>  UPI0_RX_DN0  @S9S_MB_2U_LIB.S9S_MB_2U(SCH_1):UPI_CPU0_CPU1_P1P0_DN<0>

SOCKET4677_AZIFS054P001C01  I18  U1     [SOCKET4677_AZIFS054P001C01-SOCA]
  AD87  P5E_CPU1_PE4_TX_DP<9>  PE4_TX_DP6  @S9S_MB_2U_LIB.S9S_MB_2U(SCH_1):P5E_CPU1_PE4_TX_DP<9>
  AF85  P5E_CPU1_PE4_TX_DP<8>  PE4_TX_DP7  @S9S_MB_2U_LIB.S9S_MB_2U(SCH_1):P5E_CPU1_PE4_TX_DP<8>
  AH87  P5E_CPU1_PE4_TX_DP<7>  PE4_TX_DP8  @S9S_MB_2U_LIB.S9S_MB_2U(SCH_1):P5E_CPU1_PE4_TX_DP<7>
  AK85  P5E_CPU1_PE4_TX_DP<6>  PE4_TX_DP9  @S9S_MB_2U_LIB.S9S_MB_2U(SCH_1):P5E_CPU1_PE4_TX_DP<6>
  AM87  P5E_CPU1_PE4_TX_DP<5>  PE4_TX_DP10  @S9S_MB_2U_LIB.S9S_MB_2U(SCH_1):P5E_CPU1_PE4_TX_DP<5>
  AN86  P5E_CPU1_PE4_TX_DP<4>  PE4_TX_DP11  @S9S_MB_2U_LIB.S9S_MB_2U(SCH_1):P5E_CPU1_PE4_TX_DP<4>
  AT87  P5E_CPU1_PE4_TX_DP<3>  PE4_TX_DP12  @S9S_MB_2U_LIB.S9S_MB_2U(SCH_1):P5E_CPU1_PE4_TX_DP<3>
  AV85  P5E_CPU1_PE4_TX_DP<2>  PE4_TX_DP13  @S9S_MB_2U_LIB.S9S_MB_2U(SCH_1):P5E_CPU1_PE4_TX_DP<2>
  AY87  P5E_CPU1_PE4_TX_DP<1>  PE4_TX_DP14  @S9S_MB_2U_LIB.S9S_MB_2U(SCH_1):P5E_CPU1_PE4_TX_DP<1>
  M87  P5E_CPU1_PE4_TX_DP<15>  PE4_TX_DP0  @S9S_MB_2U_LIB.S9S_MB_2U(SCH_1):P5E_CPU1_PE4_TX_DP<15>
  N86  P5E_CPU1_PE4_TX_DP<14>  PE4_TX_DP1  @S9S_MB_2U_LIB.S9S_MB_2U(SCH_1):P5E_CPU1_PE4_TX_DP<14>
  T87  P5E_CPU1_PE4_TX_DP<13>  PE4_TX_DP2  @S9S_MB_2U_LIB.S9S_MB_2U(SCH_1):P5E_CPU1_PE4_TX_DP<13>
  V85  P5E_CPU1_PE4_TX_DP<12>  PE4_TX_DP3  @S9S_MB_2U_LIB.S9S_MB_2U(SCH_1):P5E_CPU1_PE4_TX_DP<12>
  Y87  P5E_CPU1_PE4_TX_DP<11>  PE4_TX_DP4  @S9S_MB_2U_LIB.S9S_MB_2U(SCH_1):P5E_CPU1_PE4_TX_DP<11>
  AB85  P5E_CPU1_PE4_TX_DP<10>  PE4_TX_DP5  @S9S_MB_2U_LIB.S9S_MB_2U(SCH_1):P5E_CPU1_PE4_TX_DP<10>
  BB85  P5E_CPU1_PE4_TX_DP<0>  PE4_TX_DP15  @S9S_MB_2U_LIB.S9S_MB_2U(SCH_1):P5E_CPU1_PE4_TX_DP<0>
  AC86  P5E_CPU1_PE4_TX_DN<9>  PE4_TX_DN6  @S9S_MB_2U_LIB.S9S_MB_2U(SCH_1):P5E_CPU1_PE4_TX_DN<9>
  AE86  P5E_CPU1_PE4_TX_DN<8>  PE4_TX_DN7  @S9S_MB_2U_LIB.S9S_MB_2U(SCH_1):P5E_CPU1_PE4_TX_DN<8>
  AG86  P5E_CPU1_PE4_TX_DN<7>  PE4_TX_DN8  @S9S_MB_2U_LIB.S9S_MB_2U(SCH_1):P5E_CPU1_PE4_TX_DN<7>
  AJ86  P5E_CPU1_PE4_TX_DN<6>  PE4_TX_DN9  @S9S_MB_2U_LIB.S9S_MB_2U(SCH_1):P5E_CPU1_PE4_TX_DN<6>
  AL86  P5E_CPU1_PE4_TX_DN<5>  PE4_TX_DN10  @S9S_MB_2U_LIB.S9S_MB_2U(SCH_1):P5E_CPU1_PE4_TX_DN<5>
  AP85  P5E_CPU1_PE4_TX_DN<4>  PE4_TX_DN11  @S9S_MB_2U_LIB.S9S_MB_2U(SCH_1):P5E_CPU1_PE4_TX_DN<4>
  AR86  P5E_CPU1_PE4_TX_DN<3>  PE4_TX_DN12  @S9S_MB_2U_LIB.S9S_MB_2U(SCH_1):P5E_CPU1_PE4_TX_DN<3>
  AU86  P5E_CPU1_PE4_TX_DN<2>  PE4_TX_DN13  @S9S_MB_2U_LIB.S9S_MB_2U(SCH_1):P5E_CPU1_PE4_TX_DN<2>
  AW86  P5E_CPU1_PE4_TX_DN<1>  PE4_TX_DN14  @S9S_MB_2U_LIB.S9S_MB_2U(SCH_1):P5E_CPU1_PE4_TX_DN<1>
  L86  P5E_CPU1_PE4_TX_DN<15>  PE4_TX_DN0  @S9S_MB_2U_LIB.S9S_MB_2U(SCH_1):P5E_CPU1_PE4_TX_DN<15>
  P85  P5E_CPU1_PE4_TX_DN<14>  PE4_TX_DN1  @S9S_MB_2U_LIB.S9S_MB_2U(SCH_1):P5E_CPU1_PE4_TX_DN<14>
  R86  P5E_CPU1_PE4_TX_DN<13>  PE4_TX_DN2  @S9S_MB_2U_LIB.S9S_MB_2U(SCH_1):P5E_CPU1_PE4_TX_DN<13>
  U86  P5E_CPU1_PE4_TX_DN<12>  PE4_TX_DN3  @S9S_MB_2U_LIB.S9S_MB_2U(SCH_1):P5E_CPU1_PE4_TX_DN<12>
  W86  P5E_CPU1_PE4_TX_DN<11>  PE4_TX_DN4  @S9S_MB_2U_LIB.S9S_MB_2U(SCH_1):P5E_CPU1_PE4_TX_DN<11>
  AA86  P5E_CPU1_PE4_TX_DN<10>  PE4_TX_DN5  @S9S_MB_2U_LIB.S9S_MB_2U(SCH_1):P5E_CPU1_PE4_TX_DN<10>
  BA86  P5E_CPU1_PE4_TX_DN<0>  PE4_TX_DN15  @S9S_MB_2U_LIB.S9S_MB_2U(SCH_1):P5E_CPU1_PE4_TX_DN<0>
  AC90  P5E_CPU1_PE4_RX_DP<9>  PE4_RX_DP6  @S9S_MB_2U_LIB.S9S_MB_2U(SCH_1):P5E_CPU1_PE4_RX_DP<9>
  AE90  P5E_CPU1_PE4_RX_DP<8>  PE4_RX_DP7  @S9S_MB_2U_LIB.S9S_MB_2U(SCH_1):P5E_CPU1_PE4_RX_DP<8>
  AG90  P5E_CPU1_PE4_RX_DP<7>  PE4_RX_DP8  @S9S_MB_2U_LIB.S9S_MB_2U(SCH_1):P5E_CPU1_PE4_RX_DP<7>
  AJ90  P5E_CPU1_PE4_RX_DP<6>  PE4_RX_DP9  @S9S_MB_2U_LIB.S9S_MB_2U(SCH_1):P5E_CPU1_PE4_RX_DP<6>
  AL90  P5E_CPU1_PE4_RX_DP<5>  PE4_RX_DP10  @S9S_MB_2U_LIB.S9S_MB_2U(SCH_1):P5E_CPU1_PE4_RX_DP<5>
  AN90  P5E_CPU1_PE4_RX_DP<4>  PE4_RX_DP11  @S9S_MB_2U_LIB.S9S_MB_2U(SCH_1):P5E_CPU1_PE4_RX_DP<4>
  AR90  P5E_CPU1_PE4_RX_DP<3>  PE4_RX_DP12  @S9S_MB_2U_LIB.S9S_MB_2U(SCH_1):P5E_CPU1_PE4_RX_DP<3>
  AU90  P5E_CPU1_PE4_RX_DP<2>  PE4_RX_DP13  @S9S_MB_2U_LIB.S9S_MB_2U(SCH_1):P5E_CPU1_PE4_RX_DP<2>
  AW90  P5E_CPU1_PE4_RX_DP<1>  PE4_RX_DP14  @S9S_MB_2U_LIB.S9S_MB_2U(SCH_1):P5E_CPU1_PE4_RX_DP<1>
  K89  P5E_CPU1_PE4_RX_DP<15>  PE4_RX_DP0  @S9S_MB_2U_LIB.S9S_MB_2U(SCH_1):P5E_CPU1_PE4_RX_DP<15>
  N90  P5E_CPU1_PE4_RX_DP<14>  PE4_RX_DP1  @S9S_MB_2U_LIB.S9S_MB_2U(SCH_1):P5E_CPU1_PE4_RX_DP<14>
  R90  P5E_CPU1_PE4_RX_DP<13>  PE4_RX_DP2  @S9S_MB_2U_LIB.S9S_MB_2U(SCH_1):P5E_CPU1_PE4_RX_DP<13>
  U90  P5E_CPU1_PE4_RX_DP<12>  PE4_RX_DP3  @S9S_MB_2U_LIB.S9S_MB_2U(SCH_1):P5E_CPU1_PE4_RX_DP<12>
  W90  P5E_CPU1_PE4_RX_DP<11>  PE4_RX_DP4  @S9S_MB_2U_LIB.S9S_MB_2U(SCH_1):P5E_CPU1_PE4_RX_DP<11>
  AA90  P5E_CPU1_PE4_RX_DP<10>  PE4_RX_DP5  @S9S_MB_2U_LIB.S9S_MB_2U(SCH_1):P5E_CPU1_PE4_RX_DP<10>
  BA90  P5E_CPU1_PE4_RX_DP<0>  PE4_RX_DP15  @S9S_MB_2U_LIB.S9S_MB_2U(SCH_1):P5E_CPU1_PE4_RX_DP<0>
  AD91  P5E_CPU1_PE4_RX_DN<9>  PE4_RX_DN6  @S9S_MB_2U_LIB.S9S_MB_2U(SCH_1):P5E_CPU1_PE4_RX_DN<9>
  AF89  P5E_CPU1_PE4_RX_DN<8>  PE4_RX_DN7  @S9S_MB_2U_LIB.S9S_MB_2U(SCH_1):P5E_CPU1_PE4_RX_DN<8>
  AH91  P5E_CPU1_PE4_RX_DN<7>  PE4_RX_DN8  @S9S_MB_2U_LIB.S9S_MB_2U(SCH_1):P5E_CPU1_PE4_RX_DN<7>
  AK89  P5E_CPU1_PE4_RX_DN<6>  PE4_RX_DN9  @S9S_MB_2U_LIB.S9S_MB_2U(SCH_1):P5E_CPU1_PE4_RX_DN<6>
  AM91  P5E_CPU1_PE4_RX_DN<5>  PE4_RX_DN10  @S9S_MB_2U_LIB.S9S_MB_2U(SCH_1):P5E_CPU1_PE4_RX_DN<5>
  AP89  P5E_CPU1_PE4_RX_DN<4>  PE4_RX_DN11  @S9S_MB_2U_LIB.S9S_MB_2U(SCH_1):P5E_CPU1_PE4_RX_DN<4>
  AT91  P5E_CPU1_PE4_RX_DN<3>  PE4_RX_DN12  @S9S_MB_2U_LIB.S9S_MB_2U(SCH_1):P5E_CPU1_PE4_RX_DN<3>
  AV89  P5E_CPU1_PE4_RX_DN<2>  PE4_RX_DN13  @S9S_MB_2U_LIB.S9S_MB_2U(SCH_1):P5E_CPU1_PE4_RX_DN<2>
  AY91  P5E_CPU1_PE4_RX_DN<1>  PE4_RX_DN14  @S9S_MB_2U_LIB.S9S_MB_2U(SCH_1):P5E_CPU1_PE4_RX_DN<1>
  J90  P5E_CPU1_PE4_RX_DN<15>  PE4_RX_DN0  @S9S_MB_2U_LIB.S9S_MB_2U(SCH_1):P5E_CPU1_PE4_RX_DN<15>
  P89  P5E_CPU1_PE4_RX_DN<14>  PE4_RX_DN1  @S9S_MB_2U_LIB.S9S_MB_2U(SCH_1):P5E_CPU1_PE4_RX_DN<14>
  T91  P5E_CPU1_PE4_RX_DN<13>  PE4_RX_DN2  @S9S_MB_2U_LIB.S9S_MB_2U(SCH_1):P5E_CPU1_PE4_RX_DN<13>
  V89  P5E_CPU1_PE4_RX_DN<12>  PE4_RX_DN3  @S9S_MB_2U_LIB.S9S_MB_2U(SCH_1):P5E_CPU1_PE4_RX_DN<12>
  Y91  P5E_CPU1_PE4_RX_DN<11>  PE4_RX_DN4  @S9S_MB_2U_LIB.S9S_MB_2U(SCH_1):P5E_CPU1_PE4_RX_DN<11>
  AB89  P5E_CPU1_PE4_RX_DN<10>  PE4_RX_DN5  @S9S_MB_2U_LIB.S9S_MB_2U(SCH_1):P5E_CPU1_PE4_RX_DN<10>
  BB89  P5E_CPU1_PE4_RX_DN<0>  PE4_RX_DN15  @S9S_MB_2U_LIB.S9S_MB_2U(SCH_1):P5E_CPU1_PE4_RX_DN<0>

SOCKET4677_AZIFS054P001C01  I12  U1     [SOCKET4677_AZIFS054P001C01-SOCA]
  DG86  P5E_CPU1_PE3_TX_DP<9>  PE3_TX_DP9  @S9S_MB_2U_LIB.S9S_MB_2U(SCH_1):P5E_CPU1_PE3_TX_DP<9>
  DJ86  P5E_CPU1_PE3_TX_DP<8>  PE3_TX_DP8  @S9S_MB_2U_LIB.S9S_MB_2U(SCH_1):P5E_CPU1_PE3_TX_DP<8>
  DL86  P5E_CPU1_PE3_TX_DP<7>  PE3_TX_DP7  @S9S_MB_2U_LIB.S9S_MB_2U(SCH_1):P5E_CPU1_PE3_TX_DP<7>
  DN86  P5E_CPU1_PE3_TX_DP<6>  PE3_TX_DP6  @S9S_MB_2U_LIB.S9S_MB_2U(SCH_1):P5E_CPU1_PE3_TX_DP<6>
  DR86  P5E_CPU1_PE3_TX_DP<5>  PE3_TX_DP5  @S9S_MB_2U_LIB.S9S_MB_2U(SCH_1):P5E_CPU1_PE3_TX_DP<5>
  DU86  P5E_CPU1_PE3_TX_DP<4>  PE3_TX_DP4  @S9S_MB_2U_LIB.S9S_MB_2U(SCH_1):P5E_CPU1_PE3_TX_DP<4>
  DW86  P5E_CPU1_PE3_TX_DP<3>  PE3_TX_DP3  @S9S_MB_2U_LIB.S9S_MB_2U(SCH_1):P5E_CPU1_PE3_TX_DP<3>
  EA86  P5E_CPU1_PE3_TX_DP<2>  PE3_TX_DP2  @S9S_MB_2U_LIB.S9S_MB_2U(SCH_1):P5E_CPU1_PE3_TX_DP<2>
  EC86  P5E_CPU1_PE3_TX_DP<1>  PE3_TX_DP1  @S9S_MB_2U_LIB.S9S_MB_2U(SCH_1):P5E_CPU1_PE3_TX_DP<1>
  CR86  P5E_CPU1_PE3_TX_DP<15>  PE3_TX_DP15  @S9S_MB_2U_LIB.S9S_MB_2U(SCH_1):P5E_CPU1_PE3_TX_DP<15>
  CU86  P5E_CPU1_PE3_TX_DP<14>  PE3_TX_DP14  @S9S_MB_2U_LIB.S9S_MB_2U(SCH_1):P5E_CPU1_PE3_TX_DP<14>
  CW86  P5E_CPU1_PE3_TX_DP<13>  PE3_TX_DP13  @S9S_MB_2U_LIB.S9S_MB_2U(SCH_1):P5E_CPU1_PE3_TX_DP<13>
  DA86  P5E_CPU1_PE3_TX_DP<12>  PE3_TX_DP12  @S9S_MB_2U_LIB.S9S_MB_2U(SCH_1):P5E_CPU1_PE3_TX_DP<12>
  DC86  P5E_CPU1_PE3_TX_DP<11>  PE3_TX_DP11  @S9S_MB_2U_LIB.S9S_MB_2U(SCH_1):P5E_CPU1_PE3_TX_DP<11>
  DE86  P5E_CPU1_PE3_TX_DP<10>  PE3_TX_DP10  @S9S_MB_2U_LIB.S9S_MB_2U(SCH_1):P5E_CPU1_PE3_TX_DP<10>
  ED87  P5E_CPU1_PE3_TX_DP<0>  PE3_TX_DP0  @S9S_MB_2U_LIB.S9S_MB_2U(SCH_1):P5E_CPU1_PE3_TX_DP<0>
  DF85  P5E_CPU1_PE3_TX_DN<9>  PE3_TX_DN9  @S9S_MB_2U_LIB.S9S_MB_2U(SCH_1):P5E_CPU1_PE3_TX_DN<9>
  DH87  P5E_CPU1_PE3_TX_DN<8>  PE3_TX_DN8  @S9S_MB_2U_LIB.S9S_MB_2U(SCH_1):P5E_CPU1_PE3_TX_DN<8>
  DK85  P5E_CPU1_PE3_TX_DN<7>  PE3_TX_DN7  @S9S_MB_2U_LIB.S9S_MB_2U(SCH_1):P5E_CPU1_PE3_TX_DN<7>
  DM87  P5E_CPU1_PE3_TX_DN<6>  PE3_TX_DN6  @S9S_MB_2U_LIB.S9S_MB_2U(SCH_1):P5E_CPU1_PE3_TX_DN<6>
  DP85  P5E_CPU1_PE3_TX_DN<5>  PE3_TX_DN5  @S9S_MB_2U_LIB.S9S_MB_2U(SCH_1):P5E_CPU1_PE3_TX_DN<5>
  DT87  P5E_CPU1_PE3_TX_DN<4>  PE3_TX_DN4  @S9S_MB_2U_LIB.S9S_MB_2U(SCH_1):P5E_CPU1_PE3_TX_DN<4>
  DV85  P5E_CPU1_PE3_TX_DN<3>  PE3_TX_DN3  @S9S_MB_2U_LIB.S9S_MB_2U(SCH_1):P5E_CPU1_PE3_TX_DN<3>
  DY87  P5E_CPU1_PE3_TX_DN<2>  PE3_TX_DN2  @S9S_MB_2U_LIB.S9S_MB_2U(SCH_1):P5E_CPU1_PE3_TX_DN<2>
  EB85  P5E_CPU1_PE3_TX_DN<1>  PE3_TX_DN1  @S9S_MB_2U_LIB.S9S_MB_2U(SCH_1):P5E_CPU1_PE3_TX_DN<1>
  CP85  P5E_CPU1_PE3_TX_DN<15>  PE3_TX_DN15  @S9S_MB_2U_LIB.S9S_MB_2U(SCH_1):P5E_CPU1_PE3_TX_DN<15>
  CT87  P5E_CPU1_PE3_TX_DN<14>  PE3_TX_DN14  @S9S_MB_2U_LIB.S9S_MB_2U(SCH_1):P5E_CPU1_PE3_TX_DN<14>
  CV85  P5E_CPU1_PE3_TX_DN<13>  PE3_TX_DN13  @S9S_MB_2U_LIB.S9S_MB_2U(SCH_1):P5E_CPU1_PE3_TX_DN<13>
  CY87  P5E_CPU1_PE3_TX_DN<12>  PE3_TX_DN12  @S9S_MB_2U_LIB.S9S_MB_2U(SCH_1):P5E_CPU1_PE3_TX_DN<12>
  DB85  P5E_CPU1_PE3_TX_DN<11>  PE3_TX_DN11  @S9S_MB_2U_LIB.S9S_MB_2U(SCH_1):P5E_CPU1_PE3_TX_DN<11>
  DD87  P5E_CPU1_PE3_TX_DN<10>  PE3_TX_DN10  @S9S_MB_2U_LIB.S9S_MB_2U(SCH_1):P5E_CPU1_PE3_TX_DN<10>
  EE86  P5E_CPU1_PE3_TX_DN<0>  PE3_TX_DN0  @S9S_MB_2U_LIB.S9S_MB_2U(SCH_1):P5E_CPU1_PE3_TX_DN<0>
  DJ90  P5E_CPU1_PE3_RX_DP<9>  PE3_RX_DP9  @S9S_MB_2U_LIB.S9S_MB_2U(SCH_1):P5E_CPU1_PE3_RX_DP<9>
  DK89  P5E_CPU1_PE3_RX_DP<8>  PE3_RX_DP8  @S9S_MB_2U_LIB.S9S_MB_2U(SCH_1):P5E_CPU1_PE3_RX_DP<8>
  DM91  P5E_CPU1_PE3_RX_DP<7>  PE3_RX_DP7  @S9S_MB_2U_LIB.S9S_MB_2U(SCH_1):P5E_CPU1_PE3_RX_DP<7>
  DR90  P5E_CPU1_PE3_RX_DP<6>  PE3_RX_DP6  @S9S_MB_2U_LIB.S9S_MB_2U(SCH_1):P5E_CPU1_PE3_RX_DP<6>
  DT91  P5E_CPU1_PE3_RX_DP<5>  PE3_RX_DP5  @S9S_MB_2U_LIB.S9S_MB_2U(SCH_1):P5E_CPU1_PE3_RX_DP<5>
  DW90  P5E_CPU1_PE3_RX_DP<4>  PE3_RX_DP4  @S9S_MB_2U_LIB.S9S_MB_2U(SCH_1):P5E_CPU1_PE3_RX_DP<4>
  EA90  P5E_CPU1_PE3_RX_DP<3>  PE3_RX_DP3  @S9S_MB_2U_LIB.S9S_MB_2U(SCH_1):P5E_CPU1_PE3_RX_DP<3>
  EB89  P5E_CPU1_PE3_RX_DP<2>  PE3_RX_DP2  @S9S_MB_2U_LIB.S9S_MB_2U(SCH_1):P5E_CPU1_PE3_RX_DP<2>
  EE90  P5E_CPU1_PE3_RX_DP<1>  PE3_RX_DP1  @S9S_MB_2U_LIB.S9S_MB_2U(SCH_1):P5E_CPU1_PE3_RX_DP<1>
  CT91  P5E_CPU1_PE3_RX_DP<15>  PE3_RX_DP15  @S9S_MB_2U_LIB.S9S_MB_2U(SCH_1):P5E_CPU1_PE3_RX_DP<15>
  CW90  P5E_CPU1_PE3_RX_DP<14>  PE3_RX_DP14  @S9S_MB_2U_LIB.S9S_MB_2U(SCH_1):P5E_CPU1_PE3_RX_DP<14>
  CY91  P5E_CPU1_PE3_RX_DP<13>  PE3_RX_DP13  @S9S_MB_2U_LIB.S9S_MB_2U(SCH_1):P5E_CPU1_PE3_RX_DP<13>
  DC90  P5E_CPU1_PE3_RX_DP<12>  PE3_RX_DP12  @S9S_MB_2U_LIB.S9S_MB_2U(SCH_1):P5E_CPU1_PE3_RX_DP<12>
  DE90  P5E_CPU1_PE3_RX_DP<11>  PE3_RX_DP11  @S9S_MB_2U_LIB.S9S_MB_2U(SCH_1):P5E_CPU1_PE3_RX_DP<11>
  DF89  P5E_CPU1_PE3_RX_DP<10>  PE3_RX_DP10  @S9S_MB_2U_LIB.S9S_MB_2U(SCH_1):P5E_CPU1_PE3_RX_DP<10>
  EJ90  P5E_CPU1_PE3_RX_DP<0>  PE3_RX_DP0  @S9S_MB_2U_LIB.S9S_MB_2U(SCH_1):P5E_CPU1_PE3_RX_DP<0>
  DH91  P5E_CPU1_PE3_RX_DN<9>  PE3_RX_DN9  @S9S_MB_2U_LIB.S9S_MB_2U(SCH_1):P5E_CPU1_PE3_RX_DN<9>
  DL90  P5E_CPU1_PE3_RX_DN<8>  PE3_RX_DN8  @S9S_MB_2U_LIB.S9S_MB_2U(SCH_1):P5E_CPU1_PE3_RX_DN<8>
  DN90  P5E_CPU1_PE3_RX_DN<7>  PE3_RX_DN7  @S9S_MB_2U_LIB.S9S_MB_2U(SCH_1):P5E_CPU1_PE3_RX_DN<7>
  DP89  P5E_CPU1_PE3_RX_DN<6>  PE3_RX_DN6  @S9S_MB_2U_LIB.S9S_MB_2U(SCH_1):P5E_CPU1_PE3_RX_DN<6>
  DU90  P5E_CPU1_PE3_RX_DN<5>  PE3_RX_DN5  @S9S_MB_2U_LIB.S9S_MB_2U(SCH_1):P5E_CPU1_PE3_RX_DN<5>
  DV89  P5E_CPU1_PE3_RX_DN<4>  PE3_RX_DN4  @S9S_MB_2U_LIB.S9S_MB_2U(SCH_1):P5E_CPU1_PE3_RX_DN<4>
  DY91  P5E_CPU1_PE3_RX_DN<3>  PE3_RX_DN3  @S9S_MB_2U_LIB.S9S_MB_2U(SCH_1):P5E_CPU1_PE3_RX_DN<3>
  EC90  P5E_CPU1_PE3_RX_DN<2>  PE3_RX_DN2  @S9S_MB_2U_LIB.S9S_MB_2U(SCH_1):P5E_CPU1_PE3_RX_DN<2>
  ED91  P5E_CPU1_PE3_RX_DN<1>  PE3_RX_DN1  @S9S_MB_2U_LIB.S9S_MB_2U(SCH_1):P5E_CPU1_PE3_RX_DN<1>
  CU90  P5E_CPU1_PE3_RX_DN<15>  PE3_RX_DN15  @S9S_MB_2U_LIB.S9S_MB_2U(SCH_1):P5E_CPU1_PE3_RX_DN<15>
  CV89  P5E_CPU1_PE3_RX_DN<14>  PE3_RX_DN14  @S9S_MB_2U_LIB.S9S_MB_2U(SCH_1):P5E_CPU1_PE3_RX_DN<14>
  DA90  P5E_CPU1_PE3_RX_DN<13>  PE3_RX_DN13  @S9S_MB_2U_LIB.S9S_MB_2U(SCH_1):P5E_CPU1_PE3_RX_DN<13>
  DB89  P5E_CPU1_PE3_RX_DN<12>  PE3_RX_DN12  @S9S_MB_2U_LIB.S9S_MB_2U(SCH_1):P5E_CPU1_PE3_RX_DN<12>
  DD91  P5E_CPU1_PE3_RX_DN<11>  PE3_RX_DN11  @S9S_MB_2U_LIB.S9S_MB_2U(SCH_1):P5E_CPU1_PE3_RX_DN<11>
  DG90  P5E_CPU1_PE3_RX_DN<10>  PE3_RX_DN10  @S9S_MB_2U_LIB.S9S_MB_2U(SCH_1):P5E_CPU1_PE3_RX_DN<10>
  EH89  P5E_CPU1_PE3_RX_DN<0>  PE3_RX_DN0  @S9S_MB_2U_LIB.S9S_MB_2U(SCH_1):P5E_CPU1_PE3_RX_DN<0>

SOCKET4677_AZIFS054P001C01  I54  U1     [SOCKET4677_AZIFS054P001C01-SOCA]
  DR15  P5E_CPU1_PE2_TX_DP<9>  PE2_TX_DP9  @S9S_MB_2U_LIB.S9S_MB_2U(SCH_1):P5E_CPU1_PE2_TX_DP<9>
  DM14  P5E_CPU1_PE2_TX_DP<8>  PE2_TX_DP8  @S9S_MB_2U_LIB.S9S_MB_2U(SCH_1):P5E_CPU1_PE2_TX_DP<8>
  DL15  P5E_CPU1_PE2_TX_DP<7>  PE2_TX_DP7  @S9S_MB_2U_LIB.S9S_MB_2U(SCH_1):P5E_CPU1_PE2_TX_DP<7>
  DH14  P5E_CPU1_PE2_TX_DP<6>  PE2_TX_DP6  @S9S_MB_2U_LIB.S9S_MB_2U(SCH_1):P5E_CPU1_PE2_TX_DP<6>
  DG15  P5E_CPU1_PE2_TX_DP<5>  PE2_TX_DP5  @S9S_MB_2U_LIB.S9S_MB_2U(SCH_1):P5E_CPU1_PE2_TX_DP<5>
  DD14  P5E_CPU1_PE2_TX_DP<4>  PE2_TX_DP4  @S9S_MB_2U_LIB.S9S_MB_2U(SCH_1):P5E_CPU1_PE2_TX_DP<4>
  DC15  P5E_CPU1_PE2_TX_DP<3>  PE2_TX_DP3  @S9S_MB_2U_LIB.S9S_MB_2U(SCH_1):P5E_CPU1_PE2_TX_DP<3>
  CY14  P5E_CPU1_PE2_TX_DP<2>  PE2_TX_DP2  @S9S_MB_2U_LIB.S9S_MB_2U(SCH_1):P5E_CPU1_PE2_TX_DP<2>
  CW15  P5E_CPU1_PE2_TX_DP<1>  PE2_TX_DP1  @S9S_MB_2U_LIB.S9S_MB_2U(SCH_1):P5E_CPU1_PE2_TX_DP<1>
  EG15  P5E_CPU1_PE2_TX_DP<15>  PE2_TX_DP15  @S9S_MB_2U_LIB.S9S_MB_2U(SCH_1):P5E_CPU1_PE2_TX_DP<15>
  ED14  P5E_CPU1_PE2_TX_DP<14>  PE2_TX_DP14  @S9S_MB_2U_LIB.S9S_MB_2U(SCH_1):P5E_CPU1_PE2_TX_DP<14>
  EC15  P5E_CPU1_PE2_TX_DP<13>  PE2_TX_DP13  @S9S_MB_2U_LIB.S9S_MB_2U(SCH_1):P5E_CPU1_PE2_TX_DP<13>
  DY14  P5E_CPU1_PE2_TX_DP<12>  PE2_TX_DP12  @S9S_MB_2U_LIB.S9S_MB_2U(SCH_1):P5E_CPU1_PE2_TX_DP<12>
  DW15  P5E_CPU1_PE2_TX_DP<11>  PE2_TX_DP11  @S9S_MB_2U_LIB.S9S_MB_2U(SCH_1):P5E_CPU1_PE2_TX_DP<11>
  DT14  P5E_CPU1_PE2_TX_DP<10>  PE2_TX_DP10  @S9S_MB_2U_LIB.S9S_MB_2U(SCH_1):P5E_CPU1_PE2_TX_DP<10>
  CT14  P5E_CPU1_PE2_TX_DP<0>  PE2_TX_DP0  @S9S_MB_2U_LIB.S9S_MB_2U(SCH_1):P5E_CPU1_PE2_TX_DP<0>
  DP14  P5E_CPU1_PE2_TX_DN<9>  PE2_TX_DN9  @S9S_MB_2U_LIB.S9S_MB_2U(SCH_1):P5E_CPU1_PE2_TX_DN<9>
  DN13  P5E_CPU1_PE2_TX_DN<8>  PE2_TX_DN8  @S9S_MB_2U_LIB.S9S_MB_2U(SCH_1):P5E_CPU1_PE2_TX_DN<8>
  DK14  P5E_CPU1_PE2_TX_DN<7>  PE2_TX_DN7  @S9S_MB_2U_LIB.S9S_MB_2U(SCH_1):P5E_CPU1_PE2_TX_DN<7>
  DJ13  P5E_CPU1_PE2_TX_DN<6>  PE2_TX_DN6  @S9S_MB_2U_LIB.S9S_MB_2U(SCH_1):P5E_CPU1_PE2_TX_DN<6>
  DF14  P5E_CPU1_PE2_TX_DN<5>  PE2_TX_DN5  @S9S_MB_2U_LIB.S9S_MB_2U(SCH_1):P5E_CPU1_PE2_TX_DN<5>
  DE13  P5E_CPU1_PE2_TX_DN<4>  PE2_TX_DN4  @S9S_MB_2U_LIB.S9S_MB_2U(SCH_1):P5E_CPU1_PE2_TX_DN<4>
  DB14  P5E_CPU1_PE2_TX_DN<3>  PE2_TX_DN3  @S9S_MB_2U_LIB.S9S_MB_2U(SCH_1):P5E_CPU1_PE2_TX_DN<3>
  DA13  P5E_CPU1_PE2_TX_DN<2>  PE2_TX_DN2  @S9S_MB_2U_LIB.S9S_MB_2U(SCH_1):P5E_CPU1_PE2_TX_DN<2>
  CV14  P5E_CPU1_PE2_TX_DN<1>  PE2_TX_DN1  @S9S_MB_2U_LIB.S9S_MB_2U(SCH_1):P5E_CPU1_PE2_TX_DN<1>
  EF14  P5E_CPU1_PE2_TX_DN<15>  PE2_TX_DN15  @S9S_MB_2U_LIB.S9S_MB_2U(SCH_1):P5E_CPU1_PE2_TX_DN<15>
  EE13  P5E_CPU1_PE2_TX_DN<14>  PE2_TX_DN14  @S9S_MB_2U_LIB.S9S_MB_2U(SCH_1):P5E_CPU1_PE2_TX_DN<14>
  EB14  P5E_CPU1_PE2_TX_DN<13>  PE2_TX_DN13  @S9S_MB_2U_LIB.S9S_MB_2U(SCH_1):P5E_CPU1_PE2_TX_DN<13>
  EA13  P5E_CPU1_PE2_TX_DN<12>  PE2_TX_DN12  @S9S_MB_2U_LIB.S9S_MB_2U(SCH_1):P5E_CPU1_PE2_TX_DN<12>
  DV14  P5E_CPU1_PE2_TX_DN<11>  PE2_TX_DN11  @S9S_MB_2U_LIB.S9S_MB_2U(SCH_1):P5E_CPU1_PE2_TX_DN<11>
  DU13  P5E_CPU1_PE2_TX_DN<10>  PE2_TX_DN10  @S9S_MB_2U_LIB.S9S_MB_2U(SCH_1):P5E_CPU1_PE2_TX_DN<10>
  CU13  P5E_CPU1_PE2_TX_DN<0>  PE2_TX_DN0  @S9S_MB_2U_LIB.S9S_MB_2U(SCH_1):P5E_CPU1_PE2_TX_DN<0>
  DR11  P5E_CPU1_PE2_RX_DP<9>  PE2_RX_DP9  @S9S_MB_2U_LIB.S9S_MB_2U(SCH_1):P5E_CPU1_PE2_RX_DP<9>
  DP10  P5E_CPU1_PE2_RX_DP<8>  PE2_RX_DP8  @S9S_MB_2U_LIB.S9S_MB_2U(SCH_1):P5E_CPU1_PE2_RX_DP<8>
  DL11  P5E_CPU1_PE2_RX_DP<7>  PE2_RX_DP7  @S9S_MB_2U_LIB.S9S_MB_2U(SCH_1):P5E_CPU1_PE2_RX_DP<7>
  DK10  P5E_CPU1_PE2_RX_DP<6>  PE2_RX_DP6  @S9S_MB_2U_LIB.S9S_MB_2U(SCH_1):P5E_CPU1_PE2_RX_DP<6>
  DG11  P5E_CPU1_PE2_RX_DP<5>  PE2_RX_DP5  @S9S_MB_2U_LIB.S9S_MB_2U(SCH_1):P5E_CPU1_PE2_RX_DP<5>
  DF10  P5E_CPU1_PE2_RX_DP<4>  PE2_RX_DP4  @S9S_MB_2U_LIB.S9S_MB_2U(SCH_1):P5E_CPU1_PE2_RX_DP<4>
  DC11  P5E_CPU1_PE2_RX_DP<3>  PE2_RX_DP3  @S9S_MB_2U_LIB.S9S_MB_2U(SCH_1):P5E_CPU1_PE2_RX_DP<3>
  DB10  P5E_CPU1_PE2_RX_DP<2>  PE2_RX_DP2  @S9S_MB_2U_LIB.S9S_MB_2U(SCH_1):P5E_CPU1_PE2_RX_DP<2>
  CW11  P5E_CPU1_PE2_RX_DP<1>  PE2_RX_DP1  @S9S_MB_2U_LIB.S9S_MB_2U(SCH_1):P5E_CPU1_PE2_RX_DP<1>
  EG11  P5E_CPU1_PE2_RX_DP<15>  PE2_RX_DP15  @S9S_MB_2U_LIB.S9S_MB_2U(SCH_1):P5E_CPU1_PE2_RX_DP<15>
  EF10  P5E_CPU1_PE2_RX_DP<14>  PE2_RX_DP14  @S9S_MB_2U_LIB.S9S_MB_2U(SCH_1):P5E_CPU1_PE2_RX_DP<14>
  EC11  P5E_CPU1_PE2_RX_DP<13>  PE2_RX_DP13  @S9S_MB_2U_LIB.S9S_MB_2U(SCH_1):P5E_CPU1_PE2_RX_DP<13>
  EB10  P5E_CPU1_PE2_RX_DP<12>  PE2_RX_DP12  @S9S_MB_2U_LIB.S9S_MB_2U(SCH_1):P5E_CPU1_PE2_RX_DP<12>
  DW11  P5E_CPU1_PE2_RX_DP<11>  PE2_RX_DP11  @S9S_MB_2U_LIB.S9S_MB_2U(SCH_1):P5E_CPU1_PE2_RX_DP<11>
  DV10  P5E_CPU1_PE2_RX_DP<10>  PE2_RX_DP10  @S9S_MB_2U_LIB.S9S_MB_2U(SCH_1):P5E_CPU1_PE2_RX_DP<10>
  CV10  P5E_CPU1_PE2_RX_DP<0>  PE2_RX_DP0  @S9S_MB_2U_LIB.S9S_MB_2U(SCH_1):P5E_CPU1_PE2_RX_DP<0>
  DT10  P5E_CPU1_PE2_RX_DN<9>  PE2_RX_DN9  @S9S_MB_2U_LIB.S9S_MB_2U(SCH_1):P5E_CPU1_PE2_RX_DN<9>
  DN9  P5E_CPU1_PE2_RX_DN<8>  PE2_RX_DN8  @S9S_MB_2U_LIB.S9S_MB_2U(SCH_1):P5E_CPU1_PE2_RX_DN<8>
  DM10  P5E_CPU1_PE2_RX_DN<7>  PE2_RX_DN7  @S9S_MB_2U_LIB.S9S_MB_2U(SCH_1):P5E_CPU1_PE2_RX_DN<7>
  DJ9  P5E_CPU1_PE2_RX_DN<6>  PE2_RX_DN6  @S9S_MB_2U_LIB.S9S_MB_2U(SCH_1):P5E_CPU1_PE2_RX_DN<6>
  DH10  P5E_CPU1_PE2_RX_DN<5>  PE2_RX_DN5  @S9S_MB_2U_LIB.S9S_MB_2U(SCH_1):P5E_CPU1_PE2_RX_DN<5>
  DE9  P5E_CPU1_PE2_RX_DN<4>  PE2_RX_DN4  @S9S_MB_2U_LIB.S9S_MB_2U(SCH_1):P5E_CPU1_PE2_RX_DN<4>
  DD10  P5E_CPU1_PE2_RX_DN<3>  PE2_RX_DN3  @S9S_MB_2U_LIB.S9S_MB_2U(SCH_1):P5E_CPU1_PE2_RX_DN<3>
  DA9  P5E_CPU1_PE2_RX_DN<2>  PE2_RX_DN2  @S9S_MB_2U_LIB.S9S_MB_2U(SCH_1):P5E_CPU1_PE2_RX_DN<2>
  CY10  P5E_CPU1_PE2_RX_DN<1>  PE2_RX_DN1  @S9S_MB_2U_LIB.S9S_MB_2U(SCH_1):P5E_CPU1_PE2_RX_DN<1>
  EH10  P5E_CPU1_PE2_RX_DN<15>  PE2_RX_DN15  @S9S_MB_2U_LIB.S9S_MB_2U(SCH_1):P5E_CPU1_PE2_RX_DN<15>
  EE9  P5E_CPU1_PE2_RX_DN<14>  PE2_RX_DN14  @S9S_MB_2U_LIB.S9S_MB_2U(SCH_1):P5E_CPU1_PE2_RX_DN<14>
  ED10  P5E_CPU1_PE2_RX_DN<13>  PE2_RX_DN13  @S9S_MB_2U_LIB.S9S_MB_2U(SCH_1):P5E_CPU1_PE2_RX_DN<13>
  EA9  P5E_CPU1_PE2_RX_DN<12>  PE2_RX_DN12  @S9S_MB_2U_LIB.S9S_MB_2U(SCH_1):P5E_CPU1_PE2_RX_DN<12>
  DY10  P5E_CPU1_PE2_RX_DN<11>  PE2_RX_DN11  @S9S_MB_2U_LIB.S9S_MB_2U(SCH_1):P5E_CPU1_PE2_RX_DN<11>
  DU9  P5E_CPU1_PE2_RX_DN<10>  PE2_RX_DN10  @S9S_MB_2U_LIB.S9S_MB_2U(SCH_1):P5E_CPU1_PE2_RX_DN<10>
  CU9  P5E_CPU1_PE2_RX_DN<0>  PE2_RX_DN0  @S9S_MB_2U_LIB.S9S_MB_2U(SCH_1):P5E_CPU1_PE2_RX_DN<0>

SOCKET4677_AZIFS054P001C01  I69  U1     [SOCKET4677_AZIFS054P001C01-SOCA]
  CC15  P5E_CPU1_PE1_TX_DP<9>  PE1_TX_DP6  @S9S_MB_2U_LIB.S9S_MB_2U(SCH_1):P5E_CPU1_PE1_TX_DP<9>
  BY14  P5E_CPU1_PE1_TX_DP<8>  PE1_TX_DP7  @S9S_MB_2U_LIB.S9S_MB_2U(SCH_1):P5E_CPU1_PE1_TX_DP<8>
  BW15  P5E_CPU1_PE1_TX_DP<7>  PE1_TX_DP8  @S9S_MB_2U_LIB.S9S_MB_2U(SCH_1):P5E_CPU1_PE1_TX_DP<7>
  BT14  P5E_CPU1_PE1_TX_DP<6>  PE1_TX_DP9  @S9S_MB_2U_LIB.S9S_MB_2U(SCH_1):P5E_CPU1_PE1_TX_DP<6>
  BR15  P5E_CPU1_PE1_TX_DP<5>  PE1_TX_DP10  @S9S_MB_2U_LIB.S9S_MB_2U(SCH_1):P5E_CPU1_PE1_TX_DP<5>
  BM14  P5E_CPU1_PE1_TX_DP<4>  PE1_TX_DP11  @S9S_MB_2U_LIB.S9S_MB_2U(SCH_1):P5E_CPU1_PE1_TX_DP<4>
  BL15  P5E_CPU1_PE1_TX_DP<3>  PE1_TX_DP12  @S9S_MB_2U_LIB.S9S_MB_2U(SCH_1):P5E_CPU1_PE1_TX_DP<3>
  BH14  P5E_CPU1_PE1_TX_DP<2>  PE1_TX_DP13  @S9S_MB_2U_LIB.S9S_MB_2U(SCH_1):P5E_CPU1_PE1_TX_DP<2>
  BG15  P5E_CPU1_PE1_TX_DP<1>  PE1_TX_DP14  @S9S_MB_2U_LIB.S9S_MB_2U(SCH_1):P5E_CPU1_PE1_TX_DP<1>
  CR15  P5E_CPU1_PE1_TX_DP<15>  PE1_TX_DP0  @S9S_MB_2U_LIB.S9S_MB_2U(SCH_1):P5E_CPU1_PE1_TX_DP<15>
  CM14  P5E_CPU1_PE1_TX_DP<14>  PE1_TX_DP1  @S9S_MB_2U_LIB.S9S_MB_2U(SCH_1):P5E_CPU1_PE1_TX_DP<14>
  CL15  P5E_CPU1_PE1_TX_DP<13>  PE1_TX_DP2  @S9S_MB_2U_LIB.S9S_MB_2U(SCH_1):P5E_CPU1_PE1_TX_DP<13>
  CH14  P5E_CPU1_PE1_TX_DP<12>  PE1_TX_DP3  @S9S_MB_2U_LIB.S9S_MB_2U(SCH_1):P5E_CPU1_PE1_TX_DP<12>
  CG15  P5E_CPU1_PE1_TX_DP<11>  PE1_TX_DP4  @S9S_MB_2U_LIB.S9S_MB_2U(SCH_1):P5E_CPU1_PE1_TX_DP<11>
  CD14  P5E_CPU1_PE1_TX_DP<10>  PE1_TX_DP5  @S9S_MB_2U_LIB.S9S_MB_2U(SCH_1):P5E_CPU1_PE1_TX_DP<10>
  BD14  P5E_CPU1_PE1_TX_DP<0>  PE1_TX_DP15  @S9S_MB_2U_LIB.S9S_MB_2U(SCH_1):P5E_CPU1_PE1_TX_DP<0>
  CB14  P5E_CPU1_PE1_TX_DN<9>  PE1_TX_DN6  @S9S_MB_2U_LIB.S9S_MB_2U(SCH_1):P5E_CPU1_PE1_TX_DN<9>
  CA13  P5E_CPU1_PE1_TX_DN<8>  PE1_TX_DN7  @S9S_MB_2U_LIB.S9S_MB_2U(SCH_1):P5E_CPU1_PE1_TX_DN<8>
  BV14  P5E_CPU1_PE1_TX_DN<7>  PE1_TX_DN8  @S9S_MB_2U_LIB.S9S_MB_2U(SCH_1):P5E_CPU1_PE1_TX_DN<7>
  BU13  P5E_CPU1_PE1_TX_DN<6>  PE1_TX_DN9  @S9S_MB_2U_LIB.S9S_MB_2U(SCH_1):P5E_CPU1_PE1_TX_DN<6>
  BP14  P5E_CPU1_PE1_TX_DN<5>  PE1_TX_DN10  @S9S_MB_2U_LIB.S9S_MB_2U(SCH_1):P5E_CPU1_PE1_TX_DN<5>
  BN13  P5E_CPU1_PE1_TX_DN<4>  PE1_TX_DN11  @S9S_MB_2U_LIB.S9S_MB_2U(SCH_1):P5E_CPU1_PE1_TX_DN<4>
  BK14  P5E_CPU1_PE1_TX_DN<3>  PE1_TX_DN12  @S9S_MB_2U_LIB.S9S_MB_2U(SCH_1):P5E_CPU1_PE1_TX_DN<3>
  BJ13  P5E_CPU1_PE1_TX_DN<2>  PE1_TX_DN13  @S9S_MB_2U_LIB.S9S_MB_2U(SCH_1):P5E_CPU1_PE1_TX_DN<2>
  BF14  P5E_CPU1_PE1_TX_DN<1>  PE1_TX_DN14  @S9S_MB_2U_LIB.S9S_MB_2U(SCH_1):P5E_CPU1_PE1_TX_DN<1>
  CP14  P5E_CPU1_PE1_TX_DN<15>  PE1_TX_DN0  @S9S_MB_2U_LIB.S9S_MB_2U(SCH_1):P5E_CPU1_PE1_TX_DN<15>
  CN13  P5E_CPU1_PE1_TX_DN<14>  PE1_TX_DN1  @S9S_MB_2U_LIB.S9S_MB_2U(SCH_1):P5E_CPU1_PE1_TX_DN<14>
  CK14  P5E_CPU1_PE1_TX_DN<13>  PE1_TX_DN2  @S9S_MB_2U_LIB.S9S_MB_2U(SCH_1):P5E_CPU1_PE1_TX_DN<13>
  CJ13  P5E_CPU1_PE1_TX_DN<12>  PE1_TX_DN3  @S9S_MB_2U_LIB.S9S_MB_2U(SCH_1):P5E_CPU1_PE1_TX_DN<12>
  CF14  P5E_CPU1_PE1_TX_DN<11>  PE1_TX_DN4  @S9S_MB_2U_LIB.S9S_MB_2U(SCH_1):P5E_CPU1_PE1_TX_DN<11>
  CE13  P5E_CPU1_PE1_TX_DN<10>  PE1_TX_DN5  @S9S_MB_2U_LIB.S9S_MB_2U(SCH_1):P5E_CPU1_PE1_TX_DN<10>
  BE13  P5E_CPU1_PE1_TX_DN<0>  PE1_TX_DN15  @S9S_MB_2U_LIB.S9S_MB_2U(SCH_1):P5E_CPU1_PE1_TX_DN<0>
  CA9  P5E_CPU1_PE1_RX_DP<9>  PE1_RX_DP6  @S9S_MB_2U_LIB.S9S_MB_2U(SCH_1):P5E_CPU1_PE1_RX_DP<9>
  BY10  P5E_CPU1_PE1_RX_DP<8>  PE1_RX_DP7  @S9S_MB_2U_LIB.S9S_MB_2U(SCH_1):P5E_CPU1_PE1_RX_DP<8>
  BU9  P5E_CPU1_PE1_RX_DP<7>  PE1_RX_DP8  @S9S_MB_2U_LIB.S9S_MB_2U(SCH_1):P5E_CPU1_PE1_RX_DP<7>
  BT10  P5E_CPU1_PE1_RX_DP<6>  PE1_RX_DP9  @S9S_MB_2U_LIB.S9S_MB_2U(SCH_1):P5E_CPU1_PE1_RX_DP<6>
  BN9  P5E_CPU1_PE1_RX_DP<5>  PE1_RX_DP10  @S9S_MB_2U_LIB.S9S_MB_2U(SCH_1):P5E_CPU1_PE1_RX_DP<5>
  BM10  P5E_CPU1_PE1_RX_DP<4>  PE1_RX_DP11  @S9S_MB_2U_LIB.S9S_MB_2U(SCH_1):P5E_CPU1_PE1_RX_DP<4>
  BJ9  P5E_CPU1_PE1_RX_DP<3>  PE1_RX_DP12  @S9S_MB_2U_LIB.S9S_MB_2U(SCH_1):P5E_CPU1_PE1_RX_DP<3>
  BH10  P5E_CPU1_PE1_RX_DP<2>  PE1_RX_DP13  @S9S_MB_2U_LIB.S9S_MB_2U(SCH_1):P5E_CPU1_PE1_RX_DP<2>
  BE9  P5E_CPU1_PE1_RX_DP<1>  PE1_RX_DP14  @S9S_MB_2U_LIB.S9S_MB_2U(SCH_1):P5E_CPU1_PE1_RX_DP<1>
  CN9  P5E_CPU1_PE1_RX_DP<15>  PE1_RX_DP0  @S9S_MB_2U_LIB.S9S_MB_2U(SCH_1):P5E_CPU1_PE1_RX_DP<15>
  CM10  P5E_CPU1_PE1_RX_DP<14>  PE1_RX_DP1  @S9S_MB_2U_LIB.S9S_MB_2U(SCH_1):P5E_CPU1_PE1_RX_DP<14>
  CJ9  P5E_CPU1_PE1_RX_DP<13>  PE1_RX_DP2  @S9S_MB_2U_LIB.S9S_MB_2U(SCH_1):P5E_CPU1_PE1_RX_DP<13>
  CH10  P5E_CPU1_PE1_RX_DP<12>  PE1_RX_DP3  @S9S_MB_2U_LIB.S9S_MB_2U(SCH_1):P5E_CPU1_PE1_RX_DP<12>
  CE9  P5E_CPU1_PE1_RX_DP<11>  PE1_RX_DP4  @S9S_MB_2U_LIB.S9S_MB_2U(SCH_1):P5E_CPU1_PE1_RX_DP<11>
  CD10  P5E_CPU1_PE1_RX_DP<10>  PE1_RX_DP5  @S9S_MB_2U_LIB.S9S_MB_2U(SCH_1):P5E_CPU1_PE1_RX_DP<10>
  BD10  P5E_CPU1_PE1_RX_DP<0>  PE1_RX_DP15  @S9S_MB_2U_LIB.S9S_MB_2U(SCH_1):P5E_CPU1_PE1_RX_DP<0>
  CB10  P5E_CPU1_PE1_RX_DN<9>  PE1_RX_DN6  @S9S_MB_2U_LIB.S9S_MB_2U(SCH_1):P5E_CPU1_PE1_RX_DN<9>
  BW11  P5E_CPU1_PE1_RX_DN<8>  PE1_RX_DN7  @S9S_MB_2U_LIB.S9S_MB_2U(SCH_1):P5E_CPU1_PE1_RX_DN<8>
  BV10  P5E_CPU1_PE1_RX_DN<7>  PE1_RX_DN8  @S9S_MB_2U_LIB.S9S_MB_2U(SCH_1):P5E_CPU1_PE1_RX_DN<7>
  BR11  P5E_CPU1_PE1_RX_DN<6>  PE1_RX_DN9  @S9S_MB_2U_LIB.S9S_MB_2U(SCH_1):P5E_CPU1_PE1_RX_DN<6>
  BP10  P5E_CPU1_PE1_RX_DN<5>  PE1_RX_DN10  @S9S_MB_2U_LIB.S9S_MB_2U(SCH_1):P5E_CPU1_PE1_RX_DN<5>
  BL11  P5E_CPU1_PE1_RX_DN<4>  PE1_RX_DN11  @S9S_MB_2U_LIB.S9S_MB_2U(SCH_1):P5E_CPU1_PE1_RX_DN<4>
  BK10  P5E_CPU1_PE1_RX_DN<3>  PE1_RX_DN12  @S9S_MB_2U_LIB.S9S_MB_2U(SCH_1):P5E_CPU1_PE1_RX_DN<3>
  BG11  P5E_CPU1_PE1_RX_DN<2>  PE1_RX_DN13  @S9S_MB_2U_LIB.S9S_MB_2U(SCH_1):P5E_CPU1_PE1_RX_DN<2>
  BF10  P5E_CPU1_PE1_RX_DN<1>  PE1_RX_DN14  @S9S_MB_2U_LIB.S9S_MB_2U(SCH_1):P5E_CPU1_PE1_RX_DN<1>
  CP10  P5E_CPU1_PE1_RX_DN<15>  PE1_RX_DN0  @S9S_MB_2U_LIB.S9S_MB_2U(SCH_1):P5E_CPU1_PE1_RX_DN<15>
  CL11  P5E_CPU1_PE1_RX_DN<14>  PE1_RX_DN1  @S9S_MB_2U_LIB.S9S_MB_2U(SCH_1):P5E_CPU1_PE1_RX_DN<14>
  CK10  P5E_CPU1_PE1_RX_DN<13>  PE1_RX_DN2  @S9S_MB_2U_LIB.S9S_MB_2U(SCH_1):P5E_CPU1_PE1_RX_DN<13>
  CG11  P5E_CPU1_PE1_RX_DN<12>  PE1_RX_DN3  @S9S_MB_2U_LIB.S9S_MB_2U(SCH_1):P5E_CPU1_PE1_RX_DN<12>
  CF10  P5E_CPU1_PE1_RX_DN<11>  PE1_RX_DN4  @S9S_MB_2U_LIB.S9S_MB_2U(SCH_1):P5E_CPU1_PE1_RX_DN<11>
  CC11  P5E_CPU1_PE1_RX_DN<10>  PE1_RX_DN5  @S9S_MB_2U_LIB.S9S_MB_2U(SCH_1):P5E_CPU1_PE1_RX_DN<10>
  BC11  P5E_CPU1_PE1_RX_DN<0>  PE1_RX_DN15  @S9S_MB_2U_LIB.S9S_MB_2U(SCH_1):P5E_CPU1_PE1_RX_DN<0>

SOCKET4677_AZIFS054P001C01  I80  U1     [SOCKET4677_AZIFS054P001C01-SOCA]
  AD14  P5E_CPU1_PE0_TX_DP<9>  PE0_TX_DP6  @S9S_MB_2U_LIB.S9S_MB_2U(SCH_1):P5E_CPU1_PE0_TX_DP<9>
  AG15  P5E_CPU1_PE0_TX_DP<8>  PE0_TX_DP7  @S9S_MB_2U_LIB.S9S_MB_2U(SCH_1):P5E_CPU1_PE0_TX_DP<8>
  AH14  P5E_CPU1_PE0_TX_DP<7>  PE0_TX_DP8  @S9S_MB_2U_LIB.S9S_MB_2U(SCH_1):P5E_CPU1_PE0_TX_DP<7>
  AL15  P5E_CPU1_PE0_TX_DP<6>  PE0_TX_DP9  @S9S_MB_2U_LIB.S9S_MB_2U(SCH_1):P5E_CPU1_PE0_TX_DP<6>
  AM14  P5E_CPU1_PE0_TX_DP<5>  PE0_TX_DP10  @S9S_MB_2U_LIB.S9S_MB_2U(SCH_1):P5E_CPU1_PE0_TX_DP<5>
  AR15  P5E_CPU1_PE0_TX_DP<4>  PE0_TX_DP11  @S9S_MB_2U_LIB.S9S_MB_2U(SCH_1):P5E_CPU1_PE0_TX_DP<4>
  AT14  P5E_CPU1_PE0_TX_DP<3>  PE0_TX_DP12  @S9S_MB_2U_LIB.S9S_MB_2U(SCH_1):P5E_CPU1_PE0_TX_DP<3>
  AW15  P5E_CPU1_PE0_TX_DP<2>  PE0_TX_DP13  @S9S_MB_2U_LIB.S9S_MB_2U(SCH_1):P5E_CPU1_PE0_TX_DP<2>
  AY14  P5E_CPU1_PE0_TX_DP<1>  PE0_TX_DP14  @S9S_MB_2U_LIB.S9S_MB_2U(SCH_1):P5E_CPU1_PE0_TX_DP<1>
  M14  P5E_CPU1_PE0_TX_DP<15>  PE0_TX_DP0  @S9S_MB_2U_LIB.S9S_MB_2U(SCH_1):P5E_CPU1_PE0_TX_DP<15>
  R15  P5E_CPU1_PE0_TX_DP<14>  PE0_TX_DP1  @S9S_MB_2U_LIB.S9S_MB_2U(SCH_1):P5E_CPU1_PE0_TX_DP<14>
  T14  P5E_CPU1_PE0_TX_DP<13>  PE0_TX_DP2  @S9S_MB_2U_LIB.S9S_MB_2U(SCH_1):P5E_CPU1_PE0_TX_DP<13>
  W15  P5E_CPU1_PE0_TX_DP<12>  PE0_TX_DP3  @S9S_MB_2U_LIB.S9S_MB_2U(SCH_1):P5E_CPU1_PE0_TX_DP<12>
  Y14  P5E_CPU1_PE0_TX_DP<11>  PE0_TX_DP4  @S9S_MB_2U_LIB.S9S_MB_2U(SCH_1):P5E_CPU1_PE0_TX_DP<11>
  AC15  P5E_CPU1_PE0_TX_DP<10>  PE0_TX_DP5  @S9S_MB_2U_LIB.S9S_MB_2U(SCH_1):P5E_CPU1_PE0_TX_DP<10>
  BC15  P5E_CPU1_PE0_TX_DP<0>  PE0_TX_DP15  @S9S_MB_2U_LIB.S9S_MB_2U(SCH_1):P5E_CPU1_PE0_TX_DP<0>
  AE13  P5E_CPU1_PE0_TX_DN<9>  PE0_TX_DN6  @S9S_MB_2U_LIB.S9S_MB_2U(SCH_1):P5E_CPU1_PE0_TX_DN<9>
  AF14  P5E_CPU1_PE0_TX_DN<8>  PE0_TX_DN7  @S9S_MB_2U_LIB.S9S_MB_2U(SCH_1):P5E_CPU1_PE0_TX_DN<8>
  AJ13  P5E_CPU1_PE0_TX_DN<7>  PE0_TX_DN8  @S9S_MB_2U_LIB.S9S_MB_2U(SCH_1):P5E_CPU1_PE0_TX_DN<7>
  AK14  P5E_CPU1_PE0_TX_DN<6>  PE0_TX_DN9  @S9S_MB_2U_LIB.S9S_MB_2U(SCH_1):P5E_CPU1_PE0_TX_DN<6>
  AN13  P5E_CPU1_PE0_TX_DN<5>  PE0_TX_DN10  @S9S_MB_2U_LIB.S9S_MB_2U(SCH_1):P5E_CPU1_PE0_TX_DN<5>
  AP14  P5E_CPU1_PE0_TX_DN<4>  PE0_TX_DN11  @S9S_MB_2U_LIB.S9S_MB_2U(SCH_1):P5E_CPU1_PE0_TX_DN<4>
  AU13  P5E_CPU1_PE0_TX_DN<3>  PE0_TX_DN12  @S9S_MB_2U_LIB.S9S_MB_2U(SCH_1):P5E_CPU1_PE0_TX_DN<3>
  AV14  P5E_CPU1_PE0_TX_DN<2>  PE0_TX_DN13  @S9S_MB_2U_LIB.S9S_MB_2U(SCH_1):P5E_CPU1_PE0_TX_DN<2>
  BA13  P5E_CPU1_PE0_TX_DN<1>  PE0_TX_DN14  @S9S_MB_2U_LIB.S9S_MB_2U(SCH_1):P5E_CPU1_PE0_TX_DN<1>
  N13  P5E_CPU1_PE0_TX_DN<15>  PE0_TX_DN0  @S9S_MB_2U_LIB.S9S_MB_2U(SCH_1):P5E_CPU1_PE0_TX_DN<15>
  P14  P5E_CPU1_PE0_TX_DN<14>  PE0_TX_DN1  @S9S_MB_2U_LIB.S9S_MB_2U(SCH_1):P5E_CPU1_PE0_TX_DN<14>
  U13  P5E_CPU1_PE0_TX_DN<13>  PE0_TX_DN2  @S9S_MB_2U_LIB.S9S_MB_2U(SCH_1):P5E_CPU1_PE0_TX_DN<13>
  V14  P5E_CPU1_PE0_TX_DN<12>  PE0_TX_DN3  @S9S_MB_2U_LIB.S9S_MB_2U(SCH_1):P5E_CPU1_PE0_TX_DN<12>
  AA13  P5E_CPU1_PE0_TX_DN<11>  PE0_TX_DN4  @S9S_MB_2U_LIB.S9S_MB_2U(SCH_1):P5E_CPU1_PE0_TX_DN<11>
  AB14  P5E_CPU1_PE0_TX_DN<10>  PE0_TX_DN5  @S9S_MB_2U_LIB.S9S_MB_2U(SCH_1):P5E_CPU1_PE0_TX_DN<10>
  BB14  P5E_CPU1_PE0_TX_DN<0>  PE0_TX_DN15  @S9S_MB_2U_LIB.S9S_MB_2U(SCH_1):P5E_CPU1_PE0_TX_DN<0>
  AC11  P5E_CPU1_PE0_RX_DP<9>  PE0_RX_DP6  @S9S_MB_2U_LIB.S9S_MB_2U(SCH_1):P5E_CPU1_PE0_RX_DP<9>
  AD10  P5E_CPU1_PE0_RX_DP<8>  PE0_RX_DP7  @S9S_MB_2U_LIB.S9S_MB_2U(SCH_1):P5E_CPU1_PE0_RX_DP<8>
  AG11  P5E_CPU1_PE0_RX_DP<7>  PE0_RX_DP8  @S9S_MB_2U_LIB.S9S_MB_2U(SCH_1):P5E_CPU1_PE0_RX_DP<7>
  AH10  P5E_CPU1_PE0_RX_DP<6>  PE0_RX_DP9  @S9S_MB_2U_LIB.S9S_MB_2U(SCH_1):P5E_CPU1_PE0_RX_DP<6>
  AL11  P5E_CPU1_PE0_RX_DP<5>  PE0_RX_DP10  @S9S_MB_2U_LIB.S9S_MB_2U(SCH_1):P5E_CPU1_PE0_RX_DP<5>
  AN9  P5E_CPU1_PE0_RX_DP<4>  PE0_RX_DP11  @S9S_MB_2U_LIB.S9S_MB_2U(SCH_1):P5E_CPU1_PE0_RX_DP<4>
  AR11  P5E_CPU1_PE0_RX_DP<3>  PE0_RX_DP12  @S9S_MB_2U_LIB.S9S_MB_2U(SCH_1):P5E_CPU1_PE0_RX_DP<3>
  AT10  P5E_CPU1_PE0_RX_DP<2>  PE0_RX_DP13  @S9S_MB_2U_LIB.S9S_MB_2U(SCH_1):P5E_CPU1_PE0_RX_DP<2>
  AW11  P5E_CPU1_PE0_RX_DP<1>  PE0_RX_DP14  @S9S_MB_2U_LIB.S9S_MB_2U(SCH_1):P5E_CPU1_PE0_RX_DP<1>
  L11  P5E_CPU1_PE0_RX_DP<15>  PE0_RX_DP0  @S9S_MB_2U_LIB.S9S_MB_2U(SCH_1):P5E_CPU1_PE0_RX_DP<15>
   N9  P5E_CPU1_PE0_RX_DP<14>  PE0_RX_DP1  @S9S_MB_2U_LIB.S9S_MB_2U(SCH_1):P5E_CPU1_PE0_RX_DP<14>
  R11  P5E_CPU1_PE0_RX_DP<13>  PE0_RX_DP2  @S9S_MB_2U_LIB.S9S_MB_2U(SCH_1):P5E_CPU1_PE0_RX_DP<13>
   U9  P5E_CPU1_PE0_RX_DP<12>  PE0_RX_DP3  @S9S_MB_2U_LIB.S9S_MB_2U(SCH_1):P5E_CPU1_PE0_RX_DP<12>
  W11  P5E_CPU1_PE0_RX_DP<11>  PE0_RX_DP4  @S9S_MB_2U_LIB.S9S_MB_2U(SCH_1):P5E_CPU1_PE0_RX_DP<11>
  Y10  P5E_CPU1_PE0_RX_DP<10>  PE0_RX_DP5  @S9S_MB_2U_LIB.S9S_MB_2U(SCH_1):P5E_CPU1_PE0_RX_DP<10>
  AY10  P5E_CPU1_PE0_RX_DP<0>  PE0_RX_DP15  @S9S_MB_2U_LIB.S9S_MB_2U(SCH_1):P5E_CPU1_PE0_RX_DP<0>
  AB10  P5E_CPU1_PE0_RX_DN<9>  PE0_RX_DN6  @S9S_MB_2U_LIB.S9S_MB_2U(SCH_1):P5E_CPU1_PE0_RX_DN<9>
  AE9  P5E_CPU1_PE0_RX_DN<8>  PE0_RX_DN7  @S9S_MB_2U_LIB.S9S_MB_2U(SCH_1):P5E_CPU1_PE0_RX_DN<8>
  AF10  P5E_CPU1_PE0_RX_DN<7>  PE0_RX_DN8  @S9S_MB_2U_LIB.S9S_MB_2U(SCH_1):P5E_CPU1_PE0_RX_DN<7>
  AJ9  P5E_CPU1_PE0_RX_DN<6>  PE0_RX_DN9  @S9S_MB_2U_LIB.S9S_MB_2U(SCH_1):P5E_CPU1_PE0_RX_DN<6>
  AK10  P5E_CPU1_PE0_RX_DN<5>  PE0_RX_DN10  @S9S_MB_2U_LIB.S9S_MB_2U(SCH_1):P5E_CPU1_PE0_RX_DN<5>
  AM10  P5E_CPU1_PE0_RX_DN<4>  PE0_RX_DN11  @S9S_MB_2U_LIB.S9S_MB_2U(SCH_1):P5E_CPU1_PE0_RX_DN<4>
  AP10  P5E_CPU1_PE0_RX_DN<3>  PE0_RX_DN12  @S9S_MB_2U_LIB.S9S_MB_2U(SCH_1):P5E_CPU1_PE0_RX_DN<3>
  AU9  P5E_CPU1_PE0_RX_DN<2>  PE0_RX_DN13  @S9S_MB_2U_LIB.S9S_MB_2U(SCH_1):P5E_CPU1_PE0_RX_DN<2>
  AV10  P5E_CPU1_PE0_RX_DN<1>  PE0_RX_DN14  @S9S_MB_2U_LIB.S9S_MB_2U(SCH_1):P5E_CPU1_PE0_RX_DN<1>
  K10  P5E_CPU1_PE0_RX_DN<15>  PE0_RX_DN0  @S9S_MB_2U_LIB.S9S_MB_2U(SCH_1):P5E_CPU1_PE0_RX_DN<15>
  M10  P5E_CPU1_PE0_RX_DN<14>  PE0_RX_DN1  @S9S_MB_2U_LIB.S9S_MB_2U(SCH_1):P5E_CPU1_PE0_RX_DN<14>
  P10  P5E_CPU1_PE0_RX_DN<13>  PE0_RX_DN2  @S9S_MB_2U_LIB.S9S_MB_2U(SCH_1):P5E_CPU1_PE0_RX_DN<13>
  T10  P5E_CPU1_PE0_RX_DN<12>  PE0_RX_DN3  @S9S_MB_2U_LIB.S9S_MB_2U(SCH_1):P5E_CPU1_PE0_RX_DN<12>
  V10  P5E_CPU1_PE0_RX_DN<11>  PE0_RX_DN4  @S9S_MB_2U_LIB.S9S_MB_2U(SCH_1):P5E_CPU1_PE0_RX_DN<11>
  AA9  P5E_CPU1_PE0_RX_DN<10>  PE0_RX_DN5  @S9S_MB_2U_LIB.S9S_MB_2U(SCH_1):P5E_CPU1_PE0_RX_DN<10>
  BA9  P5E_CPU1_PE0_RX_DN<0>  PE0_RX_DN15  @S9S_MB_2U_LIB.S9S_MB_2U(SCH_1):P5E_CPU1_PE0_RX_DN<0>

SOCKET4677_AZIFS054P001C01  I20  U1     [SOCKET4677_AZIFS054P001C01-SOCA]
  CM18  NC             DMI_TX_DP7  NC
  CL19  NC             DMI_TX_DP6  NC
  CH18  NC             DMI_TX_DP5  NC
  CG19  NC             DMI_TX_DP4  NC
  CD18  NC             DMI_TX_DP3  NC
  CC19  NC             DMI_TX_DP2  NC
  BY18  NC             DMI_TX_DP1  NC
  CA19  NC             DMI_TX_DP0  NC
  CN17  NC             DMI_TX_DN7  NC
  CK18  NC             DMI_TX_DN6  NC
  CJ17  NC             DMI_TX_DN5  NC
  CF18  NC             DMI_TX_DN4  NC
  CE17  NC             DMI_TX_DN3  NC
  CB18  NC             DMI_TX_DN2  NC
  CA17  NC             DMI_TX_DN1  NC
  BW19  NC             DMI_TX_DN0  NC
  BT18  NC             DMI_RX_DP7  NC
  BR19  NC             DMI_RX_DP6  NC
  BM18  NC             DMI_RX_DP5  NC
  BL19  NC             DMI_RX_DP4  NC
  BH18  NC             DMI_RX_DP3  NC
  BG19  NC             DMI_RX_DP2  NC
  BD18  NC             DMI_RX_DP1  NC
  BC19  NC             DMI_RX_DP0  NC
  BU17  NC             DMI_RX_DN7  NC
  BP18  NC             DMI_RX_DN6  NC
  BN17  NC             DMI_RX_DN5  NC
  BK18  NC             DMI_RX_DN4  NC
  BJ17  NC             DMI_RX_DN3  NC
  BF18  NC             DMI_RX_DN2  NC
  BE17  NC             DMI_RX_DN1  NC
  BB18  NC             DMI_RX_DN0  NC

SOCKET4677_AZIFS054P001C01  I20  U1     [SOCKET4677_AZIFS054P001C01-SOCA]
  ED47  M_H_CPU1_SB_RSP<1>  DDR7_B_RSP1  @S9S_MB_2U_LIB.S9S_MB_2U(SCH_1):M_H_CPU1_SB_RSP<1>
  EE48  M_H_CPU1_SB_RSP<0>  DDR7_B_RSP0  @S9S_MB_2U_LIB.S9S_MB_2U(SCH_1):M_H_CPU1_SB_RSP<0>
  DR39  M_H_CPU1_SB_PAR  DDR7_SB_PAR  @S9S_MB_2U_LIB.S9S_MB_2U(SCH_1):M_H_CPU1_SB_PAR
  DB36  M_H_CPU1_SB_DQS_DP<9>  DDR7_SB_DQS_DP9  @S9S_MB_2U_LIB.S9S_MB_2U(SCH_1):M_H_CPU1_SB_DQS_DP<9>
  DH18  M_H_CPU1_SB_DQS_DP<8>  DDR7_SB_DQS_DP8  @S9S_MB_2U_LIB.S9S_MB_2U(SCH_1):M_H_CPU1_SB_DQS_DP<8>
  DN21  M_H_CPU1_SB_DQS_DP<7>  DDR7_SB_DQS_DP7  @S9S_MB_2U_LIB.S9S_MB_2U(SCH_1):M_H_CPU1_SB_DQS_DP<7>
  DF24  M_H_CPU1_SB_DQS_DP<6>  DDR7_SB_DQS_DP6  @S9S_MB_2U_LIB.S9S_MB_2U(SCH_1):M_H_CPU1_SB_DQS_DP<6>
  DF30  M_H_CPU1_SB_DQS_DP<5>  DDR7_SB_DQS_DP5  @S9S_MB_2U_LIB.S9S_MB_2U(SCH_1):M_H_CPU1_SB_DQS_DP<5>
  DF36  M_H_CPU1_SB_DQS_DP<4>  DDR7_SB_DQS_DP4  @S9S_MB_2U_LIB.S9S_MB_2U(SCH_1):M_H_CPU1_SB_DQS_DP<4>
  DD18  M_H_CPU1_SB_DQS_DP<3>  DDR7_SB_DQS_DP3  @S9S_MB_2U_LIB.S9S_MB_2U(SCH_1):M_H_CPU1_SB_DQS_DP<3>
  DJ21  M_H_CPU1_SB_DQS_DP<2>  DDR7_SB_DQS_DP2  @S9S_MB_2U_LIB.S9S_MB_2U(SCH_1):M_H_CPU1_SB_DQS_DP<2>
  DB24  M_H_CPU1_SB_DQS_DP<1>  DDR7_SB_DQS_DP1  @S9S_MB_2U_LIB.S9S_MB_2U(SCH_1):M_H_CPU1_SB_DQS_DP<1>
  DB30  M_H_CPU1_SB_DQS_DP<0>  DDR7_SB_DQS_DP0  @S9S_MB_2U_LIB.S9S_MB_2U(SCH_1):M_H_CPU1_SB_DQS_DP<0>
  DD36  M_H_CPU1_SB_DQS_DN<9>  DDR7_SB_DQS_DN9  @S9S_MB_2U_LIB.S9S_MB_2U(SCH_1):M_H_CPU1_SB_DQS_DN<9>
  DF18  M_H_CPU1_SB_DQS_DN<8>  DDR7_SB_DQS_DN8  @S9S_MB_2U_LIB.S9S_MB_2U(SCH_1):M_H_CPU1_SB_DQS_DN<8>
  DR21  M_H_CPU1_SB_DQS_DN<7>  DDR7_SB_DQS_DN7  @S9S_MB_2U_LIB.S9S_MB_2U(SCH_1):M_H_CPU1_SB_DQS_DN<7>
  DH24  M_H_CPU1_SB_DQS_DN<6>  DDR7_SB_DQS_DN6  @S9S_MB_2U_LIB.S9S_MB_2U(SCH_1):M_H_CPU1_SB_DQS_DN<6>
  DH30  M_H_CPU1_SB_DQS_DN<5>  DDR7_SB_DQS_DN5  @S9S_MB_2U_LIB.S9S_MB_2U(SCH_1):M_H_CPU1_SB_DQS_DN<5>
  DH36  M_H_CPU1_SB_DQS_DN<4>  DDR7_SB_DQS_DN4  @S9S_MB_2U_LIB.S9S_MB_2U(SCH_1):M_H_CPU1_SB_DQS_DN<4>
  DB18  M_H_CPU1_SB_DQS_DN<3>  DDR7_SB_DQS_DN3  @S9S_MB_2U_LIB.S9S_MB_2U(SCH_1):M_H_CPU1_SB_DQS_DN<3>
  DL21  M_H_CPU1_SB_DQS_DN<2>  DDR7_SB_DQS_DN2  @S9S_MB_2U_LIB.S9S_MB_2U(SCH_1):M_H_CPU1_SB_DQS_DN<2>
  DD24  M_H_CPU1_SB_DQS_DN<1>  DDR7_SB_DQS_DN1  @S9S_MB_2U_LIB.S9S_MB_2U(SCH_1):M_H_CPU1_SB_DQS_DN<1>
  DD30  M_H_CPU1_SB_DQS_DN<0>  DDR7_SB_DQS_DN0  @S9S_MB_2U_LIB.S9S_MB_2U(SCH_1):M_H_CPU1_SB_DQS_DN<0>
  DC25  M_H_CPU1_SB_DQ<9>  DDR7_SB_DQ9  @S9S_MB_2U_LIB.S9S_MB_2U(SCH_1):M_H_CPU1_SB_DQ<9>
  DD26  M_H_CPU1_SB_DQ<8>  DDR7_SB_DQ8  @S9S_MB_2U_LIB.S9S_MB_2U(SCH_1):M_H_CPU1_SB_DQ<8>
  DD28  M_H_CPU1_SB_DQ<7>  DDR7_SB_DQ7  @S9S_MB_2U_LIB.S9S_MB_2U(SCH_1):M_H_CPU1_SB_DQ<7>
  DG29  M_H_CPU1_SB_DQ<6>  DDR7_SB_DQ6  @S9S_MB_2U_LIB.S9S_MB_2U(SCH_1):M_H_CPU1_SB_DQ<6>
  DF28  M_H_CPU1_SB_DQ<5>  DDR7_SB_DQ5  @S9S_MB_2U_LIB.S9S_MB_2U(SCH_1):M_H_CPU1_SB_DQ<5>
  DC29  M_H_CPU1_SB_DQ<4>  DDR7_SB_DQ4  @S9S_MB_2U_LIB.S9S_MB_2U(SCH_1):M_H_CPU1_SB_DQ<4>
  DG31  M_H_CPU1_SB_DQ<3>  DDR7_SB_DQ3  @S9S_MB_2U_LIB.S9S_MB_2U(SCH_1):M_H_CPU1_SB_DQ<3>
  DC17  M_H_CPU1_SB_DQ<31>  DDR7_SB_DQ31  @S9S_MB_2U_LIB.S9S_MB_2U(SCH_1):M_H_CPU1_SB_DQ<31>
  DJ17  M_H_CPU1_SB_DQ<30>  DDR7_SB_DQ30  @S9S_MB_2U_LIB.S9S_MB_2U(SCH_1):M_H_CPU1_SB_DQ<30>
  DF32  M_H_CPU1_SB_DQ<2>  DDR7_SB_DQ2  @S9S_MB_2U_LIB.S9S_MB_2U(SCH_1):M_H_CPU1_SB_DQ<2>
  DA17  M_H_CPU1_SB_DQ<29>  DDR7_SB_DQ29  @S9S_MB_2U_LIB.S9S_MB_2U(SCH_1):M_H_CPU1_SB_DQ<29>
  DG17  M_H_CPU1_SB_DQ<28>  DDR7_SB_DQ28  @S9S_MB_2U_LIB.S9S_MB_2U(SCH_1):M_H_CPU1_SB_DQ<28>
  DG19  M_H_CPU1_SB_DQ<27>  DDR7_SB_DQ27  @S9S_MB_2U_LIB.S9S_MB_2U(SCH_1):M_H_CPU1_SB_DQ<27>
  DF20  M_H_CPU1_SB_DQ<26>  DDR7_SB_DQ26  @S9S_MB_2U_LIB.S9S_MB_2U(SCH_1):M_H_CPU1_SB_DQ<26>
  DC19  M_H_CPU1_SB_DQ<25>  DDR7_SB_DQ25  @S9S_MB_2U_LIB.S9S_MB_2U(SCH_1):M_H_CPU1_SB_DQ<25>
  DD20  M_H_CPU1_SB_DQ<24>  DDR7_SB_DQ24  @S9S_MB_2U_LIB.S9S_MB_2U(SCH_1):M_H_CPU1_SB_DQ<24>
  DN19  M_H_CPU1_SB_DQ<23>  DDR7_SB_DQ23  @S9S_MB_2U_LIB.S9S_MB_2U(SCH_1):M_H_CPU1_SB_DQ<23>
  DP20  M_H_CPU1_SB_DQ<22>  DDR7_SB_DQ22  @S9S_MB_2U_LIB.S9S_MB_2U(SCH_1):M_H_CPU1_SB_DQ<22>
  DL19  M_H_CPU1_SB_DQ<21>  DDR7_SB_DQ21  @S9S_MB_2U_LIB.S9S_MB_2U(SCH_1):M_H_CPU1_SB_DQ<21>
  DK20  M_H_CPU1_SB_DQ<20>  DDR7_SB_DQ20  @S9S_MB_2U_LIB.S9S_MB_2U(SCH_1):M_H_CPU1_SB_DQ<20>
  DC31  M_H_CPU1_SB_DQ<1>  DDR7_SB_DQ1  @S9S_MB_2U_LIB.S9S_MB_2U(SCH_1):M_H_CPU1_SB_DQ<1>
  DP22  M_H_CPU1_SB_DQ<19>  DDR7_SB_DQ19  @S9S_MB_2U_LIB.S9S_MB_2U(SCH_1):M_H_CPU1_SB_DQ<19>
  DN23  M_H_CPU1_SB_DQ<18>  DDR7_SB_DQ18  @S9S_MB_2U_LIB.S9S_MB_2U(SCH_1):M_H_CPU1_SB_DQ<18>
  DK22  M_H_CPU1_SB_DQ<17>  DDR7_SB_DQ17  @S9S_MB_2U_LIB.S9S_MB_2U(SCH_1):M_H_CPU1_SB_DQ<17>
  DL23  M_H_CPU1_SB_DQ<16>  DDR7_SB_DQ16  @S9S_MB_2U_LIB.S9S_MB_2U(SCH_1):M_H_CPU1_SB_DQ<16>
  DF22  M_H_CPU1_SB_DQ<15>  DDR7_SB_DQ15  @S9S_MB_2U_LIB.S9S_MB_2U(SCH_1):M_H_CPU1_SB_DQ<15>
  DG23  M_H_CPU1_SB_DQ<14>  DDR7_SB_DQ14  @S9S_MB_2U_LIB.S9S_MB_2U(SCH_1):M_H_CPU1_SB_DQ<14>
  DD22  M_H_CPU1_SB_DQ<13>  DDR7_SB_DQ13  @S9S_MB_2U_LIB.S9S_MB_2U(SCH_1):M_H_CPU1_SB_DQ<13>
  DC23  M_H_CPU1_SB_DQ<12>  DDR7_SB_DQ12  @S9S_MB_2U_LIB.S9S_MB_2U(SCH_1):M_H_CPU1_SB_DQ<12>
  DG25  M_H_CPU1_SB_DQ<11>  DDR7_SB_DQ11  @S9S_MB_2U_LIB.S9S_MB_2U(SCH_1):M_H_CPU1_SB_DQ<11>
  DF26  M_H_CPU1_SB_DQ<10>  DDR7_SB_DQ10  @S9S_MB_2U_LIB.S9S_MB_2U(SCH_1):M_H_CPU1_SB_DQ<10>
  DD32  M_H_CPU1_SB_DQ<0>  DDR7_SB_DQ0  @S9S_MB_2U_LIB.S9S_MB_2U(SCH_1):M_H_CPU1_SB_DQ<0>
  DP38  M_H_CPU1_SB_CS_N<3>  DDR7_SB_CS3_N  @S9S_MB_2U_LIB.S9S_MB_2U(SCH_1):M_H_CPU1_SB_CS_N<3>
  DK38  M_H_CPU1_SB_CS_N<2>  DDR7_SB_CS2_N  @S9S_MB_2U_LIB.S9S_MB_2U(SCH_1):M_H_CPU1_SB_CS_N<2>
  DN37  M_H_CPU1_SB_CS_N<1>  DDR7_SB_CS1_N  @S9S_MB_2U_LIB.S9S_MB_2U(SCH_1):M_H_CPU1_SB_CS_N<1>
  DL37  M_H_CPU1_SB_CS_N<0>  DDR7_SB_CS0_N  @S9S_MB_2U_LIB.S9S_MB_2U(SCH_1):M_H_CPU1_SB_CS_N<0>
  DC37  M_H_CPU1_SB_CB<7>  DDR7_SB_ECC7  @S9S_MB_2U_LIB.S9S_MB_2U(SCH_1):M_H_CPU1_SB_CB<7>
  DD38  M_H_CPU1_SB_CB<6>  DDR7_SB_ECC6  @S9S_MB_2U_LIB.S9S_MB_2U(SCH_1):M_H_CPU1_SB_CB<6>
  DG37  M_H_CPU1_SB_CB<5>  DDR7_SB_ECC5  @S9S_MB_2U_LIB.S9S_MB_2U(SCH_1):M_H_CPU1_SB_CB<5>
  DF38  M_H_CPU1_SB_CB<4>  DDR7_SB_ECC4  @S9S_MB_2U_LIB.S9S_MB_2U(SCH_1):M_H_CPU1_SB_CB<4>
  DF34  M_H_CPU1_SB_CB<3>  DDR7_SB_ECC3  @S9S_MB_2U_LIB.S9S_MB_2U(SCH_1):M_H_CPU1_SB_CB<3>
  DG35  M_H_CPU1_SB_CB<2>  DDR7_SB_ECC2  @S9S_MB_2U_LIB.S9S_MB_2U(SCH_1):M_H_CPU1_SB_CB<2>
  DD34  M_H_CPU1_SB_CB<1>  DDR7_SB_ECC1  @S9S_MB_2U_LIB.S9S_MB_2U(SCH_1):M_H_CPU1_SB_CB<1>
  DC35  M_H_CPU1_SB_CB<0>  DDR7_SB_ECC0  @S9S_MB_2U_LIB.S9S_MB_2U(SCH_1):M_H_CPU1_SB_CB<0>
  DJ39  M_H_CPU1_SB_CA<6>  DDR7_SB_CA6  @S9S_MB_2U_LIB.S9S_MB_2U(SCH_1):M_H_CPU1_SB_CA<6>
  DP40  M_H_CPU1_SB_CA<5>  DDR7_SB_CA5  @S9S_MB_2U_LIB.S9S_MB_2U(SCH_1):M_H_CPU1_SB_CA<5>
  DK40  M_H_CPU1_SB_CA<4>  DDR7_SB_CA4  @S9S_MB_2U_LIB.S9S_MB_2U(SCH_1):M_H_CPU1_SB_CA<4>
  DN41  M_H_CPU1_SB_CA<3>  DDR7_SB_CA3  @S9S_MB_2U_LIB.S9S_MB_2U(SCH_1):M_H_CPU1_SB_CA<3>
  DL41  M_H_CPU1_SB_CA<2>  DDR7_SB_CA2  @S9S_MB_2U_LIB.S9S_MB_2U(SCH_1):M_H_CPU1_SB_CA<2>
  DG41  M_H_CPU1_SB_CA<1>  DDR7_SB_CA1  @S9S_MB_2U_LIB.S9S_MB_2U(SCH_1):M_H_CPU1_SB_CA<1>
  DF40  M_H_CPU1_SB_CA<0>  DDR7_SB_CA0  @S9S_MB_2U_LIB.S9S_MB_2U(SCH_1):M_H_CPU1_SB_CA<0>
  EH47  M_H_CPU1_SA_RSP<1>  DDR7_A_RSP1  @S9S_MB_2U_LIB.S9S_MB_2U(SCH_1):M_H_CPU1_SA_RSP<1>
  EG48  M_H_CPU1_SA_RSP<0>  DDR7_A_RSP0  @S9S_MB_2U_LIB.S9S_MB_2U(SCH_1):M_H_CPU1_SA_RSP<0>
  DD40  M_H_CPU1_SA_PAR  DDR7_SA_PAR  @S9S_MB_2U_LIB.S9S_MB_2U(SCH_1):M_H_CPU1_SA_PAR
  DF55  M_H_CPU1_SA_DQS_DP<9>  DDR7_SA_DQS_DP9  @S9S_MB_2U_LIB.S9S_MB_2U(SCH_1):M_H_CPU1_SA_DQS_DP<9>
  DF61  M_H_CPU1_SA_DQS_DP<8>  DDR7_SA_DQS_DP8  @S9S_MB_2U_LIB.S9S_MB_2U(SCH_1):M_H_CPU1_SA_DQS_DP<8>
  DF67  M_H_CPU1_SA_DQS_DP<7>  DDR7_SA_DQS_DP7  @S9S_MB_2U_LIB.S9S_MB_2U(SCH_1):M_H_CPU1_SA_DQS_DP<7>
  DF73  M_H_CPU1_SA_DQS_DP<6>  DDR7_SA_DQS_DP6  @S9S_MB_2U_LIB.S9S_MB_2U(SCH_1):M_H_CPU1_SA_DQS_DP<6>
  DN76  M_H_CPU1_SA_DQS_DP<5>  DDR7_SA_DQS_DP5  @S9S_MB_2U_LIB.S9S_MB_2U(SCH_1):M_H_CPU1_SA_DQS_DP<5>
  DB55  M_H_CPU1_SA_DQS_DP<4>  DDR7_SA_DQS_DP4  @S9S_MB_2U_LIB.S9S_MB_2U(SCH_1):M_H_CPU1_SA_DQS_DP<4>
  DB61  M_H_CPU1_SA_DQS_DP<3>  DDR7_SA_DQS_DP3  @S9S_MB_2U_LIB.S9S_MB_2U(SCH_1):M_H_CPU1_SA_DQS_DP<3>
  DB67  M_H_CPU1_SA_DQS_DP<2>  DDR7_SA_DQS_DP2  @S9S_MB_2U_LIB.S9S_MB_2U(SCH_1):M_H_CPU1_SA_DQS_DP<2>
  DD73  M_H_CPU1_SA_DQS_DP<1>  DDR7_SA_DQS_DP1  @S9S_MB_2U_LIB.S9S_MB_2U(SCH_1):M_H_CPU1_SA_DQS_DP<1>
  DL76  M_H_CPU1_SA_DQS_DP<0>  DDR7_SA_DQS_DP0  @S9S_MB_2U_LIB.S9S_MB_2U(SCH_1):M_H_CPU1_SA_DQS_DP<0>
  DH55  M_H_CPU1_SA_DQS_DN<9>  DDR7_SA_DQS_DN9  @S9S_MB_2U_LIB.S9S_MB_2U(SCH_1):M_H_CPU1_SA_DQS_DN<9>
  DH61  M_H_CPU1_SA_DQS_DN<8>  DDR7_SA_DQS_DN8  @S9S_MB_2U_LIB.S9S_MB_2U(SCH_1):M_H_CPU1_SA_DQS_DN<8>
  DH67  M_H_CPU1_SA_DQS_DN<7>  DDR7_SA_DQS_DN7  @S9S_MB_2U_LIB.S9S_MB_2U(SCH_1):M_H_CPU1_SA_DQS_DN<7>
  DH73  M_H_CPU1_SA_DQS_DN<6>  DDR7_SA_DQS_DN6  @S9S_MB_2U_LIB.S9S_MB_2U(SCH_1):M_H_CPU1_SA_DQS_DN<6>
  DR76  M_H_CPU1_SA_DQS_DN<5>  DDR7_SA_DQS_DN5  @S9S_MB_2U_LIB.S9S_MB_2U(SCH_1):M_H_CPU1_SA_DQS_DN<5>
  DD55  M_H_CPU1_SA_DQS_DN<4>  DDR7_SA_DQS_DN4  @S9S_MB_2U_LIB.S9S_MB_2U(SCH_1):M_H_CPU1_SA_DQS_DN<4>
  DD61  M_H_CPU1_SA_DQS_DN<3>  DDR7_SA_DQS_DN3  @S9S_MB_2U_LIB.S9S_MB_2U(SCH_1):M_H_CPU1_SA_DQS_DN<3>
  DD67  M_H_CPU1_SA_DQS_DN<2>  DDR7_SA_DQS_DN2  @S9S_MB_2U_LIB.S9S_MB_2U(SCH_1):M_H_CPU1_SA_DQS_DN<2>
  DB73  M_H_CPU1_SA_DQS_DN<1>  DDR7_SA_DQS_DN1  @S9S_MB_2U_LIB.S9S_MB_2U(SCH_1):M_H_CPU1_SA_DQS_DN<1>
  DJ76  M_H_CPU1_SA_DQS_DN<0>  DDR7_SA_DQS_DN0  @S9S_MB_2U_LIB.S9S_MB_2U(SCH_1):M_H_CPU1_SA_DQS_DN<0>
  DC74  M_H_CPU1_SA_DQ<9>  DDR7_SA_DQ9  @S9S_MB_2U_LIB.S9S_MB_2U(SCH_1):M_H_CPU1_SA_DQ<9>
  DD75  M_H_CPU1_SA_DQ<8>  DDR7_SA_DQ8  @S9S_MB_2U_LIB.S9S_MB_2U(SCH_1):M_H_CPU1_SA_DQ<8>
  DN74  M_H_CPU1_SA_DQ<7>  DDR7_SA_DQ7  @S9S_MB_2U_LIB.S9S_MB_2U(SCH_1):M_H_CPU1_SA_DQ<7>
  DP75  M_H_CPU1_SA_DQ<6>  DDR7_SA_DQ6  @S9S_MB_2U_LIB.S9S_MB_2U(SCH_1):M_H_CPU1_SA_DQ<6>
  DL74  M_H_CPU1_SA_DQ<5>  DDR7_SA_DQ5  @S9S_MB_2U_LIB.S9S_MB_2U(SCH_1):M_H_CPU1_SA_DQ<5>
  DK75  M_H_CPU1_SA_DQ<4>  DDR7_SA_DQ4  @S9S_MB_2U_LIB.S9S_MB_2U(SCH_1):M_H_CPU1_SA_DQ<4>
  DP77  M_H_CPU1_SA_DQ<3>  DDR7_SA_DQ3  @S9S_MB_2U_LIB.S9S_MB_2U(SCH_1):M_H_CPU1_SA_DQ<3>
  DF59  M_H_CPU1_SA_DQ<31>  DDR7_SA_DQ31  @S9S_MB_2U_LIB.S9S_MB_2U(SCH_1):M_H_CPU1_SA_DQ<31>
  DG60  M_H_CPU1_SA_DQ<30>  DDR7_SA_DQ30  @S9S_MB_2U_LIB.S9S_MB_2U(SCH_1):M_H_CPU1_SA_DQ<30>
  DW78  M_H_CPU1_SA_DQ<2>  DDR7_SA_DQ2  @S9S_MB_2U_LIB.S9S_MB_2U(SCH_1):M_H_CPU1_SA_DQ<2>
  DD59  M_H_CPU1_SA_DQ<29>  DDR7_SA_DQ29  @S9S_MB_2U_LIB.S9S_MB_2U(SCH_1):M_H_CPU1_SA_DQ<29>
  DC60  M_H_CPU1_SA_DQ<28>  DDR7_SA_DQ28  @S9S_MB_2U_LIB.S9S_MB_2U(SCH_1):M_H_CPU1_SA_DQ<28>
  DG62  M_H_CPU1_SA_DQ<27>  DDR7_SA_DQ27  @S9S_MB_2U_LIB.S9S_MB_2U(SCH_1):M_H_CPU1_SA_DQ<27>
  DF63  M_H_CPU1_SA_DQ<26>  DDR7_SA_DQ26  @S9S_MB_2U_LIB.S9S_MB_2U(SCH_1):M_H_CPU1_SA_DQ<26>
  DC62  M_H_CPU1_SA_DQ<25>  DDR7_SA_DQ25  @S9S_MB_2U_LIB.S9S_MB_2U(SCH_1):M_H_CPU1_SA_DQ<25>
  DD63  M_H_CPU1_SA_DQ<24>  DDR7_SA_DQ24  @S9S_MB_2U_LIB.S9S_MB_2U(SCH_1):M_H_CPU1_SA_DQ<24>
  DF65  M_H_CPU1_SA_DQ<23>  DDR7_SA_DQ23  @S9S_MB_2U_LIB.S9S_MB_2U(SCH_1):M_H_CPU1_SA_DQ<23>
  DG66  M_H_CPU1_SA_DQ<22>  DDR7_SA_DQ22  @S9S_MB_2U_LIB.S9S_MB_2U(SCH_1):M_H_CPU1_SA_DQ<22>
  DD65  M_H_CPU1_SA_DQ<21>  DDR7_SA_DQ21  @S9S_MB_2U_LIB.S9S_MB_2U(SCH_1):M_H_CPU1_SA_DQ<21>
  DC66  M_H_CPU1_SA_DQ<20>  DDR7_SA_DQ20  @S9S_MB_2U_LIB.S9S_MB_2U(SCH_1):M_H_CPU1_SA_DQ<20>
  DT77  M_H_CPU1_SA_DQ<1>  DDR7_SA_DQ1  @S9S_MB_2U_LIB.S9S_MB_2U(SCH_1):M_H_CPU1_SA_DQ<1>
  DG68  M_H_CPU1_SA_DQ<19>  DDR7_SA_DQ19  @S9S_MB_2U_LIB.S9S_MB_2U(SCH_1):M_H_CPU1_SA_DQ<19>
  DF69  M_H_CPU1_SA_DQ<18>  DDR7_SA_DQ18  @S9S_MB_2U_LIB.S9S_MB_2U(SCH_1):M_H_CPU1_SA_DQ<18>
  DC68  M_H_CPU1_SA_DQ<17>  DDR7_SA_DQ17  @S9S_MB_2U_LIB.S9S_MB_2U(SCH_1):M_H_CPU1_SA_DQ<17>
  DD69  M_H_CPU1_SA_DQ<16>  DDR7_SA_DQ16  @S9S_MB_2U_LIB.S9S_MB_2U(SCH_1):M_H_CPU1_SA_DQ<16>
  DF71  M_H_CPU1_SA_DQ<15>  DDR7_SA_DQ15  @S9S_MB_2U_LIB.S9S_MB_2U(SCH_1):M_H_CPU1_SA_DQ<15>
  DG72  M_H_CPU1_SA_DQ<14>  DDR7_SA_DQ14  @S9S_MB_2U_LIB.S9S_MB_2U(SCH_1):M_H_CPU1_SA_DQ<14>
  DD71  M_H_CPU1_SA_DQ<13>  DDR7_SA_DQ13  @S9S_MB_2U_LIB.S9S_MB_2U(SCH_1):M_H_CPU1_SA_DQ<13>
  DC72  M_H_CPU1_SA_DQ<12>  DDR7_SA_DQ12  @S9S_MB_2U_LIB.S9S_MB_2U(SCH_1):M_H_CPU1_SA_DQ<12>
  DG74  M_H_CPU1_SA_DQ<11>  DDR7_SA_DQ11  @S9S_MB_2U_LIB.S9S_MB_2U(SCH_1):M_H_CPU1_SA_DQ<11>
  DF75  M_H_CPU1_SA_DQ<10>  DDR7_SA_DQ10  @S9S_MB_2U_LIB.S9S_MB_2U(SCH_1):M_H_CPU1_SA_DQ<10>
  DY79  M_H_CPU1_SA_DQ<0>  DDR7_SA_DQ0  @S9S_MB_2U_LIB.S9S_MB_2U(SCH_1):M_H_CPU1_SA_DQ<0>
  DC50  M_H_CPU1_SA_CS_N<3>  DDR7_SA_CS3_N  @S9S_MB_2U_LIB.S9S_MB_2U(SCH_1):M_H_CPU1_SA_CS_N<3>
  DD51  M_H_CPU1_SA_CS_N<2>  DDR7_SA_CS2_N  @S9S_MB_2U_LIB.S9S_MB_2U(SCH_1):M_H_CPU1_SA_CS_N<2>
  DG50  M_H_CPU1_SA_CS_N<1>  DDR7_SA_CS1_N  @S9S_MB_2U_LIB.S9S_MB_2U(SCH_1):M_H_CPU1_SA_CS_N<1>
  DF51  M_H_CPU1_SA_CS_N<0>  DDR7_SA_CS0_N  @S9S_MB_2U_LIB.S9S_MB_2U(SCH_1):M_H_CPU1_SA_CS_N<0>
  DF53  M_H_CPU1_SA_CB<7>  DDR7_SA_ECC7  @S9S_MB_2U_LIB.S9S_MB_2U(SCH_1):M_H_CPU1_SA_CB<7>
  DG54  M_H_CPU1_SA_CB<6>  DDR7_SA_ECC6  @S9S_MB_2U_LIB.S9S_MB_2U(SCH_1):M_H_CPU1_SA_CB<6>
  DD53  M_H_CPU1_SA_CB<5>  DDR7_SA_ECC5  @S9S_MB_2U_LIB.S9S_MB_2U(SCH_1):M_H_CPU1_SA_CB<5>
  DC54  M_H_CPU1_SA_CB<4>  DDR7_SA_ECC4  @S9S_MB_2U_LIB.S9S_MB_2U(SCH_1):M_H_CPU1_SA_CB<4>
  DG56  M_H_CPU1_SA_CB<3>  DDR7_SA_ECC3  @S9S_MB_2U_LIB.S9S_MB_2U(SCH_1):M_H_CPU1_SA_CB<3>
  DF57  M_H_CPU1_SA_CB<2>  DDR7_SA_ECC2  @S9S_MB_2U_LIB.S9S_MB_2U(SCH_1):M_H_CPU1_SA_CB<2>
  DC56  M_H_CPU1_SA_CB<1>  DDR7_SA_ECC1  @S9S_MB_2U_LIB.S9S_MB_2U(SCH_1):M_H_CPU1_SA_CB<1>
  DD57  M_H_CPU1_SA_CB<0>  DDR7_SA_ECC0  @S9S_MB_2U_LIB.S9S_MB_2U(SCH_1):M_H_CPU1_SA_CB<0>
  DC41  M_H_CPU1_SA_CA<6>  DDR7_SA_CA6  @S9S_MB_2U_LIB.S9S_MB_2U(SCH_1):M_H_CPU1_SA_CA<6>
  DF47  M_H_CPU1_SA_CA<5>  DDR7_SA_CA5  @S9S_MB_2U_LIB.S9S_MB_2U(SCH_1):M_H_CPU1_SA_CA<5>
  DD47  M_H_CPU1_SA_CA<4>  DDR7_SA_CA4  @S9S_MB_2U_LIB.S9S_MB_2U(SCH_1):M_H_CPU1_SA_CA<4>
  DG48  M_H_CPU1_SA_CA<3>  DDR7_SA_CA3  @S9S_MB_2U_LIB.S9S_MB_2U(SCH_1):M_H_CPU1_SA_CA<3>
  DC48  M_H_CPU1_SA_CA<2>  DDR7_SA_CA2  @S9S_MB_2U_LIB.S9S_MB_2U(SCH_1):M_H_CPU1_SA_CA<2>
  DH49  M_H_CPU1_SA_CA<1>  DDR7_SA_CA1  @S9S_MB_2U_LIB.S9S_MB_2U(SCH_1):M_H_CPU1_SA_CA<1>
  DB49  M_H_CPU1_SA_CA<0>  DDR7_SA_CA0  @S9S_MB_2U_LIB.S9S_MB_2U(SCH_1):M_H_CPU1_SA_CA<0>
  DB42  M_H_CPU1_CLK_DP<1>  DDR7_CLK_DP1  @S9S_MB_2U_LIB.S9S_MB_2U(SCH_1):M_H_CPU1_CLK_DP<1>
  DF42  M_H_CPU1_CLK_DP<0>  DDR7_CLK_DP0  @S9S_MB_2U_LIB.S9S_MB_2U(SCH_1):M_H_CPU1_CLK_DP<0>
  DD42  M_H_CPU1_CLK_DN<1>  DDR7_CLK_DN1  @S9S_MB_2U_LIB.S9S_MB_2U(SCH_1):M_H_CPU1_CLK_DN<1>
  DH42  M_H_CPU1_CLK_DN<0>  DDR7_CLK_DN0  @S9S_MB_2U_LIB.S9S_MB_2U(SCH_1):M_H_CPU1_CLK_DN<0>
  CY51  M_H_CPU1_ALERT_N  DDR7_ALERT_N  @S9S_MB_2U_LIB.S9S_MB_2U(SCH_1):M_H_CPU1_ALERT_N

SOCKET4677_AZIFS054P001C01  I168  U1     [SOCKET4677_AZIFS054P001C01-SOCA]
  DV47  M_G_CPU1_SB_RSP<1>  DDR6_B_RSP1  @S9S_MB_2U_LIB.S9S_MB_2U(SCH_1):M_G_CPU1_SB_RSP<1>
  DU48  M_G_CPU1_SB_RSP<0>  DDR6_B_RSP0  @S9S_MB_2U_LIB.S9S_MB_2U(SCH_1):M_G_CPU1_SB_RSP<0>
  EB42  M_G_CPU1_SB_PAR  DDR6_SB_PAR  @S9S_MB_2U_LIB.S9S_MB_2U(SCH_1):M_G_CPU1_SB_PAR
  DT36  M_G_CPU1_SB_DQS_DP<9>  DDR6_SB_DQS_DP9  @S9S_MB_2U_LIB.S9S_MB_2U(SCH_1):M_G_CPU1_SB_DQS_DP<9>
  EN5  M_G_CPU1_SB_DQS_DP<8>  DDR6_SB_DQS_DP8  @S9S_MB_2U_LIB.S9S_MB_2U(SCH_1):M_G_CPU1_SB_DQS_DP<8>
  DY24  M_G_CPU1_SB_DQS_DP<7>  DDR6_SB_DQS_DP7  @S9S_MB_2U_LIB.S9S_MB_2U(SCH_1):M_G_CPU1_SB_DQS_DP<7>
  DR27  M_G_CPU1_SB_DQS_DP<6>  DDR6_SB_DQS_DP6  @S9S_MB_2U_LIB.S9S_MB_2U(SCH_1):M_G_CPU1_SB_DQS_DP<6>
  DN33  M_G_CPU1_SB_DQS_DP<5>  DDR6_SB_DQS_DP5  @S9S_MB_2U_LIB.S9S_MB_2U(SCH_1):M_G_CPU1_SB_DQS_DP<5>
  DY36  M_G_CPU1_SB_DQS_DP<4>  DDR6_SB_DQS_DP4  @S9S_MB_2U_LIB.S9S_MB_2U(SCH_1):M_G_CPU1_SB_DQS_DP<4>
  EN7  M_G_CPU1_SB_DQS_DP<3>  DDR6_SB_DQS_DP3  @S9S_MB_2U_LIB.S9S_MB_2U(SCH_1):M_G_CPU1_SB_DQS_DP<3>
  DT24  M_G_CPU1_SB_DQS_DP<2>  DDR6_SB_DQS_DP2  @S9S_MB_2U_LIB.S9S_MB_2U(SCH_1):M_G_CPU1_SB_DQS_DP<2>
  DL27  M_G_CPU1_SB_DQS_DP<1>  DDR6_SB_DQS_DP1  @S9S_MB_2U_LIB.S9S_MB_2U(SCH_1):M_G_CPU1_SB_DQS_DP<1>
  DL33  M_G_CPU1_SB_DQS_DP<0>  DDR6_SB_DQS_DP0  @S9S_MB_2U_LIB.S9S_MB_2U(SCH_1):M_G_CPU1_SB_DQS_DP<0>
  DV36  M_G_CPU1_SB_DQS_DN<9>  DDR6_SB_DQS_DN9  @S9S_MB_2U_LIB.S9S_MB_2U(SCH_1):M_G_CPU1_SB_DQS_DN<9>
  EM6  M_G_CPU1_SB_DQS_DN<8>  DDR6_SB_DQS_DN8  @S9S_MB_2U_LIB.S9S_MB_2U(SCH_1):M_G_CPU1_SB_DQS_DN<8>
  EB24  M_G_CPU1_SB_DQS_DN<7>  DDR6_SB_DQS_DN7  @S9S_MB_2U_LIB.S9S_MB_2U(SCH_1):M_G_CPU1_SB_DQS_DN<7>
  DN27  M_G_CPU1_SB_DQS_DN<6>  DDR6_SB_DQS_DN6  @S9S_MB_2U_LIB.S9S_MB_2U(SCH_1):M_G_CPU1_SB_DQS_DN<6>
  DR33  M_G_CPU1_SB_DQS_DN<5>  DDR6_SB_DQS_DN5  @S9S_MB_2U_LIB.S9S_MB_2U(SCH_1):M_G_CPU1_SB_DQS_DN<5>
  EB36  M_G_CPU1_SB_DQS_DN<4>  DDR6_SB_DQS_DN4  @S9S_MB_2U_LIB.S9S_MB_2U(SCH_1):M_G_CPU1_SB_DQS_DN<4>
  EP6  M_G_CPU1_SB_DQS_DN<3>  DDR6_SB_DQS_DN3  @S9S_MB_2U_LIB.S9S_MB_2U(SCH_1):M_G_CPU1_SB_DQS_DN<3>
  DV24  M_G_CPU1_SB_DQS_DN<2>  DDR6_SB_DQS_DN2  @S9S_MB_2U_LIB.S9S_MB_2U(SCH_1):M_G_CPU1_SB_DQS_DN<2>
  DJ27  M_G_CPU1_SB_DQS_DN<1>  DDR6_SB_DQS_DN1  @S9S_MB_2U_LIB.S9S_MB_2U(SCH_1):M_G_CPU1_SB_DQS_DN<1>
  DJ33  M_G_CPU1_SB_DQS_DN<0>  DDR6_SB_DQS_DN0  @S9S_MB_2U_LIB.S9S_MB_2U(SCH_1):M_G_CPU1_SB_DQS_DN<0>
  DK28  M_G_CPU1_SB_DQ<9>  DDR6_SB_DQ9  @S9S_MB_2U_LIB.S9S_MB_2U(SCH_1):M_G_CPU1_SB_DQ<9>
  DN29  M_G_CPU1_SB_DQ<8>  DDR6_SB_DQ8  @S9S_MB_2U_LIB.S9S_MB_2U(SCH_1):M_G_CPU1_SB_DQ<8>
  DN31  M_G_CPU1_SB_DQ<7>  DDR6_SB_DQ7  @S9S_MB_2U_LIB.S9S_MB_2U(SCH_1):M_G_CPU1_SB_DQ<7>
  DP32  M_G_CPU1_SB_DQ<6>  DDR6_SB_DQ6  @S9S_MB_2U_LIB.S9S_MB_2U(SCH_1):M_G_CPU1_SB_DQ<6>
  DL31  M_G_CPU1_SB_DQ<5>  DDR6_SB_DQ5  @S9S_MB_2U_LIB.S9S_MB_2U(SCH_1):M_G_CPU1_SB_DQ<5>
  DK32  M_G_CPU1_SB_DQ<4>  DDR6_SB_DQ4  @S9S_MB_2U_LIB.S9S_MB_2U(SCH_1):M_G_CPU1_SB_DQ<4>
  DP34  M_G_CPU1_SB_DQ<3>  DDR6_SB_DQ3  @S9S_MB_2U_LIB.S9S_MB_2U(SCH_1):M_G_CPU1_SB_DQ<3>
  EM4  M_G_CPU1_SB_DQ<31>  DDR6_SB_DQ31  @S9S_MB_2U_LIB.S9S_MB_2U(SCH_1):M_G_CPU1_SB_DQ<31>
  EP4  M_G_CPU1_SB_DQ<30>  DDR6_SB_DQ30  @S9S_MB_2U_LIB.S9S_MB_2U(SCH_1):M_G_CPU1_SB_DQ<30>
  DN35  M_G_CPU1_SB_DQ<2>  DDR6_SB_DQ2  @S9S_MB_2U_LIB.S9S_MB_2U(SCH_1):M_G_CPU1_SB_DQ<2>
  EJ5  M_G_CPU1_SB_DQ<29>  DDR6_SB_DQ29  @S9S_MB_2U_LIB.S9S_MB_2U(SCH_1):M_G_CPU1_SB_DQ<29>
  EK6  M_G_CPU1_SB_DQ<28>  DDR6_SB_DQ28  @S9S_MB_2U_LIB.S9S_MB_2U(SCH_1):M_G_CPU1_SB_DQ<28>
  ET8  M_G_CPU1_SB_DQ<27>  DDR6_SB_DQ27  @S9S_MB_2U_LIB.S9S_MB_2U(SCH_1):M_G_CPU1_SB_DQ<27>
  EP8  M_G_CPU1_SB_DQ<26>  DDR6_SB_DQ26  @S9S_MB_2U_LIB.S9S_MB_2U(SCH_1):M_G_CPU1_SB_DQ<26>
  EH8  M_G_CPU1_SB_DQ<25>  DDR6_SB_DQ25  @S9S_MB_2U_LIB.S9S_MB_2U(SCH_1):M_G_CPU1_SB_DQ<25>
  EK8  M_G_CPU1_SB_DQ<24>  DDR6_SB_DQ24  @S9S_MB_2U_LIB.S9S_MB_2U(SCH_1):M_G_CPU1_SB_DQ<24>
  DY22  M_G_CPU1_SB_DQ<23>  DDR6_SB_DQ23  @S9S_MB_2U_LIB.S9S_MB_2U(SCH_1):M_G_CPU1_SB_DQ<23>
  EA23  M_G_CPU1_SB_DQ<22>  DDR6_SB_DQ22  @S9S_MB_2U_LIB.S9S_MB_2U(SCH_1):M_G_CPU1_SB_DQ<22>
  DV22  M_G_CPU1_SB_DQ<21>  DDR6_SB_DQ21  @S9S_MB_2U_LIB.S9S_MB_2U(SCH_1):M_G_CPU1_SB_DQ<21>
  DU23  M_G_CPU1_SB_DQ<20>  DDR6_SB_DQ20  @S9S_MB_2U_LIB.S9S_MB_2U(SCH_1):M_G_CPU1_SB_DQ<20>
  DK34  M_G_CPU1_SB_DQ<1>  DDR6_SB_DQ1  @S9S_MB_2U_LIB.S9S_MB_2U(SCH_1):M_G_CPU1_SB_DQ<1>
  EA25  M_G_CPU1_SB_DQ<19>  DDR6_SB_DQ19  @S9S_MB_2U_LIB.S9S_MB_2U(SCH_1):M_G_CPU1_SB_DQ<19>
  DY26  M_G_CPU1_SB_DQ<18>  DDR6_SB_DQ18  @S9S_MB_2U_LIB.S9S_MB_2U(SCH_1):M_G_CPU1_SB_DQ<18>
  DU25  M_G_CPU1_SB_DQ<17>  DDR6_SB_DQ17  @S9S_MB_2U_LIB.S9S_MB_2U(SCH_1):M_G_CPU1_SB_DQ<17>
  DV26  M_G_CPU1_SB_DQ<16>  DDR6_SB_DQ16  @S9S_MB_2U_LIB.S9S_MB_2U(SCH_1):M_G_CPU1_SB_DQ<16>
  DN25  M_G_CPU1_SB_DQ<15>  DDR6_SB_DQ15  @S9S_MB_2U_LIB.S9S_MB_2U(SCH_1):M_G_CPU1_SB_DQ<15>
  DP26  M_G_CPU1_SB_DQ<14>  DDR6_SB_DQ14  @S9S_MB_2U_LIB.S9S_MB_2U(SCH_1):M_G_CPU1_SB_DQ<14>
  DL25  M_G_CPU1_SB_DQ<13>  DDR6_SB_DQ13  @S9S_MB_2U_LIB.S9S_MB_2U(SCH_1):M_G_CPU1_SB_DQ<13>
  DK26  M_G_CPU1_SB_DQ<12>  DDR6_SB_DQ12  @S9S_MB_2U_LIB.S9S_MB_2U(SCH_1):M_G_CPU1_SB_DQ<12>
  DP28  M_G_CPU1_SB_DQ<11>  DDR6_SB_DQ11  @S9S_MB_2U_LIB.S9S_MB_2U(SCH_1):M_G_CPU1_SB_DQ<11>
  DL29  M_G_CPU1_SB_DQ<10>  DDR6_SB_DQ10  @S9S_MB_2U_LIB.S9S_MB_2U(SCH_1):M_G_CPU1_SB_DQ<10>
  DL35  M_G_CPU1_SB_DQ<0>  DDR6_SB_DQ0  @S9S_MB_2U_LIB.S9S_MB_2U(SCH_1):M_G_CPU1_SB_DQ<0>
  DV40  M_G_CPU1_SB_CS_N<3>  DDR6_SB_CS3_N  @S9S_MB_2U_LIB.S9S_MB_2U(SCH_1):M_G_CPU1_SB_CS_N<3>
  DU41  M_G_CPU1_SB_CS_N<2>  DDR6_SB_CS2_N  @S9S_MB_2U_LIB.S9S_MB_2U(SCH_1):M_G_CPU1_SB_CS_N<2>
  DY40  M_G_CPU1_SB_CS_N<1>  DDR6_SB_CS1_N  @S9S_MB_2U_LIB.S9S_MB_2U(SCH_1):M_G_CPU1_SB_CS_N<1>
  EA41  M_G_CPU1_SB_CS_N<0>  DDR6_SB_CS0_N  @S9S_MB_2U_LIB.S9S_MB_2U(SCH_1):M_G_CPU1_SB_CS_N<0>
  EA37  M_G_CPU1_SB_CB<7>  DDR6_SB_ECC7  @S9S_MB_2U_LIB.S9S_MB_2U(SCH_1):M_G_CPU1_SB_CB<7>
  DY38  M_G_CPU1_SB_CB<6>  DDR6_SB_ECC6  @S9S_MB_2U_LIB.S9S_MB_2U(SCH_1):M_G_CPU1_SB_CB<6>
  DU37  M_G_CPU1_SB_CB<5>  DDR6_SB_ECC5  @S9S_MB_2U_LIB.S9S_MB_2U(SCH_1):M_G_CPU1_SB_CB<5>
  DV38  M_G_CPU1_SB_CB<4>  DDR6_SB_ECC4  @S9S_MB_2U_LIB.S9S_MB_2U(SCH_1):M_G_CPU1_SB_CB<4>
  DY34  M_G_CPU1_SB_CB<3>  DDR6_SB_ECC3  @S9S_MB_2U_LIB.S9S_MB_2U(SCH_1):M_G_CPU1_SB_CB<3>
  EA35  M_G_CPU1_SB_CB<2>  DDR6_SB_ECC2  @S9S_MB_2U_LIB.S9S_MB_2U(SCH_1):M_G_CPU1_SB_CB<2>
  DV34  M_G_CPU1_SB_CB<1>  DDR6_SB_ECC1  @S9S_MB_2U_LIB.S9S_MB_2U(SCH_1):M_G_CPU1_SB_CB<1>
  DU35  M_G_CPU1_SB_CB<0>  DDR6_SB_ECC0  @S9S_MB_2U_LIB.S9S_MB_2U(SCH_1):M_G_CPU1_SB_CB<0>
  DT42  M_G_CPU1_SB_CA<6>  DDR6_SB_CA6  @S9S_MB_2U_LIB.S9S_MB_2U(SCH_1):M_G_CPU1_SB_CA<6>
  EA43  M_G_CPU1_SB_CA<5>  DDR6_SB_CA5  @S9S_MB_2U_LIB.S9S_MB_2U(SCH_1):M_G_CPU1_SB_CA<5>
  DU43  M_G_CPU1_SB_CA<4>  DDR6_SB_CA4  @S9S_MB_2U_LIB.S9S_MB_2U(SCH_1):M_G_CPU1_SB_CA<4>
  DY44  M_G_CPU1_SB_CA<3>  DDR6_SB_CA3  @S9S_MB_2U_LIB.S9S_MB_2U(SCH_1):M_G_CPU1_SB_CA<3>
  DV44  M_G_CPU1_SB_CA<2>  DDR6_SB_CA2  @S9S_MB_2U_LIB.S9S_MB_2U(SCH_1):M_G_CPU1_SB_CA<2>
  DP44  M_G_CPU1_SB_CA<1>  DDR6_SB_CA1  @S9S_MB_2U_LIB.S9S_MB_2U(SCH_1):M_G_CPU1_SB_CA<1>
  DN43  M_G_CPU1_SB_CA<0>  DDR6_SB_CA0  @S9S_MB_2U_LIB.S9S_MB_2U(SCH_1):M_G_CPU1_SB_CA<0>
  DY47  M_G_CPU1_SA_RSP<1>  DDR6_A_RSP1  @S9S_MB_2U_LIB.S9S_MB_2U(SCH_1):M_G_CPU1_SA_RSP<1>
  EA48  M_G_CPU1_SA_RSP<0>  DDR6_A_RSP0  @S9S_MB_2U_LIB.S9S_MB_2U(SCH_1):M_G_CPU1_SA_RSP<0>
  DL43  M_G_CPU1_SA_PAR  DDR6_SA_PAR  @S9S_MB_2U_LIB.S9S_MB_2U(SCH_1):M_G_CPU1_SA_PAR
  DN58  M_G_CPU1_SA_DQS_DP<9>  DDR6_SA_DQS_DP9  @S9S_MB_2U_LIB.S9S_MB_2U(SCH_1):M_G_CPU1_SA_DQS_DP<9>
  DN64  M_G_CPU1_SA_DQS_DP<8>  DDR6_SA_DQS_DP8  @S9S_MB_2U_LIB.S9S_MB_2U(SCH_1):M_G_CPU1_SA_DQS_DP<8>
  DY61  M_G_CPU1_SA_DQS_DP<7>  DDR6_SA_DQS_DP7  @S9S_MB_2U_LIB.S9S_MB_2U(SCH_1):M_G_CPU1_SA_DQS_DP<7>
  DN70  M_G_CPU1_SA_DQS_DP<6>  DDR6_SA_DQS_DP6  @S9S_MB_2U_LIB.S9S_MB_2U(SCH_1):M_G_CPU1_SA_DQS_DP<6>
  DY73  M_G_CPU1_SA_DQS_DP<5>  DDR6_SA_DQS_DP5  @S9S_MB_2U_LIB.S9S_MB_2U(SCH_1):M_G_CPU1_SA_DQS_DP<5>
  DJ58  M_G_CPU1_SA_DQS_DP<4>  DDR6_SA_DQS_DP4  @S9S_MB_2U_LIB.S9S_MB_2U(SCH_1):M_G_CPU1_SA_DQS_DP<4>
  DJ64  M_G_CPU1_SA_DQS_DP<3>  DDR6_SA_DQS_DP3  @S9S_MB_2U_LIB.S9S_MB_2U(SCH_1):M_G_CPU1_SA_DQS_DP<3>
  DV61  M_G_CPU1_SA_DQS_DP<2>  DDR6_SA_DQS_DP2  @S9S_MB_2U_LIB.S9S_MB_2U(SCH_1):M_G_CPU1_SA_DQS_DP<2>
  DL70  M_G_CPU1_SA_DQS_DP<1>  DDR6_SA_DQS_DP1  @S9S_MB_2U_LIB.S9S_MB_2U(SCH_1):M_G_CPU1_SA_DQS_DP<1>
  DT73  M_G_CPU1_SA_DQS_DP<0>  DDR6_SA_DQS_DP0  @S9S_MB_2U_LIB.S9S_MB_2U(SCH_1):M_G_CPU1_SA_DQS_DP<0>
  DR58  M_G_CPU1_SA_DQS_DN<9>  DDR6_SA_DQS_DN9  @S9S_MB_2U_LIB.S9S_MB_2U(SCH_1):M_G_CPU1_SA_DQS_DN<9>
  DR64  M_G_CPU1_SA_DQS_DN<8>  DDR6_SA_DQS_DN8  @S9S_MB_2U_LIB.S9S_MB_2U(SCH_1):M_G_CPU1_SA_DQS_DN<8>
  EB61  M_G_CPU1_SA_DQS_DN<7>  DDR6_SA_DQS_DN7  @S9S_MB_2U_LIB.S9S_MB_2U(SCH_1):M_G_CPU1_SA_DQS_DN<7>
  DR70  M_G_CPU1_SA_DQS_DN<6>  DDR6_SA_DQS_DN6  @S9S_MB_2U_LIB.S9S_MB_2U(SCH_1):M_G_CPU1_SA_DQS_DN<6>
  EB73  M_G_CPU1_SA_DQS_DN<5>  DDR6_SA_DQS_DN5  @S9S_MB_2U_LIB.S9S_MB_2U(SCH_1):M_G_CPU1_SA_DQS_DN<5>
  DL58  M_G_CPU1_SA_DQS_DN<4>  DDR6_SA_DQS_DN4  @S9S_MB_2U_LIB.S9S_MB_2U(SCH_1):M_G_CPU1_SA_DQS_DN<4>
  DL64  M_G_CPU1_SA_DQS_DN<3>  DDR6_SA_DQS_DN3  @S9S_MB_2U_LIB.S9S_MB_2U(SCH_1):M_G_CPU1_SA_DQS_DN<3>
  DT61  M_G_CPU1_SA_DQS_DN<2>  DDR6_SA_DQS_DN2  @S9S_MB_2U_LIB.S9S_MB_2U(SCH_1):M_G_CPU1_SA_DQS_DN<2>
  DJ70  M_G_CPU1_SA_DQS_DN<1>  DDR6_SA_DQS_DN1  @S9S_MB_2U_LIB.S9S_MB_2U(SCH_1):M_G_CPU1_SA_DQS_DN<1>
  DV73  M_G_CPU1_SA_DQS_DN<0>  DDR6_SA_DQS_DN0  @S9S_MB_2U_LIB.S9S_MB_2U(SCH_1):M_G_CPU1_SA_DQS_DN<0>
  DK71  M_G_CPU1_SA_DQ<9>  DDR6_SA_DQ9  @S9S_MB_2U_LIB.S9S_MB_2U(SCH_1):M_G_CPU1_SA_DQ<9>
  DL72  M_G_CPU1_SA_DQ<8>  DDR6_SA_DQ8  @S9S_MB_2U_LIB.S9S_MB_2U(SCH_1):M_G_CPU1_SA_DQ<8>
  DY71  M_G_CPU1_SA_DQ<7>  DDR6_SA_DQ7  @S9S_MB_2U_LIB.S9S_MB_2U(SCH_1):M_G_CPU1_SA_DQ<7>
  EA72  M_G_CPU1_SA_DQ<6>  DDR6_SA_DQ6  @S9S_MB_2U_LIB.S9S_MB_2U(SCH_1):M_G_CPU1_SA_DQ<6>
  DV71  M_G_CPU1_SA_DQ<5>  DDR6_SA_DQ5  @S9S_MB_2U_LIB.S9S_MB_2U(SCH_1):M_G_CPU1_SA_DQ<5>
  DU72  M_G_CPU1_SA_DQ<4>  DDR6_SA_DQ4  @S9S_MB_2U_LIB.S9S_MB_2U(SCH_1):M_G_CPU1_SA_DQ<4>
  EA74  M_G_CPU1_SA_DQ<3>  DDR6_SA_DQ3  @S9S_MB_2U_LIB.S9S_MB_2U(SCH_1):M_G_CPU1_SA_DQ<3>
  DN62  M_G_CPU1_SA_DQ<31>  DDR6_SA_DQ31  @S9S_MB_2U_LIB.S9S_MB_2U(SCH_1):M_G_CPU1_SA_DQ<31>
  DP63  M_G_CPU1_SA_DQ<30>  DDR6_SA_DQ30  @S9S_MB_2U_LIB.S9S_MB_2U(SCH_1):M_G_CPU1_SA_DQ<30>
  DY75  M_G_CPU1_SA_DQ<2>  DDR6_SA_DQ2  @S9S_MB_2U_LIB.S9S_MB_2U(SCH_1):M_G_CPU1_SA_DQ<2>
  DL62  M_G_CPU1_SA_DQ<29>  DDR6_SA_DQ29  @S9S_MB_2U_LIB.S9S_MB_2U(SCH_1):M_G_CPU1_SA_DQ<29>
  DK63  M_G_CPU1_SA_DQ<28>  DDR6_SA_DQ28  @S9S_MB_2U_LIB.S9S_MB_2U(SCH_1):M_G_CPU1_SA_DQ<28>
  DP65  M_G_CPU1_SA_DQ<27>  DDR6_SA_DQ27  @S9S_MB_2U_LIB.S9S_MB_2U(SCH_1):M_G_CPU1_SA_DQ<27>
  DN66  M_G_CPU1_SA_DQ<26>  DDR6_SA_DQ26  @S9S_MB_2U_LIB.S9S_MB_2U(SCH_1):M_G_CPU1_SA_DQ<26>
  DK65  M_G_CPU1_SA_DQ<25>  DDR6_SA_DQ25  @S9S_MB_2U_LIB.S9S_MB_2U(SCH_1):M_G_CPU1_SA_DQ<25>
  DL66  M_G_CPU1_SA_DQ<24>  DDR6_SA_DQ24  @S9S_MB_2U_LIB.S9S_MB_2U(SCH_1):M_G_CPU1_SA_DQ<24>
  DY59  M_G_CPU1_SA_DQ<23>  DDR6_SA_DQ23  @S9S_MB_2U_LIB.S9S_MB_2U(SCH_1):M_G_CPU1_SA_DQ<23>
  EA60  M_G_CPU1_SA_DQ<22>  DDR6_SA_DQ22  @S9S_MB_2U_LIB.S9S_MB_2U(SCH_1):M_G_CPU1_SA_DQ<22>
  DV59  M_G_CPU1_SA_DQ<21>  DDR6_SA_DQ21  @S9S_MB_2U_LIB.S9S_MB_2U(SCH_1):M_G_CPU1_SA_DQ<21>
  DU60  M_G_CPU1_SA_DQ<20>  DDR6_SA_DQ20  @S9S_MB_2U_LIB.S9S_MB_2U(SCH_1):M_G_CPU1_SA_DQ<20>
  DU74  M_G_CPU1_SA_DQ<1>  DDR6_SA_DQ1  @S9S_MB_2U_LIB.S9S_MB_2U(SCH_1):M_G_CPU1_SA_DQ<1>
  EA62  M_G_CPU1_SA_DQ<19>  DDR6_SA_DQ19  @S9S_MB_2U_LIB.S9S_MB_2U(SCH_1):M_G_CPU1_SA_DQ<19>
  DY63  M_G_CPU1_SA_DQ<18>  DDR6_SA_DQ18  @S9S_MB_2U_LIB.S9S_MB_2U(SCH_1):M_G_CPU1_SA_DQ<18>
  DU62  M_G_CPU1_SA_DQ<17>  DDR6_SA_DQ17  @S9S_MB_2U_LIB.S9S_MB_2U(SCH_1):M_G_CPU1_SA_DQ<17>
  DV63  M_G_CPU1_SA_DQ<16>  DDR6_SA_DQ16  @S9S_MB_2U_LIB.S9S_MB_2U(SCH_1):M_G_CPU1_SA_DQ<16>
  DN68  M_G_CPU1_SA_DQ<15>  DDR6_SA_DQ15  @S9S_MB_2U_LIB.S9S_MB_2U(SCH_1):M_G_CPU1_SA_DQ<15>
  DP69  M_G_CPU1_SA_DQ<14>  DDR6_SA_DQ14  @S9S_MB_2U_LIB.S9S_MB_2U(SCH_1):M_G_CPU1_SA_DQ<14>
  DL68  M_G_CPU1_SA_DQ<13>  DDR6_SA_DQ13  @S9S_MB_2U_LIB.S9S_MB_2U(SCH_1):M_G_CPU1_SA_DQ<13>
  DK69  M_G_CPU1_SA_DQ<12>  DDR6_SA_DQ12  @S9S_MB_2U_LIB.S9S_MB_2U(SCH_1):M_G_CPU1_SA_DQ<12>
  DP71  M_G_CPU1_SA_DQ<11>  DDR6_SA_DQ11  @S9S_MB_2U_LIB.S9S_MB_2U(SCH_1):M_G_CPU1_SA_DQ<11>
  DN72  M_G_CPU1_SA_DQ<10>  DDR6_SA_DQ10  @S9S_MB_2U_LIB.S9S_MB_2U(SCH_1):M_G_CPU1_SA_DQ<10>
  DV75  M_G_CPU1_SA_DQ<0>  DDR6_SA_DQ0  @S9S_MB_2U_LIB.S9S_MB_2U(SCH_1):M_G_CPU1_SA_DQ<0>
  DK53  M_G_CPU1_SA_CS_N<3>  DDR6_SA_CS3_N  @S9S_MB_2U_LIB.S9S_MB_2U(SCH_1):M_G_CPU1_SA_CS_N<3>
  DL54  M_G_CPU1_SA_CS_N<2>  DDR6_SA_CS2_N  @S9S_MB_2U_LIB.S9S_MB_2U(SCH_1):M_G_CPU1_SA_CS_N<2>
  DP53  M_G_CPU1_SA_CS_N<1>  DDR6_SA_CS1_N  @S9S_MB_2U_LIB.S9S_MB_2U(SCH_1):M_G_CPU1_SA_CS_N<1>
  DN54  M_G_CPU1_SA_CS_N<0>  DDR6_SA_CS0_N  @S9S_MB_2U_LIB.S9S_MB_2U(SCH_1):M_G_CPU1_SA_CS_N<0>
  DN56  M_G_CPU1_SA_CB<7>  DDR6_SA_ECC7  @S9S_MB_2U_LIB.S9S_MB_2U(SCH_1):M_G_CPU1_SA_CB<7>
  DP57  M_G_CPU1_SA_CB<6>  DDR6_SA_ECC6  @S9S_MB_2U_LIB.S9S_MB_2U(SCH_1):M_G_CPU1_SA_CB<6>
  DL56  M_G_CPU1_SA_CB<5>  DDR6_SA_ECC5  @S9S_MB_2U_LIB.S9S_MB_2U(SCH_1):M_G_CPU1_SA_CB<5>
  DK57  M_G_CPU1_SA_CB<4>  DDR6_SA_ECC4  @S9S_MB_2U_LIB.S9S_MB_2U(SCH_1):M_G_CPU1_SA_CB<4>
  DP59  M_G_CPU1_SA_CB<3>  DDR6_SA_ECC3  @S9S_MB_2U_LIB.S9S_MB_2U(SCH_1):M_G_CPU1_SA_CB<3>
  DN60  M_G_CPU1_SA_CB<2>  DDR6_SA_ECC2  @S9S_MB_2U_LIB.S9S_MB_2U(SCH_1):M_G_CPU1_SA_CB<2>
  DK59  M_G_CPU1_SA_CB<1>  DDR6_SA_ECC1  @S9S_MB_2U_LIB.S9S_MB_2U(SCH_1):M_G_CPU1_SA_CB<1>
  DL60  M_G_CPU1_SA_CB<0>  DDR6_SA_ECC0  @S9S_MB_2U_LIB.S9S_MB_2U(SCH_1):M_G_CPU1_SA_CB<0>
  DK44  M_G_CPU1_SA_CA<6>  DDR6_SA_CA6  @S9S_MB_2U_LIB.S9S_MB_2U(SCH_1):M_G_CPU1_SA_CA<6>
  DN50  M_G_CPU1_SA_CA<5>  DDR6_SA_CA5  @S9S_MB_2U_LIB.S9S_MB_2U(SCH_1):M_G_CPU1_SA_CA<5>
  DL50  M_G_CPU1_SA_CA<4>  DDR6_SA_CA4  @S9S_MB_2U_LIB.S9S_MB_2U(SCH_1):M_G_CPU1_SA_CA<4>
  DP51  M_G_CPU1_SA_CA<3>  DDR6_SA_CA3  @S9S_MB_2U_LIB.S9S_MB_2U(SCH_1):M_G_CPU1_SA_CA<3>
  DK51  M_G_CPU1_SA_CA<2>  DDR6_SA_CA2  @S9S_MB_2U_LIB.S9S_MB_2U(SCH_1):M_G_CPU1_SA_CA<2>
  DR52  M_G_CPU1_SA_CA<1>  DDR6_SA_CA1  @S9S_MB_2U_LIB.S9S_MB_2U(SCH_1):M_G_CPU1_SA_CA<1>
  DJ52  M_G_CPU1_SA_CA<0>  DDR6_SA_CA0  @S9S_MB_2U_LIB.S9S_MB_2U(SCH_1):M_G_CPU1_SA_CA<0>
  DJ45  M_G_CPU1_CLK_DP<1>  DDR6_CLK_DP1  @S9S_MB_2U_LIB.S9S_MB_2U(SCH_1):M_G_CPU1_CLK_DP<1>
  DN45  M_G_CPU1_CLK_DP<0>  DDR6_CLK_DP0  @S9S_MB_2U_LIB.S9S_MB_2U(SCH_1):M_G_CPU1_CLK_DP<0>
  DL45  M_G_CPU1_CLK_DN<1>  DDR6_CLK_DN1  @S9S_MB_2U_LIB.S9S_MB_2U(SCH_1):M_G_CPU1_CLK_DN<1>
  DR45  M_G_CPU1_CLK_DN<0>  DDR6_CLK_DN0  @S9S_MB_2U_LIB.S9S_MB_2U(SCH_1):M_G_CPU1_CLK_DN<0>
  CW50  M_G_CPU1_ALERT_N  DDR6_ALERT_N  @S9S_MB_2U_LIB.S9S_MB_2U(SCH_1):M_G_CPU1_ALERT_N

SOCKET4677_AZIFS054P001C01  I168  U1     [SOCKET4677_AZIFS054P001C01-SOCA]
  DK47  M_F_CPU1_SB_RSP<1>  DDR5_B_RSP1  @S9S_MB_2U_LIB.S9S_MB_2U(SCH_1):M_F_CPU1_SB_RSP<1>
  DL48  M_F_CPU1_SB_RSP<0>  DDR5_B_RSP0  @S9S_MB_2U_LIB.S9S_MB_2U(SCH_1):M_F_CPU1_SB_RSP<0>
  EJ39  M_F_CPU1_SB_PAR  DDR5_SB_PAR  @S9S_MB_2U_LIB.S9S_MB_2U(SCH_1):M_F_CPU1_SB_PAR
  EC33  M_F_CPU1_SB_DQS_DP<9>  DDR5_SB_DQS_DP9  @S9S_MB_2U_LIB.S9S_MB_2U(SCH_1):M_F_CPU1_SB_DQS_DP<9>
  EB18  M_F_CPU1_SB_DQS_DP<8>  DDR5_SB_DQS_DP8  @S9S_MB_2U_LIB.S9S_MB_2U(SCH_1):M_F_CPU1_SB_DQS_DP<8>
  EP12  M_F_CPU1_SB_DQS_DP<7>  DDR5_SB_DQS_DP7  @S9S_MB_2U_LIB.S9S_MB_2U(SCH_1):M_F_CPU1_SB_DQS_DP<7>
  EG21  M_F_CPU1_SB_DQS_DP<6>  DDR5_SB_DQS_DP6  @S9S_MB_2U_LIB.S9S_MB_2U(SCH_1):M_F_CPU1_SB_DQS_DP<6>
  DY30  M_F_CPU1_SB_DQS_DP<5>  DDR5_SB_DQS_DP5  @S9S_MB_2U_LIB.S9S_MB_2U(SCH_1):M_F_CPU1_SB_DQS_DP<5>
  EG33  M_F_CPU1_SB_DQS_DP<4>  DDR5_SB_DQS_DP4  @S9S_MB_2U_LIB.S9S_MB_2U(SCH_1):M_F_CPU1_SB_DQS_DP<4>
  DV18  M_F_CPU1_SB_DQS_DP<3>  DDR5_SB_DQS_DP3  @S9S_MB_2U_LIB.S9S_MB_2U(SCH_1):M_F_CPU1_SB_DQS_DP<3>
  EK12  M_F_CPU1_SB_DQS_DP<2>  DDR5_SB_DQS_DP2  @S9S_MB_2U_LIB.S9S_MB_2U(SCH_1):M_F_CPU1_SB_DQS_DP<2>
  EC21  M_F_CPU1_SB_DQS_DP<1>  DDR5_SB_DQS_DP1  @S9S_MB_2U_LIB.S9S_MB_2U(SCH_1):M_F_CPU1_SB_DQS_DP<1>
  DT30  M_F_CPU1_SB_DQS_DP<0>  DDR5_SB_DQS_DP0  @S9S_MB_2U_LIB.S9S_MB_2U(SCH_1):M_F_CPU1_SB_DQS_DP<0>
  EE33  M_F_CPU1_SB_DQS_DN<9>  DDR5_SB_DQS_DN9  @S9S_MB_2U_LIB.S9S_MB_2U(SCH_1):M_F_CPU1_SB_DQS_DN<9>
  DY18  M_F_CPU1_SB_DQS_DN<8>  DDR5_SB_DQS_DN8  @S9S_MB_2U_LIB.S9S_MB_2U(SCH_1):M_F_CPU1_SB_DQS_DN<8>
  ET12  M_F_CPU1_SB_DQS_DN<7>  DDR5_SB_DQS_DN7  @S9S_MB_2U_LIB.S9S_MB_2U(SCH_1):M_F_CPU1_SB_DQS_DN<7>
  EJ21  M_F_CPU1_SB_DQS_DN<6>  DDR5_SB_DQS_DN6  @S9S_MB_2U_LIB.S9S_MB_2U(SCH_1):M_F_CPU1_SB_DQS_DN<6>
  EB30  M_F_CPU1_SB_DQS_DN<5>  DDR5_SB_DQS_DN5  @S9S_MB_2U_LIB.S9S_MB_2U(SCH_1):M_F_CPU1_SB_DQS_DN<5>
  EJ33  M_F_CPU1_SB_DQS_DN<4>  DDR5_SB_DQS_DN4  @S9S_MB_2U_LIB.S9S_MB_2U(SCH_1):M_F_CPU1_SB_DQS_DN<4>
  DT18  M_F_CPU1_SB_DQS_DN<3>  DDR5_SB_DQS_DN3  @S9S_MB_2U_LIB.S9S_MB_2U(SCH_1):M_F_CPU1_SB_DQS_DN<3>
  EM12  M_F_CPU1_SB_DQS_DN<2>  DDR5_SB_DQS_DN2  @S9S_MB_2U_LIB.S9S_MB_2U(SCH_1):M_F_CPU1_SB_DQS_DN<2>
  EE21  M_F_CPU1_SB_DQS_DN<1>  DDR5_SB_DQS_DN1  @S9S_MB_2U_LIB.S9S_MB_2U(SCH_1):M_F_CPU1_SB_DQS_DN<1>
  DV30  M_F_CPU1_SB_DQS_DN<0>  DDR5_SB_DQS_DN0  @S9S_MB_2U_LIB.S9S_MB_2U(SCH_1):M_F_CPU1_SB_DQS_DN<0>
  ED22  M_F_CPU1_SB_DQ<9>  DDR5_SB_DQ9  @S9S_MB_2U_LIB.S9S_MB_2U(SCH_1):M_F_CPU1_SB_DQ<9>
  EE23  M_F_CPU1_SB_DQ<8>  DDR5_SB_DQ8  @S9S_MB_2U_LIB.S9S_MB_2U(SCH_1):M_F_CPU1_SB_DQ<8>
  DY28  M_F_CPU1_SB_DQ<7>  DDR5_SB_DQ7  @S9S_MB_2U_LIB.S9S_MB_2U(SCH_1):M_F_CPU1_SB_DQ<7>
  EA29  M_F_CPU1_SB_DQ<6>  DDR5_SB_DQ6  @S9S_MB_2U_LIB.S9S_MB_2U(SCH_1):M_F_CPU1_SB_DQ<6>
  DV28  M_F_CPU1_SB_DQ<5>  DDR5_SB_DQ5  @S9S_MB_2U_LIB.S9S_MB_2U(SCH_1):M_F_CPU1_SB_DQ<5>
  DU29  M_F_CPU1_SB_DQ<4>  DDR5_SB_DQ4  @S9S_MB_2U_LIB.S9S_MB_2U(SCH_1):M_F_CPU1_SB_DQ<4>
  EA31  M_F_CPU1_SB_DQ<3>  DDR5_SB_DQ3  @S9S_MB_2U_LIB.S9S_MB_2U(SCH_1):M_F_CPU1_SB_DQ<3>
  DR17  M_F_CPU1_SB_DQ<31>  DDR5_SB_DQ31  @S9S_MB_2U_LIB.S9S_MB_2U(SCH_1):M_F_CPU1_SB_DQ<31>
  EC17  M_F_CPU1_SB_DQ<30>  DDR5_SB_DQ30  @S9S_MB_2U_LIB.S9S_MB_2U(SCH_1):M_F_CPU1_SB_DQ<30>
  DY32  M_F_CPU1_SB_DQ<2>  DDR5_SB_DQ2  @S9S_MB_2U_LIB.S9S_MB_2U(SCH_1):M_F_CPU1_SB_DQ<2>
  DU17  M_F_CPU1_SB_DQ<29>  DDR5_SB_DQ29  @S9S_MB_2U_LIB.S9S_MB_2U(SCH_1):M_F_CPU1_SB_DQ<29>
  EA17  M_F_CPU1_SB_DQ<28>  DDR5_SB_DQ28  @S9S_MB_2U_LIB.S9S_MB_2U(SCH_1):M_F_CPU1_SB_DQ<28>
  EA19  M_F_CPU1_SB_DQ<27>  DDR5_SB_DQ27  @S9S_MB_2U_LIB.S9S_MB_2U(SCH_1):M_F_CPU1_SB_DQ<27>
  DY20  M_F_CPU1_SB_DQ<26>  DDR5_SB_DQ26  @S9S_MB_2U_LIB.S9S_MB_2U(SCH_1):M_F_CPU1_SB_DQ<26>
  DU19  M_F_CPU1_SB_DQ<25>  DDR5_SB_DQ25  @S9S_MB_2U_LIB.S9S_MB_2U(SCH_1):M_F_CPU1_SB_DQ<25>
  DV20  M_F_CPU1_SB_DQ<24>  DDR5_SB_DQ24  @S9S_MB_2U_LIB.S9S_MB_2U(SCH_1):M_F_CPU1_SB_DQ<24>
  EP10  M_F_CPU1_SB_DQ<23>  DDR5_SB_DQ23  @S9S_MB_2U_LIB.S9S_MB_2U(SCH_1):M_F_CPU1_SB_DQ<23>
  ER11  M_F_CPU1_SB_DQ<22>  DDR5_SB_DQ22  @S9S_MB_2U_LIB.S9S_MB_2U(SCH_1):M_F_CPU1_SB_DQ<22>
  EM10  M_F_CPU1_SB_DQ<21>  DDR5_SB_DQ21  @S9S_MB_2U_LIB.S9S_MB_2U(SCH_1):M_F_CPU1_SB_DQ<21>
  EL11  M_F_CPU1_SB_DQ<20>  DDR5_SB_DQ20  @S9S_MB_2U_LIB.S9S_MB_2U(SCH_1):M_F_CPU1_SB_DQ<20>
  DU31  M_F_CPU1_SB_DQ<1>  DDR5_SB_DQ1  @S9S_MB_2U_LIB.S9S_MB_2U(SCH_1):M_F_CPU1_SB_DQ<1>
  ER13  M_F_CPU1_SB_DQ<19>  DDR5_SB_DQ19  @S9S_MB_2U_LIB.S9S_MB_2U(SCH_1):M_F_CPU1_SB_DQ<19>
  EP14  M_F_CPU1_SB_DQ<18>  DDR5_SB_DQ18  @S9S_MB_2U_LIB.S9S_MB_2U(SCH_1):M_F_CPU1_SB_DQ<18>
  EL13  M_F_CPU1_SB_DQ<17>  DDR5_SB_DQ17  @S9S_MB_2U_LIB.S9S_MB_2U(SCH_1):M_F_CPU1_SB_DQ<17>
  EM14  M_F_CPU1_SB_DQ<16>  DDR5_SB_DQ16  @S9S_MB_2U_LIB.S9S_MB_2U(SCH_1):M_F_CPU1_SB_DQ<16>
  EG19  M_F_CPU1_SB_DQ<15>  DDR5_SB_DQ15  @S9S_MB_2U_LIB.S9S_MB_2U(SCH_1):M_F_CPU1_SB_DQ<15>
  EH20  M_F_CPU1_SB_DQ<14>  DDR5_SB_DQ14  @S9S_MB_2U_LIB.S9S_MB_2U(SCH_1):M_F_CPU1_SB_DQ<14>
  EE19  M_F_CPU1_SB_DQ<13>  DDR5_SB_DQ13  @S9S_MB_2U_LIB.S9S_MB_2U(SCH_1):M_F_CPU1_SB_DQ<13>
  ED20  M_F_CPU1_SB_DQ<12>  DDR5_SB_DQ12  @S9S_MB_2U_LIB.S9S_MB_2U(SCH_1):M_F_CPU1_SB_DQ<12>
  EH22  M_F_CPU1_SB_DQ<11>  DDR5_SB_DQ11  @S9S_MB_2U_LIB.S9S_MB_2U(SCH_1):M_F_CPU1_SB_DQ<11>
  EG23  M_F_CPU1_SB_DQ<10>  DDR5_SB_DQ10  @S9S_MB_2U_LIB.S9S_MB_2U(SCH_1):M_F_CPU1_SB_DQ<10>
  DV32  M_F_CPU1_SB_DQ<0>  DDR5_SB_DQ0  @S9S_MB_2U_LIB.S9S_MB_2U(SCH_1):M_F_CPU1_SB_DQ<0>
  EE37  M_F_CPU1_SB_CS_N<3>  DDR5_SB_CS3_N  @S9S_MB_2U_LIB.S9S_MB_2U(SCH_1):M_F_CPU1_SB_CS_N<3>
  ED38  M_F_CPU1_SB_CS_N<2>  DDR5_SB_CS2_N  @S9S_MB_2U_LIB.S9S_MB_2U(SCH_1):M_F_CPU1_SB_CS_N<2>
  EG37  M_F_CPU1_SB_CS_N<1>  DDR5_SB_CS1_N  @S9S_MB_2U_LIB.S9S_MB_2U(SCH_1):M_F_CPU1_SB_CS_N<1>
  EH38  M_F_CPU1_SB_CS_N<0>  DDR5_SB_CS0_N  @S9S_MB_2U_LIB.S9S_MB_2U(SCH_1):M_F_CPU1_SB_CS_N<0>
  EH34  M_F_CPU1_SB_CB<7>  DDR5_SB_ECC7  @S9S_MB_2U_LIB.S9S_MB_2U(SCH_1):M_F_CPU1_SB_CB<7>
  EG35  M_F_CPU1_SB_CB<6>  DDR5_SB_ECC6  @S9S_MB_2U_LIB.S9S_MB_2U(SCH_1):M_F_CPU1_SB_CB<6>
  ED34  M_F_CPU1_SB_CB<5>  DDR5_SB_ECC5  @S9S_MB_2U_LIB.S9S_MB_2U(SCH_1):M_F_CPU1_SB_CB<5>
  EE35  M_F_CPU1_SB_CB<4>  DDR5_SB_ECC4  @S9S_MB_2U_LIB.S9S_MB_2U(SCH_1):M_F_CPU1_SB_CB<4>
  EG31  M_F_CPU1_SB_CB<3>  DDR5_SB_ECC3  @S9S_MB_2U_LIB.S9S_MB_2U(SCH_1):M_F_CPU1_SB_CB<3>
  EH32  M_F_CPU1_SB_CB<2>  DDR5_SB_ECC2  @S9S_MB_2U_LIB.S9S_MB_2U(SCH_1):M_F_CPU1_SB_CB<2>
  EE31  M_F_CPU1_SB_CB<1>  DDR5_SB_ECC1  @S9S_MB_2U_LIB.S9S_MB_2U(SCH_1):M_F_CPU1_SB_CB<1>
  ED32  M_F_CPU1_SB_CB<0>  DDR5_SB_ECC0  @S9S_MB_2U_LIB.S9S_MB_2U(SCH_1):M_F_CPU1_SB_CB<0>
  EC39  M_F_CPU1_SB_CA<6>  DDR5_SB_CA6  @S9S_MB_2U_LIB.S9S_MB_2U(SCH_1):M_F_CPU1_SB_CA<6>
  EH40  M_F_CPU1_SB_CA<5>  DDR5_SB_CA5  @S9S_MB_2U_LIB.S9S_MB_2U(SCH_1):M_F_CPU1_SB_CA<5>
  ED40  M_F_CPU1_SB_CA<4>  DDR5_SB_CA4  @S9S_MB_2U_LIB.S9S_MB_2U(SCH_1):M_F_CPU1_SB_CA<4>
  EG41  M_F_CPU1_SB_CA<3>  DDR5_SB_CA3  @S9S_MB_2U_LIB.S9S_MB_2U(SCH_1):M_F_CPU1_SB_CA<3>
  EE41  M_F_CPU1_SB_CA<2>  DDR5_SB_CA2  @S9S_MB_2U_LIB.S9S_MB_2U(SCH_1):M_F_CPU1_SB_CA<2>
  DU50  M_F_CPU1_SB_CA<1>  DDR5_SB_CA1  @S9S_MB_2U_LIB.S9S_MB_2U(SCH_1):M_F_CPU1_SB_CA<1>
  DV51  M_F_CPU1_SB_CA<0>  DDR5_SB_CA0  @S9S_MB_2U_LIB.S9S_MB_2U(SCH_1):M_F_CPU1_SB_CA<0>
  DP47  M_F_CPU1_SA_RSP<1>  DDR5_A_RSP1  @S9S_MB_2U_LIB.S9S_MB_2U(SCH_1):M_F_CPU1_SA_RSP<1>
  DN48  M_F_CPU1_SA_RSP<0>  DDR5_A_RSP0  @S9S_MB_2U_LIB.S9S_MB_2U(SCH_1):M_F_CPU1_SA_RSP<0>
  EA50  M_F_CPU1_SA_PAR  DDR5_SA_PAR  @S9S_MB_2U_LIB.S9S_MB_2U(SCH_1):M_F_CPU1_SA_PAR
  EG58  M_F_CPU1_SA_DQS_DP<9>  DDR5_SA_DQS_DP9  @S9S_MB_2U_LIB.S9S_MB_2U(SCH_1):M_F_CPU1_SA_DQS_DP<9>
  DY55  M_F_CPU1_SA_DQS_DP<8>  DDR5_SA_DQS_DP8  @S9S_MB_2U_LIB.S9S_MB_2U(SCH_1):M_F_CPU1_SA_DQS_DP<8>
  EG64  M_F_CPU1_SA_DQS_DP<7>  DDR5_SA_DQS_DP7  @S9S_MB_2U_LIB.S9S_MB_2U(SCH_1):M_F_CPU1_SA_DQS_DP<7>
  DY67  M_F_CPU1_SA_DQS_DP<6>  DDR5_SA_DQS_DP6  @S9S_MB_2U_LIB.S9S_MB_2U(SCH_1):M_F_CPU1_SA_DQS_DP<6>
  EG76  M_F_CPU1_SA_DQS_DP<5>  DDR5_SA_DQS_DP5  @S9S_MB_2U_LIB.S9S_MB_2U(SCH_1):M_F_CPU1_SA_DQS_DP<5>
  EC58  M_F_CPU1_SA_DQS_DP<4>  DDR5_SA_DQS_DP4  @S9S_MB_2U_LIB.S9S_MB_2U(SCH_1):M_F_CPU1_SA_DQS_DP<4>
  DT55  M_F_CPU1_SA_DQS_DP<3>  DDR5_SA_DQS_DP3  @S9S_MB_2U_LIB.S9S_MB_2U(SCH_1):M_F_CPU1_SA_DQS_DP<3>
  EE64  M_F_CPU1_SA_DQS_DP<2>  DDR5_SA_DQS_DP2  @S9S_MB_2U_LIB.S9S_MB_2U(SCH_1):M_F_CPU1_SA_DQS_DP<2>
  DV67  M_F_CPU1_SA_DQS_DP<1>  DDR5_SA_DQS_DP1  @S9S_MB_2U_LIB.S9S_MB_2U(SCH_1):M_F_CPU1_SA_DQS_DP<1>
  EC76  M_F_CPU1_SA_DQS_DP<0>  DDR5_SA_DQS_DP0  @S9S_MB_2U_LIB.S9S_MB_2U(SCH_1):M_F_CPU1_SA_DQS_DP<0>
  EJ58  M_F_CPU1_SA_DQS_DN<9>  DDR5_SA_DQS_DN9  @S9S_MB_2U_LIB.S9S_MB_2U(SCH_1):M_F_CPU1_SA_DQS_DN<9>
  EB55  M_F_CPU1_SA_DQS_DN<8>  DDR5_SA_DQS_DN8  @S9S_MB_2U_LIB.S9S_MB_2U(SCH_1):M_F_CPU1_SA_DQS_DN<8>
  EJ64  M_F_CPU1_SA_DQS_DN<7>  DDR5_SA_DQS_DN7  @S9S_MB_2U_LIB.S9S_MB_2U(SCH_1):M_F_CPU1_SA_DQS_DN<7>
  EB67  M_F_CPU1_SA_DQS_DN<6>  DDR5_SA_DQS_DN6  @S9S_MB_2U_LIB.S9S_MB_2U(SCH_1):M_F_CPU1_SA_DQS_DN<6>
  EJ76  M_F_CPU1_SA_DQS_DN<5>  DDR5_SA_DQS_DN5  @S9S_MB_2U_LIB.S9S_MB_2U(SCH_1):M_F_CPU1_SA_DQS_DN<5>
  EE58  M_F_CPU1_SA_DQS_DN<4>  DDR5_SA_DQS_DN4  @S9S_MB_2U_LIB.S9S_MB_2U(SCH_1):M_F_CPU1_SA_DQS_DN<4>
  DV55  M_F_CPU1_SA_DQS_DN<3>  DDR5_SA_DQS_DN3  @S9S_MB_2U_LIB.S9S_MB_2U(SCH_1):M_F_CPU1_SA_DQS_DN<3>
  EC64  M_F_CPU1_SA_DQS_DN<2>  DDR5_SA_DQS_DN2  @S9S_MB_2U_LIB.S9S_MB_2U(SCH_1):M_F_CPU1_SA_DQS_DN<2>
  DT67  M_F_CPU1_SA_DQS_DN<1>  DDR5_SA_DQS_DN1  @S9S_MB_2U_LIB.S9S_MB_2U(SCH_1):M_F_CPU1_SA_DQS_DN<1>
  EE76  M_F_CPU1_SA_DQS_DN<0>  DDR5_SA_DQS_DN0  @S9S_MB_2U_LIB.S9S_MB_2U(SCH_1):M_F_CPU1_SA_DQS_DN<0>
  DU68  M_F_CPU1_SA_DQ<9>  DDR5_SA_DQ9  @S9S_MB_2U_LIB.S9S_MB_2U(SCH_1):M_F_CPU1_SA_DQ<9>
  DV69  M_F_CPU1_SA_DQ<8>  DDR5_SA_DQ8  @S9S_MB_2U_LIB.S9S_MB_2U(SCH_1):M_F_CPU1_SA_DQ<8>
  EG74  M_F_CPU1_SA_DQ<7>  DDR5_SA_DQ7  @S9S_MB_2U_LIB.S9S_MB_2U(SCH_1):M_F_CPU1_SA_DQ<7>
  EH75  M_F_CPU1_SA_DQ<6>  DDR5_SA_DQ6  @S9S_MB_2U_LIB.S9S_MB_2U(SCH_1):M_F_CPU1_SA_DQ<6>
  EE74  M_F_CPU1_SA_DQ<5>  DDR5_SA_DQ5  @S9S_MB_2U_LIB.S9S_MB_2U(SCH_1):M_F_CPU1_SA_DQ<5>
  ED75  M_F_CPU1_SA_DQ<4>  DDR5_SA_DQ4  @S9S_MB_2U_LIB.S9S_MB_2U(SCH_1):M_F_CPU1_SA_DQ<4>
  EG78  M_F_CPU1_SA_DQ<3>  DDR5_SA_DQ3  @S9S_MB_2U_LIB.S9S_MB_2U(SCH_1):M_F_CPU1_SA_DQ<3>
  DY53  M_F_CPU1_SA_DQ<31>  DDR5_SA_DQ31  @S9S_MB_2U_LIB.S9S_MB_2U(SCH_1):M_F_CPU1_SA_DQ<31>
  EA54  M_F_CPU1_SA_DQ<30>  DDR5_SA_DQ30  @S9S_MB_2U_LIB.S9S_MB_2U(SCH_1):M_F_CPU1_SA_DQ<30>
  ED77  M_F_CPU1_SA_DQ<2>  DDR5_SA_DQ2  @S9S_MB_2U_LIB.S9S_MB_2U(SCH_1):M_F_CPU1_SA_DQ<2>
  DV53  M_F_CPU1_SA_DQ<29>  DDR5_SA_DQ29  @S9S_MB_2U_LIB.S9S_MB_2U(SCH_1):M_F_CPU1_SA_DQ<29>
  DU54  M_F_CPU1_SA_DQ<28>  DDR5_SA_DQ28  @S9S_MB_2U_LIB.S9S_MB_2U(SCH_1):M_F_CPU1_SA_DQ<28>
  EA56  M_F_CPU1_SA_DQ<27>  DDR5_SA_DQ27  @S9S_MB_2U_LIB.S9S_MB_2U(SCH_1):M_F_CPU1_SA_DQ<27>
  DY57  M_F_CPU1_SA_DQ<26>  DDR5_SA_DQ26  @S9S_MB_2U_LIB.S9S_MB_2U(SCH_1):M_F_CPU1_SA_DQ<26>
  DU56  M_F_CPU1_SA_DQ<25>  DDR5_SA_DQ25  @S9S_MB_2U_LIB.S9S_MB_2U(SCH_1):M_F_CPU1_SA_DQ<25>
  DV57  M_F_CPU1_SA_DQ<24>  DDR5_SA_DQ24  @S9S_MB_2U_LIB.S9S_MB_2U(SCH_1):M_F_CPU1_SA_DQ<24>
  EG62  M_F_CPU1_SA_DQ<23>  DDR5_SA_DQ23  @S9S_MB_2U_LIB.S9S_MB_2U(SCH_1):M_F_CPU1_SA_DQ<23>
  EH63  M_F_CPU1_SA_DQ<22>  DDR5_SA_DQ22  @S9S_MB_2U_LIB.S9S_MB_2U(SCH_1):M_F_CPU1_SA_DQ<22>
  EE62  M_F_CPU1_SA_DQ<21>  DDR5_SA_DQ21  @S9S_MB_2U_LIB.S9S_MB_2U(SCH_1):M_F_CPU1_SA_DQ<21>
  ED63  M_F_CPU1_SA_DQ<20>  DDR5_SA_DQ20  @S9S_MB_2U_LIB.S9S_MB_2U(SCH_1):M_F_CPU1_SA_DQ<20>
  EH77  M_F_CPU1_SA_DQ<1>  DDR5_SA_DQ1  @S9S_MB_2U_LIB.S9S_MB_2U(SCH_1):M_F_CPU1_SA_DQ<1>
  EH65  M_F_CPU1_SA_DQ<19>  DDR5_SA_DQ19  @S9S_MB_2U_LIB.S9S_MB_2U(SCH_1):M_F_CPU1_SA_DQ<19>
  EG66  M_F_CPU1_SA_DQ<18>  DDR5_SA_DQ18  @S9S_MB_2U_LIB.S9S_MB_2U(SCH_1):M_F_CPU1_SA_DQ<18>
  ED65  M_F_CPU1_SA_DQ<17>  DDR5_SA_DQ17  @S9S_MB_2U_LIB.S9S_MB_2U(SCH_1):M_F_CPU1_SA_DQ<17>
  EE66  M_F_CPU1_SA_DQ<16>  DDR5_SA_DQ16  @S9S_MB_2U_LIB.S9S_MB_2U(SCH_1):M_F_CPU1_SA_DQ<16>
  DY65  M_F_CPU1_SA_DQ<15>  DDR5_SA_DQ15  @S9S_MB_2U_LIB.S9S_MB_2U(SCH_1):M_F_CPU1_SA_DQ<15>
  EA66  M_F_CPU1_SA_DQ<14>  DDR5_SA_DQ14  @S9S_MB_2U_LIB.S9S_MB_2U(SCH_1):M_F_CPU1_SA_DQ<14>
  DV65  M_F_CPU1_SA_DQ<13>  DDR5_SA_DQ13  @S9S_MB_2U_LIB.S9S_MB_2U(SCH_1):M_F_CPU1_SA_DQ<13>
  DU66  M_F_CPU1_SA_DQ<12>  DDR5_SA_DQ12  @S9S_MB_2U_LIB.S9S_MB_2U(SCH_1):M_F_CPU1_SA_DQ<12>
  EA68  M_F_CPU1_SA_DQ<11>  DDR5_SA_DQ11  @S9S_MB_2U_LIB.S9S_MB_2U(SCH_1):M_F_CPU1_SA_DQ<11>
  DY69  M_F_CPU1_SA_DQ<10>  DDR5_SA_DQ10  @S9S_MB_2U_LIB.S9S_MB_2U(SCH_1):M_F_CPU1_SA_DQ<10>
  EB77  M_F_CPU1_SA_DQ<0>  DDR5_SA_DQ0  @S9S_MB_2U_LIB.S9S_MB_2U(SCH_1):M_F_CPU1_SA_DQ<0>
  ED53  M_F_CPU1_SA_CS_N<3>  DDR5_SA_CS3_N  @S9S_MB_2U_LIB.S9S_MB_2U(SCH_1):M_F_CPU1_SA_CS_N<3>
  EE54  M_F_CPU1_SA_CS_N<2>  DDR5_SA_CS2_N  @S9S_MB_2U_LIB.S9S_MB_2U(SCH_1):M_F_CPU1_SA_CS_N<2>
  EH53  M_F_CPU1_SA_CS_N<1>  DDR5_SA_CS1_N  @S9S_MB_2U_LIB.S9S_MB_2U(SCH_1):M_F_CPU1_SA_CS_N<1>
  EG54  M_F_CPU1_SA_CS_N<0>  DDR5_SA_CS0_N  @S9S_MB_2U_LIB.S9S_MB_2U(SCH_1):M_F_CPU1_SA_CS_N<0>
  EG56  M_F_CPU1_SA_CB<7>  DDR5_SA_ECC7  @S9S_MB_2U_LIB.S9S_MB_2U(SCH_1):M_F_CPU1_SA_CB<7>
  EH57  M_F_CPU1_SA_CB<6>  DDR5_SA_ECC6  @S9S_MB_2U_LIB.S9S_MB_2U(SCH_1):M_F_CPU1_SA_CB<6>
  EE56  M_F_CPU1_SA_CB<5>  DDR5_SA_ECC5  @S9S_MB_2U_LIB.S9S_MB_2U(SCH_1):M_F_CPU1_SA_CB<5>
  ED57  M_F_CPU1_SA_CB<4>  DDR5_SA_ECC4  @S9S_MB_2U_LIB.S9S_MB_2U(SCH_1):M_F_CPU1_SA_CB<4>
  EH59  M_F_CPU1_SA_CB<3>  DDR5_SA_ECC3  @S9S_MB_2U_LIB.S9S_MB_2U(SCH_1):M_F_CPU1_SA_CB<3>
  EG60  M_F_CPU1_SA_CB<2>  DDR5_SA_ECC2  @S9S_MB_2U_LIB.S9S_MB_2U(SCH_1):M_F_CPU1_SA_CB<2>
  ED59  M_F_CPU1_SA_CB<1>  DDR5_SA_ECC1  @S9S_MB_2U_LIB.S9S_MB_2U(SCH_1):M_F_CPU1_SA_CB<1>
  EE60  M_F_CPU1_SA_CB<0>  DDR5_SA_ECC0  @S9S_MB_2U_LIB.S9S_MB_2U(SCH_1):M_F_CPU1_SA_CB<0>
  DY51  M_F_CPU1_SA_CA<6>  DDR5_SA_CA6  @S9S_MB_2U_LIB.S9S_MB_2U(SCH_1):M_F_CPU1_SA_CA<6>
  EG50  M_F_CPU1_SA_CA<5>  DDR5_SA_CA5  @S9S_MB_2U_LIB.S9S_MB_2U(SCH_1):M_F_CPU1_SA_CA<5>
  EE50  M_F_CPU1_SA_CA<4>  DDR5_SA_CA4  @S9S_MB_2U_LIB.S9S_MB_2U(SCH_1):M_F_CPU1_SA_CA<4>
  EH51  M_F_CPU1_SA_CA<3>  DDR5_SA_CA3  @S9S_MB_2U_LIB.S9S_MB_2U(SCH_1):M_F_CPU1_SA_CA<3>
  ED51  M_F_CPU1_SA_CA<2>  DDR5_SA_CA2  @S9S_MB_2U_LIB.S9S_MB_2U(SCH_1):M_F_CPU1_SA_CA<2>
  EJ52  M_F_CPU1_SA_CA<1>  DDR5_SA_CA1  @S9S_MB_2U_LIB.S9S_MB_2U(SCH_1):M_F_CPU1_SA_CA<1>
  EC52  M_F_CPU1_SA_CA<0>  DDR5_SA_CA0  @S9S_MB_2U_LIB.S9S_MB_2U(SCH_1):M_F_CPU1_SA_CA<0>
  DT49  M_F_CPU1_CLK_DP<1>  DDR5_CLK_DP1  @S9S_MB_2U_LIB.S9S_MB_2U(SCH_1):M_F_CPU1_CLK_DP<1>
  EB49  M_F_CPU1_CLK_DP<0>  DDR5_CLK_DP0  @S9S_MB_2U_LIB.S9S_MB_2U(SCH_1):M_F_CPU1_CLK_DP<0>
  DV49  M_F_CPU1_CLK_DN<1>  DDR5_CLK_DN1  @S9S_MB_2U_LIB.S9S_MB_2U(SCH_1):M_F_CPU1_CLK_DN<1>
  DY49  M_F_CPU1_CLK_DN<0>  DDR5_CLK_DN0  @S9S_MB_2U_LIB.S9S_MB_2U(SCH_1):M_F_CPU1_CLK_DN<0>
  CW48  M_F_CPU1_ALERT_N  DDR5_ALERT_N  @S9S_MB_2U_LIB.S9S_MB_2U(SCH_1):M_F_CPU1_ALERT_N

SOCKET4677_AZIFS054P001C01  I7   U1     [SOCKET4677_AZIFS054P001C01-SOCA]
  DG43  M_E_CPU1_SB_RSP<1>  DDR4_B_RSP1  @S9S_MB_2U_LIB.S9S_MB_2U(SCH_1):M_E_CPU1_SB_RSP<1>
  DF44  M_E_CPU1_SB_RSP<0>  DDR4_B_RSP0  @S9S_MB_2U_LIB.S9S_MB_2U(SCH_1):M_E_CPU1_SB_RSP<0>
  EP42  M_E_CPU1_SB_PAR  DDR4_SB_PAR  @S9S_MB_2U_LIB.S9S_MB_2U(SCH_1):M_E_CPU1_SB_PAR
  EM36  M_E_CPU1_SB_DQS_DP<9>  DDR4_SB_DQS_DP9  @S9S_MB_2U_LIB.S9S_MB_2U(SCH_1):M_E_CPU1_SB_DQS_DP<9>
  EP18  M_E_CPU1_SB_DQS_DP<8>  DDR4_SB_DQS_DP8  @S9S_MB_2U_LIB.S9S_MB_2U(SCH_1):M_E_CPU1_SB_DQS_DP<8>
  EP24  M_E_CPU1_SB_DQS_DP<7>  DDR4_SB_DQS_DP7  @S9S_MB_2U_LIB.S9S_MB_2U(SCH_1):M_E_CPU1_SB_DQS_DP<7>
  EP30  M_E_CPU1_SB_DQS_DP<6>  DDR4_SB_DQS_DP6  @S9S_MB_2U_LIB.S9S_MB_2U(SCH_1):M_E_CPU1_SB_DQS_DP<6>
  EG27  M_E_CPU1_SB_DQS_DP<5>  DDR4_SB_DQS_DP5  @S9S_MB_2U_LIB.S9S_MB_2U(SCH_1):M_E_CPU1_SB_DQS_DP<5>
  EP36  M_E_CPU1_SB_DQS_DP<4>  DDR4_SB_DQS_DP4  @S9S_MB_2U_LIB.S9S_MB_2U(SCH_1):M_E_CPU1_SB_DQS_DP<4>
  EM18  M_E_CPU1_SB_DQS_DP<3>  DDR4_SB_DQS_DP3  @S9S_MB_2U_LIB.S9S_MB_2U(SCH_1):M_E_CPU1_SB_DQS_DP<3>
  EM24  M_E_CPU1_SB_DQS_DP<2>  DDR4_SB_DQS_DP2  @S9S_MB_2U_LIB.S9S_MB_2U(SCH_1):M_E_CPU1_SB_DQS_DP<2>
  EM30  M_E_CPU1_SB_DQS_DP<1>  DDR4_SB_DQS_DP1  @S9S_MB_2U_LIB.S9S_MB_2U(SCH_1):M_E_CPU1_SB_DQS_DP<1>
  EC27  M_E_CPU1_SB_DQS_DP<0>  DDR4_SB_DQS_DP0  @S9S_MB_2U_LIB.S9S_MB_2U(SCH_1):M_E_CPU1_SB_DQS_DP<0>
  EK36  M_E_CPU1_SB_DQS_DN<9>  DDR4_SB_DQS_DN9  @S9S_MB_2U_LIB.S9S_MB_2U(SCH_1):M_E_CPU1_SB_DQS_DN<9>
  ET18  M_E_CPU1_SB_DQS_DN<8>  DDR4_SB_DQS_DN8  @S9S_MB_2U_LIB.S9S_MB_2U(SCH_1):M_E_CPU1_SB_DQS_DN<8>
  ET24  M_E_CPU1_SB_DQS_DN<7>  DDR4_SB_DQS_DN7  @S9S_MB_2U_LIB.S9S_MB_2U(SCH_1):M_E_CPU1_SB_DQS_DN<7>
  ET30  M_E_CPU1_SB_DQS_DN<6>  DDR4_SB_DQS_DN6  @S9S_MB_2U_LIB.S9S_MB_2U(SCH_1):M_E_CPU1_SB_DQS_DN<6>
  EJ27  M_E_CPU1_SB_DQS_DN<5>  DDR4_SB_DQS_DN5  @S9S_MB_2U_LIB.S9S_MB_2U(SCH_1):M_E_CPU1_SB_DQS_DN<5>
  ET36  M_E_CPU1_SB_DQS_DN<4>  DDR4_SB_DQS_DN4  @S9S_MB_2U_LIB.S9S_MB_2U(SCH_1):M_E_CPU1_SB_DQS_DN<4>
  EK18  M_E_CPU1_SB_DQS_DN<3>  DDR4_SB_DQS_DN3  @S9S_MB_2U_LIB.S9S_MB_2U(SCH_1):M_E_CPU1_SB_DQS_DN<3>
  EK24  M_E_CPU1_SB_DQS_DN<2>  DDR4_SB_DQS_DN2  @S9S_MB_2U_LIB.S9S_MB_2U(SCH_1):M_E_CPU1_SB_DQS_DN<2>
  EK30  M_E_CPU1_SB_DQS_DN<1>  DDR4_SB_DQS_DN1  @S9S_MB_2U_LIB.S9S_MB_2U(SCH_1):M_E_CPU1_SB_DQS_DN<1>
  EE27  M_E_CPU1_SB_DQS_DN<0>  DDR4_SB_DQS_DN0  @S9S_MB_2U_LIB.S9S_MB_2U(SCH_1):M_E_CPU1_SB_DQS_DN<0>
  EL31  M_E_CPU1_SB_DQ<9>  DDR4_SB_DQ9  @S9S_MB_2U_LIB.S9S_MB_2U(SCH_1):M_E_CPU1_SB_DQ<9>
  EM32  M_E_CPU1_SB_DQ<8>  DDR4_SB_DQ8  @S9S_MB_2U_LIB.S9S_MB_2U(SCH_1):M_E_CPU1_SB_DQ<8>
  EG25  M_E_CPU1_SB_DQ<7>  DDR4_SB_DQ7  @S9S_MB_2U_LIB.S9S_MB_2U(SCH_1):M_E_CPU1_SB_DQ<7>
  EH26  M_E_CPU1_SB_DQ<6>  DDR4_SB_DQ6  @S9S_MB_2U_LIB.S9S_MB_2U(SCH_1):M_E_CPU1_SB_DQ<6>
  EE25  M_E_CPU1_SB_DQ<5>  DDR4_SB_DQ5  @S9S_MB_2U_LIB.S9S_MB_2U(SCH_1):M_E_CPU1_SB_DQ<5>
  ED26  M_E_CPU1_SB_DQ<4>  DDR4_SB_DQ4  @S9S_MB_2U_LIB.S9S_MB_2U(SCH_1):M_E_CPU1_SB_DQ<4>
  EH28  M_E_CPU1_SB_DQ<3>  DDR4_SB_DQ3  @S9S_MB_2U_LIB.S9S_MB_2U(SCH_1):M_E_CPU1_SB_DQ<3>
  EP16  M_E_CPU1_SB_DQ<31>  DDR4_SB_DQ31  @S9S_MB_2U_LIB.S9S_MB_2U(SCH_1):M_E_CPU1_SB_DQ<31>
  ER17  M_E_CPU1_SB_DQ<30>  DDR4_SB_DQ30  @S9S_MB_2U_LIB.S9S_MB_2U(SCH_1):M_E_CPU1_SB_DQ<30>
  EG29  M_E_CPU1_SB_DQ<2>  DDR4_SB_DQ2  @S9S_MB_2U_LIB.S9S_MB_2U(SCH_1):M_E_CPU1_SB_DQ<2>
  EM16  M_E_CPU1_SB_DQ<29>  DDR4_SB_DQ29  @S9S_MB_2U_LIB.S9S_MB_2U(SCH_1):M_E_CPU1_SB_DQ<29>
  EL17  M_E_CPU1_SB_DQ<28>  DDR4_SB_DQ28  @S9S_MB_2U_LIB.S9S_MB_2U(SCH_1):M_E_CPU1_SB_DQ<28>
  ER19  M_E_CPU1_SB_DQ<27>  DDR4_SB_DQ27  @S9S_MB_2U_LIB.S9S_MB_2U(SCH_1):M_E_CPU1_SB_DQ<27>
  EP20  M_E_CPU1_SB_DQ<26>  DDR4_SB_DQ26  @S9S_MB_2U_LIB.S9S_MB_2U(SCH_1):M_E_CPU1_SB_DQ<26>
  EL19  M_E_CPU1_SB_DQ<25>  DDR4_SB_DQ25  @S9S_MB_2U_LIB.S9S_MB_2U(SCH_1):M_E_CPU1_SB_DQ<25>
  EM20  M_E_CPU1_SB_DQ<24>  DDR4_SB_DQ24  @S9S_MB_2U_LIB.S9S_MB_2U(SCH_1):M_E_CPU1_SB_DQ<24>
  EP22  M_E_CPU1_SB_DQ<23>  DDR4_SB_DQ23  @S9S_MB_2U_LIB.S9S_MB_2U(SCH_1):M_E_CPU1_SB_DQ<23>
  ER23  M_E_CPU1_SB_DQ<22>  DDR4_SB_DQ22  @S9S_MB_2U_LIB.S9S_MB_2U(SCH_1):M_E_CPU1_SB_DQ<22>
  EM22  M_E_CPU1_SB_DQ<21>  DDR4_SB_DQ21  @S9S_MB_2U_LIB.S9S_MB_2U(SCH_1):M_E_CPU1_SB_DQ<21>
  EL23  M_E_CPU1_SB_DQ<20>  DDR4_SB_DQ20  @S9S_MB_2U_LIB.S9S_MB_2U(SCH_1):M_E_CPU1_SB_DQ<20>
  ED28  M_E_CPU1_SB_DQ<1>  DDR4_SB_DQ1  @S9S_MB_2U_LIB.S9S_MB_2U(SCH_1):M_E_CPU1_SB_DQ<1>
  ER25  M_E_CPU1_SB_DQ<19>  DDR4_SB_DQ19  @S9S_MB_2U_LIB.S9S_MB_2U(SCH_1):M_E_CPU1_SB_DQ<19>
  EP26  M_E_CPU1_SB_DQ<18>  DDR4_SB_DQ18  @S9S_MB_2U_LIB.S9S_MB_2U(SCH_1):M_E_CPU1_SB_DQ<18>
  EL25  M_E_CPU1_SB_DQ<17>  DDR4_SB_DQ17  @S9S_MB_2U_LIB.S9S_MB_2U(SCH_1):M_E_CPU1_SB_DQ<17>
  EM26  M_E_CPU1_SB_DQ<16>  DDR4_SB_DQ16  @S9S_MB_2U_LIB.S9S_MB_2U(SCH_1):M_E_CPU1_SB_DQ<16>
  EP28  M_E_CPU1_SB_DQ<15>  DDR4_SB_DQ15  @S9S_MB_2U_LIB.S9S_MB_2U(SCH_1):M_E_CPU1_SB_DQ<15>
  ER29  M_E_CPU1_SB_DQ<14>  DDR4_SB_DQ14  @S9S_MB_2U_LIB.S9S_MB_2U(SCH_1):M_E_CPU1_SB_DQ<14>
  EM28  M_E_CPU1_SB_DQ<13>  DDR4_SB_DQ13  @S9S_MB_2U_LIB.S9S_MB_2U(SCH_1):M_E_CPU1_SB_DQ<13>
  EL29  M_E_CPU1_SB_DQ<12>  DDR4_SB_DQ12  @S9S_MB_2U_LIB.S9S_MB_2U(SCH_1):M_E_CPU1_SB_DQ<12>
  ER31  M_E_CPU1_SB_DQ<11>  DDR4_SB_DQ11  @S9S_MB_2U_LIB.S9S_MB_2U(SCH_1):M_E_CPU1_SB_DQ<11>
  EP32  M_E_CPU1_SB_DQ<10>  DDR4_SB_DQ10  @S9S_MB_2U_LIB.S9S_MB_2U(SCH_1):M_E_CPU1_SB_DQ<10>
  EE29  M_E_CPU1_SB_DQ<0>  DDR4_SB_DQ0  @S9S_MB_2U_LIB.S9S_MB_2U(SCH_1):M_E_CPU1_SB_DQ<0>
  EL41  M_E_CPU1_SB_CS_N<3>  DDR4_SB_CS3_N  @S9S_MB_2U_LIB.S9S_MB_2U(SCH_1):M_E_CPU1_SB_CS_N<3>
  EM40  M_E_CPU1_SB_CS_N<2>  DDR4_SB_CS2_N  @S9S_MB_2U_LIB.S9S_MB_2U(SCH_1):M_E_CPU1_SB_CS_N<2>
  ET40  M_E_CPU1_SB_CS_N<1>  DDR4_SB_CS1_N  @S9S_MB_2U_LIB.S9S_MB_2U(SCH_1):M_E_CPU1_SB_CS_N<1>
  EP40  M_E_CPU1_SB_CS_N<0>  DDR4_SB_CS0_N  @S9S_MB_2U_LIB.S9S_MB_2U(SCH_1):M_E_CPU1_SB_CS_N<0>
  ER37  M_E_CPU1_SB_CB<7>  DDR4_SB_ECC7  @S9S_MB_2U_LIB.S9S_MB_2U(SCH_1):M_E_CPU1_SB_CB<7>
  EP38  M_E_CPU1_SB_CB<6>  DDR4_SB_ECC6  @S9S_MB_2U_LIB.S9S_MB_2U(SCH_1):M_E_CPU1_SB_CB<6>
  EL37  M_E_CPU1_SB_CB<5>  DDR4_SB_ECC5  @S9S_MB_2U_LIB.S9S_MB_2U(SCH_1):M_E_CPU1_SB_CB<5>
  EM38  M_E_CPU1_SB_CB<4>  DDR4_SB_ECC4  @S9S_MB_2U_LIB.S9S_MB_2U(SCH_1):M_E_CPU1_SB_CB<4>
  EP34  M_E_CPU1_SB_CB<3>  DDR4_SB_ECC3  @S9S_MB_2U_LIB.S9S_MB_2U(SCH_1):M_E_CPU1_SB_CB<3>
  ER35  M_E_CPU1_SB_CB<2>  DDR4_SB_ECC2  @S9S_MB_2U_LIB.S9S_MB_2U(SCH_1):M_E_CPU1_SB_CB<2>
  EM34  M_E_CPU1_SB_CB<1>  DDR4_SB_ECC1  @S9S_MB_2U_LIB.S9S_MB_2U(SCH_1):M_E_CPU1_SB_CB<1>
  EL35  M_E_CPU1_SB_CB<0>  DDR4_SB_ECC0  @S9S_MB_2U_LIB.S9S_MB_2U(SCH_1):M_E_CPU1_SB_CB<0>
  EK42  M_E_CPU1_SB_CA<6>  DDR4_SB_CA6  @S9S_MB_2U_LIB.S9S_MB_2U(SCH_1):M_E_CPU1_SB_CA<6>
  ET42  M_E_CPU1_SB_CA<5>  DDR4_SB_CA5  @S9S_MB_2U_LIB.S9S_MB_2U(SCH_1):M_E_CPU1_SB_CA<5>
  EL43  M_E_CPU1_SB_CA<4>  DDR4_SB_CA4  @S9S_MB_2U_LIB.S9S_MB_2U(SCH_1):M_E_CPU1_SB_CA<4>
  EP44  M_E_CPU1_SB_CA<3>  DDR4_SB_CA3  @S9S_MB_2U_LIB.S9S_MB_2U(SCH_1):M_E_CPU1_SB_CA<3>
  EM44  M_E_CPU1_SB_CA<2>  DDR4_SB_CA2  @S9S_MB_2U_LIB.S9S_MB_2U(SCH_1):M_E_CPU1_SB_CA<2>
  EH44  M_E_CPU1_SB_CA<1>  DDR4_SB_CA1  @S9S_MB_2U_LIB.S9S_MB_2U(SCH_1):M_E_CPU1_SB_CA<1>
  EG43  M_E_CPU1_SB_CA<0>  DDR4_SB_CA0  @S9S_MB_2U_LIB.S9S_MB_2U(SCH_1):M_E_CPU1_SB_CA<0>
  DC43  M_E_CPU1_SA_RSP<1>  DDR4_A_RSP1  @S9S_MB_2U_LIB.S9S_MB_2U(SCH_1):M_E_CPU1_SA_RSP<1>
  DD44  M_E_CPU1_SA_RSP<0>  DDR4_A_RSP0  @S9S_MB_2U_LIB.S9S_MB_2U(SCH_1):M_E_CPU1_SA_RSP<0>
  EE43  M_E_CPU1_SA_PAR  DDR4_SA_PAR  @S9S_MB_2U_LIB.S9S_MB_2U(SCH_1):M_E_CPU1_SA_PAR
  EP55  M_E_CPU1_SA_DQS_DP<9>  DDR4_SA_DQS_DP9  @S9S_MB_2U_LIB.S9S_MB_2U(SCH_1):M_E_CPU1_SA_DQS_DP<9>
  EP61  M_E_CPU1_SA_DQS_DP<8>  DDR4_SA_DQS_DP8  @S9S_MB_2U_LIB.S9S_MB_2U(SCH_1):M_E_CPU1_SA_DQS_DP<8>
  EM67  M_E_CPU1_SA_DQS_DP<7>  DDR4_SA_DQS_DP7  @S9S_MB_2U_LIB.S9S_MB_2U(SCH_1):M_E_CPU1_SA_DQS_DP<7>
  EG70  M_E_CPU1_SA_DQS_DP<6>  DDR4_SA_DQS_DP6  @S9S_MB_2U_LIB.S9S_MB_2U(SCH_1):M_E_CPU1_SA_DQS_DP<6>
  EN74  M_E_CPU1_SA_DQS_DP<5>  DDR4_SA_DQS_DP5  @S9S_MB_2U_LIB.S9S_MB_2U(SCH_1):M_E_CPU1_SA_DQS_DP<5>
  EK55  M_E_CPU1_SA_DQS_DP<4>  DDR4_SA_DQS_DP4  @S9S_MB_2U_LIB.S9S_MB_2U(SCH_1):M_E_CPU1_SA_DQS_DP<4>
  EM61  M_E_CPU1_SA_DQS_DP<3>  DDR4_SA_DQS_DP3  @S9S_MB_2U_LIB.S9S_MB_2U(SCH_1):M_E_CPU1_SA_DQS_DP<3>
  EL68  M_E_CPU1_SA_DQS_DP<2>  DDR4_SA_DQS_DP2  @S9S_MB_2U_LIB.S9S_MB_2U(SCH_1):M_E_CPU1_SA_DQS_DP<2>
  EE70  M_E_CPU1_SA_DQS_DP<1>  DDR4_SA_DQS_DP1  @S9S_MB_2U_LIB.S9S_MB_2U(SCH_1):M_E_CPU1_SA_DQS_DP<1>
  EN76  M_E_CPU1_SA_DQS_DP<0>  DDR4_SA_DQS_DP0  @S9S_MB_2U_LIB.S9S_MB_2U(SCH_1):M_E_CPU1_SA_DQS_DP<0>
  ET55  M_E_CPU1_SA_DQS_DN<9>  DDR4_SA_DQS_DN9  @S9S_MB_2U_LIB.S9S_MB_2U(SCH_1):M_E_CPU1_SA_DQS_DN<9>
  ET61  M_E_CPU1_SA_DQS_DN<8>  DDR4_SA_DQS_DN8  @S9S_MB_2U_LIB.S9S_MB_2U(SCH_1):M_E_CPU1_SA_DQS_DN<8>
  EN68  M_E_CPU1_SA_DQS_DN<7>  DDR4_SA_DQS_DN7  @S9S_MB_2U_LIB.S9S_MB_2U(SCH_1):M_E_CPU1_SA_DQS_DN<7>
  EJ70  M_E_CPU1_SA_DQS_DN<6>  DDR4_SA_DQS_DN6  @S9S_MB_2U_LIB.S9S_MB_2U(SCH_1):M_E_CPU1_SA_DQS_DN<6>
  EM75  M_E_CPU1_SA_DQS_DN<5>  DDR4_SA_DQS_DN5  @S9S_MB_2U_LIB.S9S_MB_2U(SCH_1):M_E_CPU1_SA_DQS_DN<5>
  EM55  M_E_CPU1_SA_DQS_DN<4>  DDR4_SA_DQS_DN4  @S9S_MB_2U_LIB.S9S_MB_2U(SCH_1):M_E_CPU1_SA_DQS_DN<4>
  EK61  M_E_CPU1_SA_DQS_DN<3>  DDR4_SA_DQS_DN3  @S9S_MB_2U_LIB.S9S_MB_2U(SCH_1):M_E_CPU1_SA_DQS_DN<3>
  EK67  M_E_CPU1_SA_DQS_DN<2>  DDR4_SA_DQS_DN2  @S9S_MB_2U_LIB.S9S_MB_2U(SCH_1):M_E_CPU1_SA_DQS_DN<2>
  EC70  M_E_CPU1_SA_DQS_DN<1>  DDR4_SA_DQS_DN1  @S9S_MB_2U_LIB.S9S_MB_2U(SCH_1):M_E_CPU1_SA_DQS_DN<1>
  EP75  M_E_CPU1_SA_DQS_DN<0>  DDR4_SA_DQS_DN0  @S9S_MB_2U_LIB.S9S_MB_2U(SCH_1):M_E_CPU1_SA_DQS_DN<0>
  ED71  M_E_CPU1_SA_DQ<9>  DDR4_SA_DQ9  @S9S_MB_2U_LIB.S9S_MB_2U(SCH_1):M_E_CPU1_SA_DQ<9>
  EE72  M_E_CPU1_SA_DQ<8>  DDR4_SA_DQ8  @S9S_MB_2U_LIB.S9S_MB_2U(SCH_1):M_E_CPU1_SA_DQ<8>
  ER72  M_E_CPU1_SA_DQ<7>  DDR4_SA_DQ7  @S9S_MB_2U_LIB.S9S_MB_2U(SCH_1):M_E_CPU1_SA_DQ<7>
  EP73  M_E_CPU1_SA_DQ<6>  DDR4_SA_DQ6  @S9S_MB_2U_LIB.S9S_MB_2U(SCH_1):M_E_CPU1_SA_DQ<6>
  EK73  M_E_CPU1_SA_DQ<5>  DDR4_SA_DQ5  @S9S_MB_2U_LIB.S9S_MB_2U(SCH_1):M_E_CPU1_SA_DQ<5>
  EL74  M_E_CPU1_SA_DQ<4>  DDR4_SA_DQ4  @S9S_MB_2U_LIB.S9S_MB_2U(SCH_1):M_E_CPU1_SA_DQ<4>
  ER76  M_E_CPU1_SA_DQ<3>  DDR4_SA_DQ3  @S9S_MB_2U_LIB.S9S_MB_2U(SCH_1):M_E_CPU1_SA_DQ<3>
  EP59  M_E_CPU1_SA_DQ<31>  DDR4_SA_DQ31  @S9S_MB_2U_LIB.S9S_MB_2U(SCH_1):M_E_CPU1_SA_DQ<31>
  ER60  M_E_CPU1_SA_DQ<30>  DDR4_SA_DQ30  @S9S_MB_2U_LIB.S9S_MB_2U(SCH_1):M_E_CPU1_SA_DQ<30>
  EP79  M_E_CPU1_SA_DQ<2>  DDR4_SA_DQ2  @S9S_MB_2U_LIB.S9S_MB_2U(SCH_1):M_E_CPU1_SA_DQ<2>
  EM59  M_E_CPU1_SA_DQ<29>  DDR4_SA_DQ29  @S9S_MB_2U_LIB.S9S_MB_2U(SCH_1):M_E_CPU1_SA_DQ<29>
  EL60  M_E_CPU1_SA_DQ<28>  DDR4_SA_DQ28  @S9S_MB_2U_LIB.S9S_MB_2U(SCH_1):M_E_CPU1_SA_DQ<28>
  ER62  M_E_CPU1_SA_DQ<27>  DDR4_SA_DQ27  @S9S_MB_2U_LIB.S9S_MB_2U(SCH_1):M_E_CPU1_SA_DQ<27>
  EP63  M_E_CPU1_SA_DQ<26>  DDR4_SA_DQ26  @S9S_MB_2U_LIB.S9S_MB_2U(SCH_1):M_E_CPU1_SA_DQ<26>
  EL62  M_E_CPU1_SA_DQ<25>  DDR4_SA_DQ25  @S9S_MB_2U_LIB.S9S_MB_2U(SCH_1):M_E_CPU1_SA_DQ<25>
  EM63  M_E_CPU1_SA_DQ<24>  DDR4_SA_DQ24  @S9S_MB_2U_LIB.S9S_MB_2U(SCH_1):M_E_CPU1_SA_DQ<24>
  EP65  M_E_CPU1_SA_DQ<23>  DDR4_SA_DQ23  @S9S_MB_2U_LIB.S9S_MB_2U(SCH_1):M_E_CPU1_SA_DQ<23>
  EL66  M_E_CPU1_SA_DQ<22>  DDR4_SA_DQ22  @S9S_MB_2U_LIB.S9S_MB_2U(SCH_1):M_E_CPU1_SA_DQ<22>
  EM65  M_E_CPU1_SA_DQ<21>  DDR4_SA_DQ21  @S9S_MB_2U_LIB.S9S_MB_2U(SCH_1):M_E_CPU1_SA_DQ<21>
  ER66  M_E_CPU1_SA_DQ<20>  DDR4_SA_DQ20  @S9S_MB_2U_LIB.S9S_MB_2U(SCH_1):M_E_CPU1_SA_DQ<20>
  EM77  M_E_CPU1_SA_DQ<1>  DDR4_SA_DQ1  @S9S_MB_2U_LIB.S9S_MB_2U(SCH_1):M_E_CPU1_SA_DQ<1>
  ER68  M_E_CPU1_SA_DQ<19>  DDR4_SA_DQ19  @S9S_MB_2U_LIB.S9S_MB_2U(SCH_1):M_E_CPU1_SA_DQ<19>
  EN70  M_E_CPU1_SA_DQ<18>  DDR4_SA_DQ18  @S9S_MB_2U_LIB.S9S_MB_2U(SCH_1):M_E_CPU1_SA_DQ<18>
  EM69  M_E_CPU1_SA_DQ<17>  DDR4_SA_DQ17  @S9S_MB_2U_LIB.S9S_MB_2U(SCH_1):M_E_CPU1_SA_DQ<17>
  EM71  M_E_CPU1_SA_DQ<16>  DDR4_SA_DQ16  @S9S_MB_2U_LIB.S9S_MB_2U(SCH_1):M_E_CPU1_SA_DQ<16>
  EG68  M_E_CPU1_SA_DQ<15>  DDR4_SA_DQ15  @S9S_MB_2U_LIB.S9S_MB_2U(SCH_1):M_E_CPU1_SA_DQ<15>
  EH69  M_E_CPU1_SA_DQ<14>  DDR4_SA_DQ14  @S9S_MB_2U_LIB.S9S_MB_2U(SCH_1):M_E_CPU1_SA_DQ<14>
  EE68  M_E_CPU1_SA_DQ<13>  DDR4_SA_DQ13  @S9S_MB_2U_LIB.S9S_MB_2U(SCH_1):M_E_CPU1_SA_DQ<13>
  ED69  M_E_CPU1_SA_DQ<12>  DDR4_SA_DQ12  @S9S_MB_2U_LIB.S9S_MB_2U(SCH_1):M_E_CPU1_SA_DQ<12>
  EH71  M_E_CPU1_SA_DQ<11>  DDR4_SA_DQ11  @S9S_MB_2U_LIB.S9S_MB_2U(SCH_1):M_E_CPU1_SA_DQ<11>
  EG72  M_E_CPU1_SA_DQ<10>  DDR4_SA_DQ10  @S9S_MB_2U_LIB.S9S_MB_2U(SCH_1):M_E_CPU1_SA_DQ<10>
  EL78  M_E_CPU1_SA_DQ<0>  DDR4_SA_DQ0  @S9S_MB_2U_LIB.S9S_MB_2U(SCH_1):M_E_CPU1_SA_DQ<0>
  EL50  M_E_CPU1_SA_CS_N<3>  DDR4_SA_CS3_N  @S9S_MB_2U_LIB.S9S_MB_2U(SCH_1):M_E_CPU1_SA_CS_N<3>
  EM51  M_E_CPU1_SA_CS_N<2>  DDR4_SA_CS2_N  @S9S_MB_2U_LIB.S9S_MB_2U(SCH_1):M_E_CPU1_SA_CS_N<2>
  ET51  M_E_CPU1_SA_CS_N<1>  DDR4_SA_CS1_N  @S9S_MB_2U_LIB.S9S_MB_2U(SCH_1):M_E_CPU1_SA_CS_N<1>
  EP51  M_E_CPU1_SA_CS_N<0>  DDR4_SA_CS0_N  @S9S_MB_2U_LIB.S9S_MB_2U(SCH_1):M_E_CPU1_SA_CS_N<0>
  EP53  M_E_CPU1_SA_CB<7>  DDR4_SA_ECC7  @S9S_MB_2U_LIB.S9S_MB_2U(SCH_1):M_E_CPU1_SA_CB<7>
  ER54  M_E_CPU1_SA_CB<6>  DDR4_SA_ECC6  @S9S_MB_2U_LIB.S9S_MB_2U(SCH_1):M_E_CPU1_SA_CB<6>
  EM53  M_E_CPU1_SA_CB<5>  DDR4_SA_ECC5  @S9S_MB_2U_LIB.S9S_MB_2U(SCH_1):M_E_CPU1_SA_CB<5>
  EL54  M_E_CPU1_SA_CB<4>  DDR4_SA_ECC4  @S9S_MB_2U_LIB.S9S_MB_2U(SCH_1):M_E_CPU1_SA_CB<4>
  ER56  M_E_CPU1_SA_CB<3>  DDR4_SA_ECC3  @S9S_MB_2U_LIB.S9S_MB_2U(SCH_1):M_E_CPU1_SA_CB<3>
  EP57  M_E_CPU1_SA_CB<2>  DDR4_SA_ECC2  @S9S_MB_2U_LIB.S9S_MB_2U(SCH_1):M_E_CPU1_SA_CB<2>
  EL56  M_E_CPU1_SA_CB<1>  DDR4_SA_ECC1  @S9S_MB_2U_LIB.S9S_MB_2U(SCH_1):M_E_CPU1_SA_CB<1>
  EM57  M_E_CPU1_SA_CB<0>  DDR4_SA_ECC0  @S9S_MB_2U_LIB.S9S_MB_2U(SCH_1):M_E_CPU1_SA_CB<0>
  ED44  M_E_CPU1_SA_CA<6>  DDR4_SA_CA6  @S9S_MB_2U_LIB.S9S_MB_2U(SCH_1):M_E_CPU1_SA_CA<6>
  EP47  M_E_CPU1_SA_CA<5>  DDR4_SA_CA5  @S9S_MB_2U_LIB.S9S_MB_2U(SCH_1):M_E_CPU1_SA_CA<5>
  EM47  M_E_CPU1_SA_CA<4>  DDR4_SA_CA4  @S9S_MB_2U_LIB.S9S_MB_2U(SCH_1):M_E_CPU1_SA_CA<4>
  EL48  M_E_CPU1_SA_CA<3>  DDR4_SA_CA3  @S9S_MB_2U_LIB.S9S_MB_2U(SCH_1):M_E_CPU1_SA_CA<3>
  EK49  M_E_CPU1_SA_CA<2>  DDR4_SA_CA2  @S9S_MB_2U_LIB.S9S_MB_2U(SCH_1):M_E_CPU1_SA_CA<2>
  ET49  M_E_CPU1_SA_CA<1>  DDR4_SA_CA1  @S9S_MB_2U_LIB.S9S_MB_2U(SCH_1):M_E_CPU1_SA_CA<1>
  EP49  M_E_CPU1_SA_CA<0>  DDR4_SA_CA0  @S9S_MB_2U_LIB.S9S_MB_2U(SCH_1):M_E_CPU1_SA_CA<0>
  EC45  M_E_CPU1_CLK_DP<1>  DDR4_CLK_DP1  @S9S_MB_2U_LIB.S9S_MB_2U(SCH_1):M_E_CPU1_CLK_DP<1>
  EG45  M_E_CPU1_CLK_DP<0>  DDR4_CLK_DP0  @S9S_MB_2U_LIB.S9S_MB_2U(SCH_1):M_E_CPU1_CLK_DP<0>
  EE45  M_E_CPU1_CLK_DN<1>  DDR4_CLK_DN1  @S9S_MB_2U_LIB.S9S_MB_2U(SCH_1):M_E_CPU1_CLK_DN<1>
  EJ45  M_E_CPU1_CLK_DN<0>  DDR4_CLK_DN0  @S9S_MB_2U_LIB.S9S_MB_2U(SCH_1):M_E_CPU1_CLK_DN<0>
  CY47  M_E_CPU1_ALERT_N  DDR4_ALERT_N  @S9S_MB_2U_LIB.S9S_MB_2U(SCH_1):M_E_CPU1_ALERT_N

SOCKET4677_AZIFS054P001C01  I91  U1     [SOCKET4677_AZIFS054P001C01-SOCA]
  AG50  M_D_CPU1_SB_RSP<1>  DDR3_B_RSP1  @S9S_MB_2U_LIB.S9S_MB_2U(SCH_1):M_D_CPU1_SB_RSP<1>
  AF51  M_D_CPU1_SB_RSP<0>  DDR3_B_RSP0  @S9S_MB_2U_LIB.S9S_MB_2U(SCH_1):M_D_CPU1_SB_RSP<0>
  AH42  M_D_CPU1_SB_PAR  DDR3_SB_PAR  @S9S_MB_2U_LIB.S9S_MB_2U(SCH_1):M_D_CPU1_SB_PAR
  AL39  M_D_CPU1_SB_DQS_DP<9>  DDR3_SB_DQS_DP9  @S9S_MB_2U_LIB.S9S_MB_2U(SCH_1):M_D_CPU1_SB_DQS_DP<9>
  AR21  M_D_CPU1_SB_DQS_DP<8>  DDR3_SB_DQS_DP8  @S9S_MB_2U_LIB.S9S_MB_2U(SCH_1):M_D_CPU1_SB_DQS_DP<8>
  AH24  M_D_CPU1_SB_DQS_DP<7>  DDR3_SB_DQS_DP7  @S9S_MB_2U_LIB.S9S_MB_2U(SCH_1):M_D_CPU1_SB_DQS_DP<7>
  AR27  M_D_CPU1_SB_DQS_DP<6>  DDR3_SB_DQS_DP6  @S9S_MB_2U_LIB.S9S_MB_2U(SCH_1):M_D_CPU1_SB_DQS_DP<6>
  AR33  M_D_CPU1_SB_DQS_DP<5>  DDR3_SB_DQS_DP5  @S9S_MB_2U_LIB.S9S_MB_2U(SCH_1):M_D_CPU1_SB_DQS_DP<5>
  AN39  M_D_CPU1_SB_DQS_DP<4>  DDR3_SB_DQS_DP4  @S9S_MB_2U_LIB.S9S_MB_2U(SCH_1):M_D_CPU1_SB_DQS_DP<4>
  AL21  M_D_CPU1_SB_DQS_DP<3>  DDR3_SB_DQS_DP3  @S9S_MB_2U_LIB.S9S_MB_2U(SCH_1):M_D_CPU1_SB_DQS_DP<3>
  AD24  M_D_CPU1_SB_DQS_DP<2>  DDR3_SB_DQS_DP2  @S9S_MB_2U_LIB.S9S_MB_2U(SCH_1):M_D_CPU1_SB_DQS_DP<2>
  AL27  M_D_CPU1_SB_DQS_DP<1>  DDR3_SB_DQS_DP1  @S9S_MB_2U_LIB.S9S_MB_2U(SCH_1):M_D_CPU1_SB_DQS_DP<1>
  AL33  M_D_CPU1_SB_DQS_DP<0>  DDR3_SB_DQS_DP0  @S9S_MB_2U_LIB.S9S_MB_2U(SCH_1):M_D_CPU1_SB_DQS_DP<0>
  AJ39  M_D_CPU1_SB_DQS_DN<9>  DDR3_SB_DQS_DN9  @S9S_MB_2U_LIB.S9S_MB_2U(SCH_1):M_D_CPU1_SB_DQS_DN<9>
  AN21  M_D_CPU1_SB_DQS_DN<8>  DDR3_SB_DQS_DN8  @S9S_MB_2U_LIB.S9S_MB_2U(SCH_1):M_D_CPU1_SB_DQS_DN<8>
  AF24  M_D_CPU1_SB_DQS_DN<7>  DDR3_SB_DQS_DN7  @S9S_MB_2U_LIB.S9S_MB_2U(SCH_1):M_D_CPU1_SB_DQS_DN<7>
  AN27  M_D_CPU1_SB_DQS_DN<6>  DDR3_SB_DQS_DN6  @S9S_MB_2U_LIB.S9S_MB_2U(SCH_1):M_D_CPU1_SB_DQS_DN<6>
  AN33  M_D_CPU1_SB_DQS_DN<5>  DDR3_SB_DQS_DN5  @S9S_MB_2U_LIB.S9S_MB_2U(SCH_1):M_D_CPU1_SB_DQS_DN<5>
  AR39  M_D_CPU1_SB_DQS_DN<4>  DDR3_SB_DQS_DN4  @S9S_MB_2U_LIB.S9S_MB_2U(SCH_1):M_D_CPU1_SB_DQS_DN<4>
  AJ21  M_D_CPU1_SB_DQS_DN<3>  DDR3_SB_DQS_DN3  @S9S_MB_2U_LIB.S9S_MB_2U(SCH_1):M_D_CPU1_SB_DQS_DN<3>
  AB24  M_D_CPU1_SB_DQS_DN<2>  DDR3_SB_DQS_DN2  @S9S_MB_2U_LIB.S9S_MB_2U(SCH_1):M_D_CPU1_SB_DQS_DN<2>
  AJ27  M_D_CPU1_SB_DQS_DN<1>  DDR3_SB_DQS_DN1  @S9S_MB_2U_LIB.S9S_MB_2U(SCH_1):M_D_CPU1_SB_DQS_DN<1>
  AJ33  M_D_CPU1_SB_DQS_DN<0>  DDR3_SB_DQS_DN0  @S9S_MB_2U_LIB.S9S_MB_2U(SCH_1):M_D_CPU1_SB_DQS_DN<0>
  AK28  M_D_CPU1_SB_DQ<9>  DDR3_SB_DQ9  @S9S_MB_2U_LIB.S9S_MB_2U(SCH_1):M_D_CPU1_SB_DQ<9>
  AL29  M_D_CPU1_SB_DQ<8>  DDR3_SB_DQ8  @S9S_MB_2U_LIB.S9S_MB_2U(SCH_1):M_D_CPU1_SB_DQ<8>
  AN31  M_D_CPU1_SB_DQ<7>  DDR3_SB_DQ7  @S9S_MB_2U_LIB.S9S_MB_2U(SCH_1):M_D_CPU1_SB_DQ<7>
  AP32  M_D_CPU1_SB_DQ<6>  DDR3_SB_DQ6  @S9S_MB_2U_LIB.S9S_MB_2U(SCH_1):M_D_CPU1_SB_DQ<6>
  AL31  M_D_CPU1_SB_DQ<5>  DDR3_SB_DQ5  @S9S_MB_2U_LIB.S9S_MB_2U(SCH_1):M_D_CPU1_SB_DQ<5>
  AK32  M_D_CPU1_SB_DQ<4>  DDR3_SB_DQ4  @S9S_MB_2U_LIB.S9S_MB_2U(SCH_1):M_D_CPU1_SB_DQ<4>
  AP34  M_D_CPU1_SB_DQ<3>  DDR3_SB_DQ3  @S9S_MB_2U_LIB.S9S_MB_2U(SCH_1):M_D_CPU1_SB_DQ<3>
  AN19  M_D_CPU1_SB_DQ<31>  DDR3_SB_DQ31  @S9S_MB_2U_LIB.S9S_MB_2U(SCH_1):M_D_CPU1_SB_DQ<31>
  AP20  M_D_CPU1_SB_DQ<30>  DDR3_SB_DQ30  @S9S_MB_2U_LIB.S9S_MB_2U(SCH_1):M_D_CPU1_SB_DQ<30>
  AN35  M_D_CPU1_SB_DQ<2>  DDR3_SB_DQ2  @S9S_MB_2U_LIB.S9S_MB_2U(SCH_1):M_D_CPU1_SB_DQ<2>
  AL19  M_D_CPU1_SB_DQ<29>  DDR3_SB_DQ29  @S9S_MB_2U_LIB.S9S_MB_2U(SCH_1):M_D_CPU1_SB_DQ<29>
  AK20  M_D_CPU1_SB_DQ<28>  DDR3_SB_DQ28  @S9S_MB_2U_LIB.S9S_MB_2U(SCH_1):M_D_CPU1_SB_DQ<28>
  AP22  M_D_CPU1_SB_DQ<27>  DDR3_SB_DQ27  @S9S_MB_2U_LIB.S9S_MB_2U(SCH_1):M_D_CPU1_SB_DQ<27>
  AN23  M_D_CPU1_SB_DQ<26>  DDR3_SB_DQ26  @S9S_MB_2U_LIB.S9S_MB_2U(SCH_1):M_D_CPU1_SB_DQ<26>
  AK22  M_D_CPU1_SB_DQ<25>  DDR3_SB_DQ25  @S9S_MB_2U_LIB.S9S_MB_2U(SCH_1):M_D_CPU1_SB_DQ<25>
  AL23  M_D_CPU1_SB_DQ<24>  DDR3_SB_DQ24  @S9S_MB_2U_LIB.S9S_MB_2U(SCH_1):M_D_CPU1_SB_DQ<24>
  AF22  M_D_CPU1_SB_DQ<23>  DDR3_SB_DQ23  @S9S_MB_2U_LIB.S9S_MB_2U(SCH_1):M_D_CPU1_SB_DQ<23>
  AG23  M_D_CPU1_SB_DQ<22>  DDR3_SB_DQ22  @S9S_MB_2U_LIB.S9S_MB_2U(SCH_1):M_D_CPU1_SB_DQ<22>
  AD22  M_D_CPU1_SB_DQ<21>  DDR3_SB_DQ21  @S9S_MB_2U_LIB.S9S_MB_2U(SCH_1):M_D_CPU1_SB_DQ<21>
  AC23  M_D_CPU1_SB_DQ<20>  DDR3_SB_DQ20  @S9S_MB_2U_LIB.S9S_MB_2U(SCH_1):M_D_CPU1_SB_DQ<20>
  AK34  M_D_CPU1_SB_DQ<1>  DDR3_SB_DQ1  @S9S_MB_2U_LIB.S9S_MB_2U(SCH_1):M_D_CPU1_SB_DQ<1>
  AG25  M_D_CPU1_SB_DQ<19>  DDR3_SB_DQ19  @S9S_MB_2U_LIB.S9S_MB_2U(SCH_1):M_D_CPU1_SB_DQ<19>
  AF26  M_D_CPU1_SB_DQ<18>  DDR3_SB_DQ18  @S9S_MB_2U_LIB.S9S_MB_2U(SCH_1):M_D_CPU1_SB_DQ<18>
  AC25  M_D_CPU1_SB_DQ<17>  DDR3_SB_DQ17  @S9S_MB_2U_LIB.S9S_MB_2U(SCH_1):M_D_CPU1_SB_DQ<17>
  AD26  M_D_CPU1_SB_DQ<16>  DDR3_SB_DQ16  @S9S_MB_2U_LIB.S9S_MB_2U(SCH_1):M_D_CPU1_SB_DQ<16>
  AN25  M_D_CPU1_SB_DQ<15>  DDR3_SB_DQ15  @S9S_MB_2U_LIB.S9S_MB_2U(SCH_1):M_D_CPU1_SB_DQ<15>
  AP26  M_D_CPU1_SB_DQ<14>  DDR3_SB_DQ14  @S9S_MB_2U_LIB.S9S_MB_2U(SCH_1):M_D_CPU1_SB_DQ<14>
  AL25  M_D_CPU1_SB_DQ<13>  DDR3_SB_DQ13  @S9S_MB_2U_LIB.S9S_MB_2U(SCH_1):M_D_CPU1_SB_DQ<13>
  AK26  M_D_CPU1_SB_DQ<12>  DDR3_SB_DQ12  @S9S_MB_2U_LIB.S9S_MB_2U(SCH_1):M_D_CPU1_SB_DQ<12>
  AP28  M_D_CPU1_SB_DQ<11>  DDR3_SB_DQ11  @S9S_MB_2U_LIB.S9S_MB_2U(SCH_1):M_D_CPU1_SB_DQ<11>
  AN29  M_D_CPU1_SB_DQ<10>  DDR3_SB_DQ10  @S9S_MB_2U_LIB.S9S_MB_2U(SCH_1):M_D_CPU1_SB_DQ<10>
  AL35  M_D_CPU1_SB_DQ<0>  DDR3_SB_DQ0  @S9S_MB_2U_LIB.S9S_MB_2U(SCH_1):M_D_CPU1_SB_DQ<0>
  AD40  M_D_CPU1_SB_CS_N<3>  DDR3_SB_CS3_N  @S9S_MB_2U_LIB.S9S_MB_2U(SCH_1):M_D_CPU1_SB_CS_N<3>
  AF40  M_D_CPU1_SB_CS_N<2>  DDR3_SB_CS2_N  @S9S_MB_2U_LIB.S9S_MB_2U(SCH_1):M_D_CPU1_SB_CS_N<2>
  AG41  M_D_CPU1_SB_CS_N<1>  DDR3_SB_CS1_N  @S9S_MB_2U_LIB.S9S_MB_2U(SCH_1):M_D_CPU1_SB_CS_N<1>
  AC41  M_D_CPU1_SB_CS_N<0>  DDR3_SB_CS0_N  @S9S_MB_2U_LIB.S9S_MB_2U(SCH_1):M_D_CPU1_SB_CS_N<0>
  AP40  M_D_CPU1_SB_CB<7>  DDR3_SB_ECC7  @S9S_MB_2U_LIB.S9S_MB_2U(SCH_1):M_D_CPU1_SB_CB<7>
  AN41  M_D_CPU1_SB_CB<6>  DDR3_SB_ECC6  @S9S_MB_2U_LIB.S9S_MB_2U(SCH_1):M_D_CPU1_SB_CB<6>
  AK40  M_D_CPU1_SB_CB<5>  DDR3_SB_ECC5  @S9S_MB_2U_LIB.S9S_MB_2U(SCH_1):M_D_CPU1_SB_CB<5>
  AL41  M_D_CPU1_SB_CB<4>  DDR3_SB_ECC4  @S9S_MB_2U_LIB.S9S_MB_2U(SCH_1):M_D_CPU1_SB_CB<4>
  AN37  M_D_CPU1_SB_CB<3>  DDR3_SB_ECC3  @S9S_MB_2U_LIB.S9S_MB_2U(SCH_1):M_D_CPU1_SB_CB<3>
  AP38  M_D_CPU1_SB_CB<2>  DDR3_SB_ECC2  @S9S_MB_2U_LIB.S9S_MB_2U(SCH_1):M_D_CPU1_SB_CB<2>
  AL37  M_D_CPU1_SB_CB<1>  DDR3_SB_ECC1  @S9S_MB_2U_LIB.S9S_MB_2U(SCH_1):M_D_CPU1_SB_CB<1>
  AK38  M_D_CPU1_SB_CB<0>  DDR3_SB_ECC0  @S9S_MB_2U_LIB.S9S_MB_2U(SCH_1):M_D_CPU1_SB_CB<0>
  AB42  M_D_CPU1_SB_CA<6>  DDR3_SB_CA6  @S9S_MB_2U_LIB.S9S_MB_2U(SCH_1):M_D_CPU1_SB_CA<6>
  AG43  M_D_CPU1_SB_CA<5>  DDR3_SB_CA5  @S9S_MB_2U_LIB.S9S_MB_2U(SCH_1):M_D_CPU1_SB_CA<5>
  AC43  M_D_CPU1_SB_CA<4>  DDR3_SB_CA4  @S9S_MB_2U_LIB.S9S_MB_2U(SCH_1):M_D_CPU1_SB_CA<4>
  AF44  M_D_CPU1_SB_CA<3>  DDR3_SB_CA3  @S9S_MB_2U_LIB.S9S_MB_2U(SCH_1):M_D_CPU1_SB_CA<3>
  AD44  M_D_CPU1_SB_CA<2>  DDR3_SB_CA2  @S9S_MB_2U_LIB.S9S_MB_2U(SCH_1):M_D_CPU1_SB_CA<2>
  AL43  M_D_CPU1_SB_CA<1>  DDR3_SB_CA1  @S9S_MB_2U_LIB.S9S_MB_2U(SCH_1):M_D_CPU1_SB_CA<1>
  AK44  M_D_CPU1_SB_CA<0>  DDR3_SB_CA0  @S9S_MB_2U_LIB.S9S_MB_2U(SCH_1):M_D_CPU1_SB_CA<0>
  AC50  M_D_CPU1_SA_RSP<1>  DDR3_A_RSP1  @S9S_MB_2U_LIB.S9S_MB_2U(SCH_1):M_D_CPU1_SA_RSP<1>
  AD51  M_D_CPU1_SA_RSP<0>  DDR3_A_RSP0  @S9S_MB_2U_LIB.S9S_MB_2U(SCH_1):M_D_CPU1_SA_RSP<0>
  AP44  M_D_CPU1_SA_PAR  DDR3_SA_PAR  @S9S_MB_2U_LIB.S9S_MB_2U(SCH_1):M_D_CPU1_SA_PAR
  AR58  M_D_CPU1_SA_DQS_DP<9>  DDR3_SA_DQS_DP9  @S9S_MB_2U_LIB.S9S_MB_2U(SCH_1):M_D_CPU1_SA_DQS_DP<9>
  AR64  M_D_CPU1_SA_DQS_DP<8>  DDR3_SA_DQS_DP8  @S9S_MB_2U_LIB.S9S_MB_2U(SCH_1):M_D_CPU1_SA_DQS_DP<8>
  AR70  M_D_CPU1_SA_DQS_DP<7>  DDR3_SA_DQS_DP7  @S9S_MB_2U_LIB.S9S_MB_2U(SCH_1):M_D_CPU1_SA_DQS_DP<7>
  AR76  M_D_CPU1_SA_DQS_DP<6>  DDR3_SA_DQS_DP6  @S9S_MB_2U_LIB.S9S_MB_2U(SCH_1):M_D_CPU1_SA_DQS_DP<6>
  AF73  M_D_CPU1_SA_DQS_DP<5>  DDR3_SA_DQS_DP5  @S9S_MB_2U_LIB.S9S_MB_2U(SCH_1):M_D_CPU1_SA_DQS_DP<5>
  AL58  M_D_CPU1_SA_DQS_DP<4>  DDR3_SA_DQS_DP4  @S9S_MB_2U_LIB.S9S_MB_2U(SCH_1):M_D_CPU1_SA_DQS_DP<4>
  AL64  M_D_CPU1_SA_DQS_DP<3>  DDR3_SA_DQS_DP3  @S9S_MB_2U_LIB.S9S_MB_2U(SCH_1):M_D_CPU1_SA_DQS_DP<3>
  AL70  M_D_CPU1_SA_DQS_DP<2>  DDR3_SA_DQS_DP2  @S9S_MB_2U_LIB.S9S_MB_2U(SCH_1):M_D_CPU1_SA_DQS_DP<2>
  AL76  M_D_CPU1_SA_DQS_DP<1>  DDR3_SA_DQS_DP1  @S9S_MB_2U_LIB.S9S_MB_2U(SCH_1):M_D_CPU1_SA_DQS_DP<1>
  AD73  M_D_CPU1_SA_DQS_DP<0>  DDR3_SA_DQS_DP0  @S9S_MB_2U_LIB.S9S_MB_2U(SCH_1):M_D_CPU1_SA_DQS_DP<0>
  AN58  M_D_CPU1_SA_DQS_DN<9>  DDR3_SA_DQS_DN9  @S9S_MB_2U_LIB.S9S_MB_2U(SCH_1):M_D_CPU1_SA_DQS_DN<9>
  AN64  M_D_CPU1_SA_DQS_DN<8>  DDR3_SA_DQS_DN8  @S9S_MB_2U_LIB.S9S_MB_2U(SCH_1):M_D_CPU1_SA_DQS_DN<8>
  AN70  M_D_CPU1_SA_DQS_DN<7>  DDR3_SA_DQS_DN7  @S9S_MB_2U_LIB.S9S_MB_2U(SCH_1):M_D_CPU1_SA_DQS_DN<7>
  AN76  M_D_CPU1_SA_DQS_DN<6>  DDR3_SA_DQS_DN6  @S9S_MB_2U_LIB.S9S_MB_2U(SCH_1):M_D_CPU1_SA_DQS_DN<6>
  AH73  M_D_CPU1_SA_DQS_DN<5>  DDR3_SA_DQS_DN5  @S9S_MB_2U_LIB.S9S_MB_2U(SCH_1):M_D_CPU1_SA_DQS_DN<5>
  AJ58  M_D_CPU1_SA_DQS_DN<4>  DDR3_SA_DQS_DN4  @S9S_MB_2U_LIB.S9S_MB_2U(SCH_1):M_D_CPU1_SA_DQS_DN<4>
  AJ64  M_D_CPU1_SA_DQS_DN<3>  DDR3_SA_DQS_DN3  @S9S_MB_2U_LIB.S9S_MB_2U(SCH_1):M_D_CPU1_SA_DQS_DN<3>
  AJ70  M_D_CPU1_SA_DQS_DN<2>  DDR3_SA_DQS_DN2  @S9S_MB_2U_LIB.S9S_MB_2U(SCH_1):M_D_CPU1_SA_DQS_DN<2>
  AJ76  M_D_CPU1_SA_DQS_DN<1>  DDR3_SA_DQS_DN1  @S9S_MB_2U_LIB.S9S_MB_2U(SCH_1):M_D_CPU1_SA_DQS_DN<1>
  AB73  M_D_CPU1_SA_DQS_DN<0>  DDR3_SA_DQS_DN0  @S9S_MB_2U_LIB.S9S_MB_2U(SCH_1):M_D_CPU1_SA_DQS_DN<0>
  AK77  M_D_CPU1_SA_DQ<9>  DDR3_SA_DQ9  @S9S_MB_2U_LIB.S9S_MB_2U(SCH_1):M_D_CPU1_SA_DQ<9>
  AL78  M_D_CPU1_SA_DQ<8>  DDR3_SA_DQ8  @S9S_MB_2U_LIB.S9S_MB_2U(SCH_1):M_D_CPU1_SA_DQ<8>
  AF71  M_D_CPU1_SA_DQ<7>  DDR3_SA_DQ7  @S9S_MB_2U_LIB.S9S_MB_2U(SCH_1):M_D_CPU1_SA_DQ<7>
  AG72  M_D_CPU1_SA_DQ<6>  DDR3_SA_DQ6  @S9S_MB_2U_LIB.S9S_MB_2U(SCH_1):M_D_CPU1_SA_DQ<6>
  AD71  M_D_CPU1_SA_DQ<5>  DDR3_SA_DQ5  @S9S_MB_2U_LIB.S9S_MB_2U(SCH_1):M_D_CPU1_SA_DQ<5>
  AC72  M_D_CPU1_SA_DQ<4>  DDR3_SA_DQ4  @S9S_MB_2U_LIB.S9S_MB_2U(SCH_1):M_D_CPU1_SA_DQ<4>
  AG74  M_D_CPU1_SA_DQ<3>  DDR3_SA_DQ3  @S9S_MB_2U_LIB.S9S_MB_2U(SCH_1):M_D_CPU1_SA_DQ<3>
  AN62  M_D_CPU1_SA_DQ<31>  DDR3_SA_DQ31  @S9S_MB_2U_LIB.S9S_MB_2U(SCH_1):M_D_CPU1_SA_DQ<31>
  AP63  M_D_CPU1_SA_DQ<30>  DDR3_SA_DQ30  @S9S_MB_2U_LIB.S9S_MB_2U(SCH_1):M_D_CPU1_SA_DQ<30>
  AF75  M_D_CPU1_SA_DQ<2>  DDR3_SA_DQ2  @S9S_MB_2U_LIB.S9S_MB_2U(SCH_1):M_D_CPU1_SA_DQ<2>
  AL62  M_D_CPU1_SA_DQ<29>  DDR3_SA_DQ29  @S9S_MB_2U_LIB.S9S_MB_2U(SCH_1):M_D_CPU1_SA_DQ<29>
  AK63  M_D_CPU1_SA_DQ<28>  DDR3_SA_DQ28  @S9S_MB_2U_LIB.S9S_MB_2U(SCH_1):M_D_CPU1_SA_DQ<28>
  AP65  M_D_CPU1_SA_DQ<27>  DDR3_SA_DQ27  @S9S_MB_2U_LIB.S9S_MB_2U(SCH_1):M_D_CPU1_SA_DQ<27>
  AN66  M_D_CPU1_SA_DQ<26>  DDR3_SA_DQ26  @S9S_MB_2U_LIB.S9S_MB_2U(SCH_1):M_D_CPU1_SA_DQ<26>
  AK65  M_D_CPU1_SA_DQ<25>  DDR3_SA_DQ25  @S9S_MB_2U_LIB.S9S_MB_2U(SCH_1):M_D_CPU1_SA_DQ<25>
  AL66  M_D_CPU1_SA_DQ<24>  DDR3_SA_DQ24  @S9S_MB_2U_LIB.S9S_MB_2U(SCH_1):M_D_CPU1_SA_DQ<24>
  AN68  M_D_CPU1_SA_DQ<23>  DDR3_SA_DQ23  @S9S_MB_2U_LIB.S9S_MB_2U(SCH_1):M_D_CPU1_SA_DQ<23>
  AP69  M_D_CPU1_SA_DQ<22>  DDR3_SA_DQ22  @S9S_MB_2U_LIB.S9S_MB_2U(SCH_1):M_D_CPU1_SA_DQ<22>
  AL68  M_D_CPU1_SA_DQ<21>  DDR3_SA_DQ21  @S9S_MB_2U_LIB.S9S_MB_2U(SCH_1):M_D_CPU1_SA_DQ<21>
  AK69  M_D_CPU1_SA_DQ<20>  DDR3_SA_DQ20  @S9S_MB_2U_LIB.S9S_MB_2U(SCH_1):M_D_CPU1_SA_DQ<20>
  AC74  M_D_CPU1_SA_DQ<1>  DDR3_SA_DQ1  @S9S_MB_2U_LIB.S9S_MB_2U(SCH_1):M_D_CPU1_SA_DQ<1>
  AP71  M_D_CPU1_SA_DQ<19>  DDR3_SA_DQ19  @S9S_MB_2U_LIB.S9S_MB_2U(SCH_1):M_D_CPU1_SA_DQ<19>
  AN72  M_D_CPU1_SA_DQ<18>  DDR3_SA_DQ18  @S9S_MB_2U_LIB.S9S_MB_2U(SCH_1):M_D_CPU1_SA_DQ<18>
  AK71  M_D_CPU1_SA_DQ<17>  DDR3_SA_DQ17  @S9S_MB_2U_LIB.S9S_MB_2U(SCH_1):M_D_CPU1_SA_DQ<17>
  AL72  M_D_CPU1_SA_DQ<16>  DDR3_SA_DQ16  @S9S_MB_2U_LIB.S9S_MB_2U(SCH_1):M_D_CPU1_SA_DQ<16>
  AN74  M_D_CPU1_SA_DQ<15>  DDR3_SA_DQ15  @S9S_MB_2U_LIB.S9S_MB_2U(SCH_1):M_D_CPU1_SA_DQ<15>
  AP75  M_D_CPU1_SA_DQ<14>  DDR3_SA_DQ14  @S9S_MB_2U_LIB.S9S_MB_2U(SCH_1):M_D_CPU1_SA_DQ<14>
  AL74  M_D_CPU1_SA_DQ<13>  DDR3_SA_DQ13  @S9S_MB_2U_LIB.S9S_MB_2U(SCH_1):M_D_CPU1_SA_DQ<13>
  AK75  M_D_CPU1_SA_DQ<12>  DDR3_SA_DQ12  @S9S_MB_2U_LIB.S9S_MB_2U(SCH_1):M_D_CPU1_SA_DQ<12>
  AP77  M_D_CPU1_SA_DQ<11>  DDR3_SA_DQ11  @S9S_MB_2U_LIB.S9S_MB_2U(SCH_1):M_D_CPU1_SA_DQ<11>
  AN78  M_D_CPU1_SA_DQ<10>  DDR3_SA_DQ10  @S9S_MB_2U_LIB.S9S_MB_2U(SCH_1):M_D_CPU1_SA_DQ<10>
  AD75  M_D_CPU1_SA_DQ<0>  DDR3_SA_DQ0  @S9S_MB_2U_LIB.S9S_MB_2U(SCH_1):M_D_CPU1_SA_DQ<0>
  AP53  M_D_CPU1_SA_CS_N<3>  DDR3_SA_CS3_N  @S9S_MB_2U_LIB.S9S_MB_2U(SCH_1):M_D_CPU1_SA_CS_N<3>
  AN54  M_D_CPU1_SA_CS_N<2>  DDR3_SA_CS2_N  @S9S_MB_2U_LIB.S9S_MB_2U(SCH_1):M_D_CPU1_SA_CS_N<2>
  AK53  M_D_CPU1_SA_CS_N<1>  DDR3_SA_CS1_N  @S9S_MB_2U_LIB.S9S_MB_2U(SCH_1):M_D_CPU1_SA_CS_N<1>
  AL54  M_D_CPU1_SA_CS_N<0>  DDR3_SA_CS0_N  @S9S_MB_2U_LIB.S9S_MB_2U(SCH_1):M_D_CPU1_SA_CS_N<0>
  AN56  M_D_CPU1_SA_CB<7>  DDR3_SA_ECC7  @S9S_MB_2U_LIB.S9S_MB_2U(SCH_1):M_D_CPU1_SA_CB<7>
  AP57  M_D_CPU1_SA_CB<6>  DDR3_SA_ECC6  @S9S_MB_2U_LIB.S9S_MB_2U(SCH_1):M_D_CPU1_SA_CB<6>
  AL56  M_D_CPU1_SA_CB<5>  DDR3_SA_ECC5  @S9S_MB_2U_LIB.S9S_MB_2U(SCH_1):M_D_CPU1_SA_CB<5>
  AK57  M_D_CPU1_SA_CB<4>  DDR3_SA_ECC4  @S9S_MB_2U_LIB.S9S_MB_2U(SCH_1):M_D_CPU1_SA_CB<4>
  AP59  M_D_CPU1_SA_CB<3>  DDR3_SA_ECC3  @S9S_MB_2U_LIB.S9S_MB_2U(SCH_1):M_D_CPU1_SA_CB<3>
  AN60  M_D_CPU1_SA_CB<2>  DDR3_SA_ECC2  @S9S_MB_2U_LIB.S9S_MB_2U(SCH_1):M_D_CPU1_SA_CB<2>
  AK59  M_D_CPU1_SA_CB<1>  DDR3_SA_ECC1  @S9S_MB_2U_LIB.S9S_MB_2U(SCH_1):M_D_CPU1_SA_CB<1>
  AL60  M_D_CPU1_SA_CB<0>  DDR3_SA_ECC0  @S9S_MB_2U_LIB.S9S_MB_2U(SCH_1):M_D_CPU1_SA_CB<0>
  AN43  M_D_CPU1_SA_CA<6>  DDR3_SA_CA6  @S9S_MB_2U_LIB.S9S_MB_2U(SCH_1):M_D_CPU1_SA_CA<6>
  AN50  M_D_CPU1_SA_CA<5>  DDR3_SA_CA5  @S9S_MB_2U_LIB.S9S_MB_2U(SCH_1):M_D_CPU1_SA_CA<5>
  AL50  M_D_CPU1_SA_CA<4>  DDR3_SA_CA4  @S9S_MB_2U_LIB.S9S_MB_2U(SCH_1):M_D_CPU1_SA_CA<4>
  AP51  M_D_CPU1_SA_CA<3>  DDR3_SA_CA3  @S9S_MB_2U_LIB.S9S_MB_2U(SCH_1):M_D_CPU1_SA_CA<3>
  AK51  M_D_CPU1_SA_CA<2>  DDR3_SA_CA2  @S9S_MB_2U_LIB.S9S_MB_2U(SCH_1):M_D_CPU1_SA_CA<2>
  AR52  M_D_CPU1_SA_CA<1>  DDR3_SA_CA1  @S9S_MB_2U_LIB.S9S_MB_2U(SCH_1):M_D_CPU1_SA_CA<1>
  AJ52  M_D_CPU1_SA_CA<0>  DDR3_SA_CA0  @S9S_MB_2U_LIB.S9S_MB_2U(SCH_1):M_D_CPU1_SA_CA<0>
  AR45  M_D_CPU1_CLK_DP<1>  DDR3_CLK_DP1  @S9S_MB_2U_LIB.S9S_MB_2U(SCH_1):M_D_CPU1_CLK_DP<1>
  AL45  M_D_CPU1_CLK_DP<0>  DDR3_CLK_DP0  @S9S_MB_2U_LIB.S9S_MB_2U(SCH_1):M_D_CPU1_CLK_DP<0>
  AN45  M_D_CPU1_CLK_DN<1>  DDR3_CLK_DN1  @S9S_MB_2U_LIB.S9S_MB_2U(SCH_1):M_D_CPU1_CLK_DN<1>
  AJ45  M_D_CPU1_CLK_DN<0>  DDR3_CLK_DN0  @S9S_MB_2U_LIB.S9S_MB_2U(SCH_1):M_D_CPU1_CLK_DN<0>
  AV47  M_D_CPU1_ALERT_N  DDR3_ALERT_N  @S9S_MB_2U_LIB.S9S_MB_2U(SCH_1):M_D_CPU1_ALERT_N

SOCKET4677_AZIFS054P001C01  I91  U1     [SOCKET4677_AZIFS054P001C01-SOCA]
  AF47  M_C_CPU1_SB_RSP<1>  DDR2_B_RSP1  @S9S_MB_2U_LIB.S9S_MB_2U(SCH_1):M_C_CPU1_SB_RSP<1>
  AG48  M_C_CPU1_SB_RSP<0>  DDR2_B_RSP0  @S9S_MB_2U_LIB.S9S_MB_2U(SCH_1):M_C_CPU1_SB_RSP<0>
  AA39  M_C_CPU1_SB_PAR  DDR2_SB_PAR  @S9S_MB_2U_LIB.S9S_MB_2U(SCH_1):M_C_CPU1_SB_PAR
  U33  M_C_CPU1_SB_DQS_DP<9>  DDR2_SB_DQS_DP9  @S9S_MB_2U_LIB.S9S_MB_2U(SCH_1):M_C_CPU1_SB_DQS_DP<9>
  AH18  M_C_CPU1_SB_DQS_DP<8>  DDR2_SB_DQS_DP8  @S9S_MB_2U_LIB.S9S_MB_2U(SCH_1):M_C_CPU1_SB_DQS_DP<8>
  AA21  M_C_CPU1_SB_DQS_DP<7>  DDR2_SB_DQS_DP7  @S9S_MB_2U_LIB.S9S_MB_2U(SCH_1):M_C_CPU1_SB_DQS_DP<7>
  AH30  M_C_CPU1_SB_DQS_DP<6>  DDR2_SB_DQS_DP6  @S9S_MB_2U_LIB.S9S_MB_2U(SCH_1):M_C_CPU1_SB_DQS_DP<6>
  AH36  M_C_CPU1_SB_DQS_DP<5>  DDR2_SB_DQS_DP5  @S9S_MB_2U_LIB.S9S_MB_2U(SCH_1):M_C_CPU1_SB_DQS_DP<5>
  AA33  M_C_CPU1_SB_DQS_DP<4>  DDR2_SB_DQS_DP4  @S9S_MB_2U_LIB.S9S_MB_2U(SCH_1):M_C_CPU1_SB_DQS_DP<4>
  AD18  M_C_CPU1_SB_DQS_DP<3>  DDR2_SB_DQS_DP3  @S9S_MB_2U_LIB.S9S_MB_2U(SCH_1):M_C_CPU1_SB_DQS_DP<3>
  U21  M_C_CPU1_SB_DQS_DP<2>  DDR2_SB_DQS_DP2  @S9S_MB_2U_LIB.S9S_MB_2U(SCH_1):M_C_CPU1_SB_DQS_DP<2>
  AD30  M_C_CPU1_SB_DQS_DP<1>  DDR2_SB_DQS_DP1  @S9S_MB_2U_LIB.S9S_MB_2U(SCH_1):M_C_CPU1_SB_DQS_DP<1>
  AD36  M_C_CPU1_SB_DQS_DP<0>  DDR2_SB_DQS_DP0  @S9S_MB_2U_LIB.S9S_MB_2U(SCH_1):M_C_CPU1_SB_DQS_DP<0>
  R33  M_C_CPU1_SB_DQS_DN<9>  DDR2_SB_DQS_DN9  @S9S_MB_2U_LIB.S9S_MB_2U(SCH_1):M_C_CPU1_SB_DQS_DN<9>
  AF18  M_C_CPU1_SB_DQS_DN<8>  DDR2_SB_DQS_DN8  @S9S_MB_2U_LIB.S9S_MB_2U(SCH_1):M_C_CPU1_SB_DQS_DN<8>
  W21  M_C_CPU1_SB_DQS_DN<7>  DDR2_SB_DQS_DN7  @S9S_MB_2U_LIB.S9S_MB_2U(SCH_1):M_C_CPU1_SB_DQS_DN<7>
  AF30  M_C_CPU1_SB_DQS_DN<6>  DDR2_SB_DQS_DN6  @S9S_MB_2U_LIB.S9S_MB_2U(SCH_1):M_C_CPU1_SB_DQS_DN<6>
  AF36  M_C_CPU1_SB_DQS_DN<5>  DDR2_SB_DQS_DN5  @S9S_MB_2U_LIB.S9S_MB_2U(SCH_1):M_C_CPU1_SB_DQS_DN<5>
  W33  M_C_CPU1_SB_DQS_DN<4>  DDR2_SB_DQS_DN4  @S9S_MB_2U_LIB.S9S_MB_2U(SCH_1):M_C_CPU1_SB_DQS_DN<4>
  AB18  M_C_CPU1_SB_DQS_DN<3>  DDR2_SB_DQS_DN3  @S9S_MB_2U_LIB.S9S_MB_2U(SCH_1):M_C_CPU1_SB_DQS_DN<3>
  R21  M_C_CPU1_SB_DQS_DN<2>  DDR2_SB_DQS_DN2  @S9S_MB_2U_LIB.S9S_MB_2U(SCH_1):M_C_CPU1_SB_DQS_DN<2>
  AB30  M_C_CPU1_SB_DQS_DN<1>  DDR2_SB_DQS_DN1  @S9S_MB_2U_LIB.S9S_MB_2U(SCH_1):M_C_CPU1_SB_DQS_DN<1>
  AB36  M_C_CPU1_SB_DQS_DN<0>  DDR2_SB_DQS_DN0  @S9S_MB_2U_LIB.S9S_MB_2U(SCH_1):M_C_CPU1_SB_DQS_DN<0>
  AC31  M_C_CPU1_SB_DQ<9>  DDR2_SB_DQ9  @S9S_MB_2U_LIB.S9S_MB_2U(SCH_1):M_C_CPU1_SB_DQ<9>
  AD32  M_C_CPU1_SB_DQ<8>  DDR2_SB_DQ8  @S9S_MB_2U_LIB.S9S_MB_2U(SCH_1):M_C_CPU1_SB_DQ<8>
  AF34  M_C_CPU1_SB_DQ<7>  DDR2_SB_DQ7  @S9S_MB_2U_LIB.S9S_MB_2U(SCH_1):M_C_CPU1_SB_DQ<7>
  AG35  M_C_CPU1_SB_DQ<6>  DDR2_SB_DQ6  @S9S_MB_2U_LIB.S9S_MB_2U(SCH_1):M_C_CPU1_SB_DQ<6>
  AD34  M_C_CPU1_SB_DQ<5>  DDR2_SB_DQ5  @S9S_MB_2U_LIB.S9S_MB_2U(SCH_1):M_C_CPU1_SB_DQ<5>
  AC35  M_C_CPU1_SB_DQ<4>  DDR2_SB_DQ4  @S9S_MB_2U_LIB.S9S_MB_2U(SCH_1):M_C_CPU1_SB_DQ<4>
  AG37  M_C_CPU1_SB_DQ<3>  DDR2_SB_DQ3  @S9S_MB_2U_LIB.S9S_MB_2U(SCH_1):M_C_CPU1_SB_DQ<3>
  AJ17  M_C_CPU1_SB_DQ<31>  DDR2_SB_DQ31  @S9S_MB_2U_LIB.S9S_MB_2U(SCH_1):M_C_CPU1_SB_DQ<31>
  AC17  M_C_CPU1_SB_DQ<30>  DDR2_SB_DQ30  @S9S_MB_2U_LIB.S9S_MB_2U(SCH_1):M_C_CPU1_SB_DQ<30>
  AF38  M_C_CPU1_SB_DQ<2>  DDR2_SB_DQ2  @S9S_MB_2U_LIB.S9S_MB_2U(SCH_1):M_C_CPU1_SB_DQ<2>
  AG17  M_C_CPU1_SB_DQ<29>  DDR2_SB_DQ29  @S9S_MB_2U_LIB.S9S_MB_2U(SCH_1):M_C_CPU1_SB_DQ<29>
  AA17  M_C_CPU1_SB_DQ<28>  DDR2_SB_DQ28  @S9S_MB_2U_LIB.S9S_MB_2U(SCH_1):M_C_CPU1_SB_DQ<28>
  AG19  M_C_CPU1_SB_DQ<27>  DDR2_SB_DQ27  @S9S_MB_2U_LIB.S9S_MB_2U(SCH_1):M_C_CPU1_SB_DQ<27>
  AF20  M_C_CPU1_SB_DQ<26>  DDR2_SB_DQ26  @S9S_MB_2U_LIB.S9S_MB_2U(SCH_1):M_C_CPU1_SB_DQ<26>
  AC19  M_C_CPU1_SB_DQ<25>  DDR2_SB_DQ25  @S9S_MB_2U_LIB.S9S_MB_2U(SCH_1):M_C_CPU1_SB_DQ<25>
  AD20  M_C_CPU1_SB_DQ<24>  DDR2_SB_DQ24  @S9S_MB_2U_LIB.S9S_MB_2U(SCH_1):M_C_CPU1_SB_DQ<24>
  W19  M_C_CPU1_SB_DQ<23>  DDR2_SB_DQ23  @S9S_MB_2U_LIB.S9S_MB_2U(SCH_1):M_C_CPU1_SB_DQ<23>
  Y20  M_C_CPU1_SB_DQ<22>  DDR2_SB_DQ22  @S9S_MB_2U_LIB.S9S_MB_2U(SCH_1):M_C_CPU1_SB_DQ<22>
  U19  M_C_CPU1_SB_DQ<21>  DDR2_SB_DQ21  @S9S_MB_2U_LIB.S9S_MB_2U(SCH_1):M_C_CPU1_SB_DQ<21>
  T20  M_C_CPU1_SB_DQ<20>  DDR2_SB_DQ20  @S9S_MB_2U_LIB.S9S_MB_2U(SCH_1):M_C_CPU1_SB_DQ<20>
  AC37  M_C_CPU1_SB_DQ<1>  DDR2_SB_DQ1  @S9S_MB_2U_LIB.S9S_MB_2U(SCH_1):M_C_CPU1_SB_DQ<1>
  Y22  M_C_CPU1_SB_DQ<19>  DDR2_SB_DQ19  @S9S_MB_2U_LIB.S9S_MB_2U(SCH_1):M_C_CPU1_SB_DQ<19>
  W23  M_C_CPU1_SB_DQ<18>  DDR2_SB_DQ18  @S9S_MB_2U_LIB.S9S_MB_2U(SCH_1):M_C_CPU1_SB_DQ<18>
  T22  M_C_CPU1_SB_DQ<17>  DDR2_SB_DQ17  @S9S_MB_2U_LIB.S9S_MB_2U(SCH_1):M_C_CPU1_SB_DQ<17>
  U23  M_C_CPU1_SB_DQ<16>  DDR2_SB_DQ16  @S9S_MB_2U_LIB.S9S_MB_2U(SCH_1):M_C_CPU1_SB_DQ<16>
  AF28  M_C_CPU1_SB_DQ<15>  DDR2_SB_DQ15  @S9S_MB_2U_LIB.S9S_MB_2U(SCH_1):M_C_CPU1_SB_DQ<15>
  AG29  M_C_CPU1_SB_DQ<14>  DDR2_SB_DQ14  @S9S_MB_2U_LIB.S9S_MB_2U(SCH_1):M_C_CPU1_SB_DQ<14>
  AD28  M_C_CPU1_SB_DQ<13>  DDR2_SB_DQ13  @S9S_MB_2U_LIB.S9S_MB_2U(SCH_1):M_C_CPU1_SB_DQ<13>
  AC29  M_C_CPU1_SB_DQ<12>  DDR2_SB_DQ12  @S9S_MB_2U_LIB.S9S_MB_2U(SCH_1):M_C_CPU1_SB_DQ<12>
  AG31  M_C_CPU1_SB_DQ<11>  DDR2_SB_DQ11  @S9S_MB_2U_LIB.S9S_MB_2U(SCH_1):M_C_CPU1_SB_DQ<11>
  AF32  M_C_CPU1_SB_DQ<10>  DDR2_SB_DQ10  @S9S_MB_2U_LIB.S9S_MB_2U(SCH_1):M_C_CPU1_SB_DQ<10>
  AD38  M_C_CPU1_SB_DQ<0>  DDR2_SB_DQ0  @S9S_MB_2U_LIB.S9S_MB_2U(SCH_1):M_C_CPU1_SB_DQ<0>
  W37  M_C_CPU1_SB_CS_N<3>  DDR2_SB_CS3_N  @S9S_MB_2U_LIB.S9S_MB_2U(SCH_1):M_C_CPU1_SB_CS_N<3>
  Y38  M_C_CPU1_SB_CS_N<2>  DDR2_SB_CS2_N  @S9S_MB_2U_LIB.S9S_MB_2U(SCH_1):M_C_CPU1_SB_CS_N<2>
  U37  M_C_CPU1_SB_CS_N<1>  DDR2_SB_CS1_N  @S9S_MB_2U_LIB.S9S_MB_2U(SCH_1):M_C_CPU1_SB_CS_N<1>
  T38  M_C_CPU1_SB_CS_N<0>  DDR2_SB_CS0_N  @S9S_MB_2U_LIB.S9S_MB_2U(SCH_1):M_C_CPU1_SB_CS_N<0>
  Y34  M_C_CPU1_SB_CB<7>  DDR2_SB_ECC7  @S9S_MB_2U_LIB.S9S_MB_2U(SCH_1):M_C_CPU1_SB_CB<7>
  W35  M_C_CPU1_SB_CB<6>  DDR2_SB_ECC6  @S9S_MB_2U_LIB.S9S_MB_2U(SCH_1):M_C_CPU1_SB_CB<6>
  T34  M_C_CPU1_SB_CB<5>  DDR2_SB_ECC5  @S9S_MB_2U_LIB.S9S_MB_2U(SCH_1):M_C_CPU1_SB_CB<5>
  U35  M_C_CPU1_SB_CB<4>  DDR2_SB_ECC4  @S9S_MB_2U_LIB.S9S_MB_2U(SCH_1):M_C_CPU1_SB_CB<4>
  W31  M_C_CPU1_SB_CB<3>  DDR2_SB_ECC3  @S9S_MB_2U_LIB.S9S_MB_2U(SCH_1):M_C_CPU1_SB_CB<3>
  Y32  M_C_CPU1_SB_CB<2>  DDR2_SB_ECC2  @S9S_MB_2U_LIB.S9S_MB_2U(SCH_1):M_C_CPU1_SB_CB<2>
  U31  M_C_CPU1_SB_CB<1>  DDR2_SB_ECC1  @S9S_MB_2U_LIB.S9S_MB_2U(SCH_1):M_C_CPU1_SB_CB<1>
  T32  M_C_CPU1_SB_CB<0>  DDR2_SB_ECC0  @S9S_MB_2U_LIB.S9S_MB_2U(SCH_1):M_C_CPU1_SB_CB<0>
  R39  M_C_CPU1_SB_CA<6>  DDR2_SB_CA6  @S9S_MB_2U_LIB.S9S_MB_2U(SCH_1):M_C_CPU1_SB_CA<6>
  Y40  M_C_CPU1_SB_CA<5>  DDR2_SB_CA5  @S9S_MB_2U_LIB.S9S_MB_2U(SCH_1):M_C_CPU1_SB_CA<5>
  T40  M_C_CPU1_SB_CA<4>  DDR2_SB_CA4  @S9S_MB_2U_LIB.S9S_MB_2U(SCH_1):M_C_CPU1_SB_CA<4>
  W41  M_C_CPU1_SB_CA<3>  DDR2_SB_CA3  @S9S_MB_2U_LIB.S9S_MB_2U(SCH_1):M_C_CPU1_SB_CA<3>
  U41  M_C_CPU1_SB_CA<2>  DDR2_SB_CA2  @S9S_MB_2U_LIB.S9S_MB_2U(SCH_1):M_C_CPU1_SB_CA<2>
  Y47  M_C_CPU1_SB_CA<1>  DDR2_SB_CA1  @S9S_MB_2U_LIB.S9S_MB_2U(SCH_1):M_C_CPU1_SB_CA<1>
  W48  M_C_CPU1_SB_CA<0>  DDR2_SB_CA0  @S9S_MB_2U_LIB.S9S_MB_2U(SCH_1):M_C_CPU1_SB_CA<0>
  AD47  M_C_CPU1_SA_RSP<1>  DDR2_A_RSP1  @S9S_MB_2U_LIB.S9S_MB_2U(SCH_1):M_C_CPU1_SA_RSP<1>
  AC48  M_C_CPU1_SA_RSP<0>  DDR2_A_RSP0  @S9S_MB_2U_LIB.S9S_MB_2U(SCH_1):M_C_CPU1_SA_RSP<0>
  T47  M_C_CPU1_SA_PAR  DDR2_SA_PAR  @S9S_MB_2U_LIB.S9S_MB_2U(SCH_1):M_C_CPU1_SA_PAR
  AF55  M_C_CPU1_SA_DQS_DP<9>  DDR2_SA_DQS_DP9  @S9S_MB_2U_LIB.S9S_MB_2U(SCH_1):M_C_CPU1_SA_DQS_DP<9>
  AH61  M_C_CPU1_SA_DQS_DP<8>  DDR2_SA_DQS_DP8  @S9S_MB_2U_LIB.S9S_MB_2U(SCH_1):M_C_CPU1_SA_DQS_DP<8>
  W64  M_C_CPU1_SA_DQS_DP<7>  DDR2_SA_DQS_DP7  @S9S_MB_2U_LIB.S9S_MB_2U(SCH_1):M_C_CPU1_SA_DQS_DP<7>
  AF67  M_C_CPU1_SA_DQS_DP<6>  DDR2_SA_DQS_DP6  @S9S_MB_2U_LIB.S9S_MB_2U(SCH_1):M_C_CPU1_SA_DQS_DP<6>
  AA76  M_C_CPU1_SA_DQS_DP<5>  DDR2_SA_DQS_DP5  @S9S_MB_2U_LIB.S9S_MB_2U(SCH_1):M_C_CPU1_SA_DQS_DP<5>
  AB55  M_C_CPU1_SA_DQS_DP<4>  DDR2_SA_DQS_DP4  @S9S_MB_2U_LIB.S9S_MB_2U(SCH_1):M_C_CPU1_SA_DQS_DP<4>
  AD61  M_C_CPU1_SA_DQS_DP<3>  DDR2_SA_DQS_DP3  @S9S_MB_2U_LIB.S9S_MB_2U(SCH_1):M_C_CPU1_SA_DQS_DP<3>
  U64  M_C_CPU1_SA_DQS_DP<2>  DDR2_SA_DQS_DP2  @S9S_MB_2U_LIB.S9S_MB_2U(SCH_1):M_C_CPU1_SA_DQS_DP<2>
  AD67  M_C_CPU1_SA_DQS_DP<1>  DDR2_SA_DQS_DP1  @S9S_MB_2U_LIB.S9S_MB_2U(SCH_1):M_C_CPU1_SA_DQS_DP<1>
  U76  M_C_CPU1_SA_DQS_DP<0>  DDR2_SA_DQS_DP0  @S9S_MB_2U_LIB.S9S_MB_2U(SCH_1):M_C_CPU1_SA_DQS_DP<0>
  AH55  M_C_CPU1_SA_DQS_DN<9>  DDR2_SA_DQS_DN9  @S9S_MB_2U_LIB.S9S_MB_2U(SCH_1):M_C_CPU1_SA_DQS_DN<9>
  AF61  M_C_CPU1_SA_DQS_DN<8>  DDR2_SA_DQS_DN8  @S9S_MB_2U_LIB.S9S_MB_2U(SCH_1):M_C_CPU1_SA_DQS_DN<8>
  AA64  M_C_CPU1_SA_DQS_DN<7>  DDR2_SA_DQS_DN7  @S9S_MB_2U_LIB.S9S_MB_2U(SCH_1):M_C_CPU1_SA_DQS_DN<7>
  AH67  M_C_CPU1_SA_DQS_DN<6>  DDR2_SA_DQS_DN6  @S9S_MB_2U_LIB.S9S_MB_2U(SCH_1):M_C_CPU1_SA_DQS_DN<6>
  W76  M_C_CPU1_SA_DQS_DN<5>  DDR2_SA_DQS_DN5  @S9S_MB_2U_LIB.S9S_MB_2U(SCH_1):M_C_CPU1_SA_DQS_DN<5>
  AD55  M_C_CPU1_SA_DQS_DN<4>  DDR2_SA_DQS_DN4  @S9S_MB_2U_LIB.S9S_MB_2U(SCH_1):M_C_CPU1_SA_DQS_DN<4>
  AB61  M_C_CPU1_SA_DQS_DN<3>  DDR2_SA_DQS_DN3  @S9S_MB_2U_LIB.S9S_MB_2U(SCH_1):M_C_CPU1_SA_DQS_DN<3>
  R64  M_C_CPU1_SA_DQS_DN<2>  DDR2_SA_DQS_DN2  @S9S_MB_2U_LIB.S9S_MB_2U(SCH_1):M_C_CPU1_SA_DQS_DN<2>
  AB67  M_C_CPU1_SA_DQS_DN<1>  DDR2_SA_DQS_DN1  @S9S_MB_2U_LIB.S9S_MB_2U(SCH_1):M_C_CPU1_SA_DQS_DN<1>
  R76  M_C_CPU1_SA_DQS_DN<0>  DDR2_SA_DQS_DN0  @S9S_MB_2U_LIB.S9S_MB_2U(SCH_1):M_C_CPU1_SA_DQS_DN<0>
  AC68  M_C_CPU1_SA_DQ<9>  DDR2_SA_DQ9  @S9S_MB_2U_LIB.S9S_MB_2U(SCH_1):M_C_CPU1_SA_DQ<9>
  AD69  M_C_CPU1_SA_DQ<8>  DDR2_SA_DQ8  @S9S_MB_2U_LIB.S9S_MB_2U(SCH_1):M_C_CPU1_SA_DQ<8>
  W74  M_C_CPU1_SA_DQ<7>  DDR2_SA_DQ7  @S9S_MB_2U_LIB.S9S_MB_2U(SCH_1):M_C_CPU1_SA_DQ<7>
  Y75  M_C_CPU1_SA_DQ<6>  DDR2_SA_DQ6  @S9S_MB_2U_LIB.S9S_MB_2U(SCH_1):M_C_CPU1_SA_DQ<6>
  U74  M_C_CPU1_SA_DQ<5>  DDR2_SA_DQ5  @S9S_MB_2U_LIB.S9S_MB_2U(SCH_1):M_C_CPU1_SA_DQ<5>
  T75  M_C_CPU1_SA_DQ<4>  DDR2_SA_DQ4  @S9S_MB_2U_LIB.S9S_MB_2U(SCH_1):M_C_CPU1_SA_DQ<4>
  Y77  M_C_CPU1_SA_DQ<3>  DDR2_SA_DQ3  @S9S_MB_2U_LIB.S9S_MB_2U(SCH_1):M_C_CPU1_SA_DQ<3>
  AF59  M_C_CPU1_SA_DQ<31>  DDR2_SA_DQ31  @S9S_MB_2U_LIB.S9S_MB_2U(SCH_1):M_C_CPU1_SA_DQ<31>
  AG60  M_C_CPU1_SA_DQ<30>  DDR2_SA_DQ30  @S9S_MB_2U_LIB.S9S_MB_2U(SCH_1):M_C_CPU1_SA_DQ<30>
  W78  M_C_CPU1_SA_DQ<2>  DDR2_SA_DQ2  @S9S_MB_2U_LIB.S9S_MB_2U(SCH_1):M_C_CPU1_SA_DQ<2>
  AD59  M_C_CPU1_SA_DQ<29>  DDR2_SA_DQ29  @S9S_MB_2U_LIB.S9S_MB_2U(SCH_1):M_C_CPU1_SA_DQ<29>
  AC60  M_C_CPU1_SA_DQ<28>  DDR2_SA_DQ28  @S9S_MB_2U_LIB.S9S_MB_2U(SCH_1):M_C_CPU1_SA_DQ<28>
  AG62  M_C_CPU1_SA_DQ<27>  DDR2_SA_DQ27  @S9S_MB_2U_LIB.S9S_MB_2U(SCH_1):M_C_CPU1_SA_DQ<27>
  AF63  M_C_CPU1_SA_DQ<26>  DDR2_SA_DQ26  @S9S_MB_2U_LIB.S9S_MB_2U(SCH_1):M_C_CPU1_SA_DQ<26>
  AC62  M_C_CPU1_SA_DQ<25>  DDR2_SA_DQ25  @S9S_MB_2U_LIB.S9S_MB_2U(SCH_1):M_C_CPU1_SA_DQ<25>
  AD63  M_C_CPU1_SA_DQ<24>  DDR2_SA_DQ24  @S9S_MB_2U_LIB.S9S_MB_2U(SCH_1):M_C_CPU1_SA_DQ<24>
  W62  M_C_CPU1_SA_DQ<23>  DDR2_SA_DQ23  @S9S_MB_2U_LIB.S9S_MB_2U(SCH_1):M_C_CPU1_SA_DQ<23>
  Y63  M_C_CPU1_SA_DQ<22>  DDR2_SA_DQ22  @S9S_MB_2U_LIB.S9S_MB_2U(SCH_1):M_C_CPU1_SA_DQ<22>
  U62  M_C_CPU1_SA_DQ<21>  DDR2_SA_DQ21  @S9S_MB_2U_LIB.S9S_MB_2U(SCH_1):M_C_CPU1_SA_DQ<21>
  T63  M_C_CPU1_SA_DQ<20>  DDR2_SA_DQ20  @S9S_MB_2U_LIB.S9S_MB_2U(SCH_1):M_C_CPU1_SA_DQ<20>
  T77  M_C_CPU1_SA_DQ<1>  DDR2_SA_DQ1  @S9S_MB_2U_LIB.S9S_MB_2U(SCH_1):M_C_CPU1_SA_DQ<1>
  Y65  M_C_CPU1_SA_DQ<19>  DDR2_SA_DQ19  @S9S_MB_2U_LIB.S9S_MB_2U(SCH_1):M_C_CPU1_SA_DQ<19>
  W66  M_C_CPU1_SA_DQ<18>  DDR2_SA_DQ18  @S9S_MB_2U_LIB.S9S_MB_2U(SCH_1):M_C_CPU1_SA_DQ<18>
  T65  M_C_CPU1_SA_DQ<17>  DDR2_SA_DQ17  @S9S_MB_2U_LIB.S9S_MB_2U(SCH_1):M_C_CPU1_SA_DQ<17>
  U66  M_C_CPU1_SA_DQ<16>  DDR2_SA_DQ16  @S9S_MB_2U_LIB.S9S_MB_2U(SCH_1):M_C_CPU1_SA_DQ<16>
  AF65  M_C_CPU1_SA_DQ<15>  DDR2_SA_DQ15  @S9S_MB_2U_LIB.S9S_MB_2U(SCH_1):M_C_CPU1_SA_DQ<15>
  AG66  M_C_CPU1_SA_DQ<14>  DDR2_SA_DQ14  @S9S_MB_2U_LIB.S9S_MB_2U(SCH_1):M_C_CPU1_SA_DQ<14>
  AD65  M_C_CPU1_SA_DQ<13>  DDR2_SA_DQ13  @S9S_MB_2U_LIB.S9S_MB_2U(SCH_1):M_C_CPU1_SA_DQ<13>
  AC66  M_C_CPU1_SA_DQ<12>  DDR2_SA_DQ12  @S9S_MB_2U_LIB.S9S_MB_2U(SCH_1):M_C_CPU1_SA_DQ<12>
  AG68  M_C_CPU1_SA_DQ<11>  DDR2_SA_DQ11  @S9S_MB_2U_LIB.S9S_MB_2U(SCH_1):M_C_CPU1_SA_DQ<11>
  AF69  M_C_CPU1_SA_DQ<10>  DDR2_SA_DQ10  @S9S_MB_2U_LIB.S9S_MB_2U(SCH_1):M_C_CPU1_SA_DQ<10>
  U78  M_C_CPU1_SA_DQ<0>  DDR2_SA_DQ0  @S9S_MB_2U_LIB.S9S_MB_2U(SCH_1):M_C_CPU1_SA_DQ<0>
  Y53  M_C_CPU1_SA_CS_N<3>  DDR2_SA_CS3_N  @S9S_MB_2U_LIB.S9S_MB_2U(SCH_1):M_C_CPU1_SA_CS_N<3>
  W54  M_C_CPU1_SA_CS_N<2>  DDR2_SA_CS2_N  @S9S_MB_2U_LIB.S9S_MB_2U(SCH_1):M_C_CPU1_SA_CS_N<2>
  T53  M_C_CPU1_SA_CS_N<1>  DDR2_SA_CS1_N  @S9S_MB_2U_LIB.S9S_MB_2U(SCH_1):M_C_CPU1_SA_CS_N<1>
  U54  M_C_CPU1_SA_CS_N<0>  DDR2_SA_CS0_N  @S9S_MB_2U_LIB.S9S_MB_2U(SCH_1):M_C_CPU1_SA_CS_N<0>
  AF53  M_C_CPU1_SA_CB<7>  DDR2_SA_ECC7  @S9S_MB_2U_LIB.S9S_MB_2U(SCH_1):M_C_CPU1_SA_CB<7>
  AG54  M_C_CPU1_SA_CB<6>  DDR2_SA_ECC6  @S9S_MB_2U_LIB.S9S_MB_2U(SCH_1):M_C_CPU1_SA_CB<6>
  AD53  M_C_CPU1_SA_CB<5>  DDR2_SA_ECC5  @S9S_MB_2U_LIB.S9S_MB_2U(SCH_1):M_C_CPU1_SA_CB<5>
  AC54  M_C_CPU1_SA_CB<4>  DDR2_SA_ECC4  @S9S_MB_2U_LIB.S9S_MB_2U(SCH_1):M_C_CPU1_SA_CB<4>
  AG56  M_C_CPU1_SA_CB<3>  DDR2_SA_ECC3  @S9S_MB_2U_LIB.S9S_MB_2U(SCH_1):M_C_CPU1_SA_CB<3>
  AF57  M_C_CPU1_SA_CB<2>  DDR2_SA_ECC2  @S9S_MB_2U_LIB.S9S_MB_2U(SCH_1):M_C_CPU1_SA_CB<2>
  AC56  M_C_CPU1_SA_CB<1>  DDR2_SA_ECC1  @S9S_MB_2U_LIB.S9S_MB_2U(SCH_1):M_C_CPU1_SA_CB<1>
  AD57  M_C_CPU1_SA_CB<0>  DDR2_SA_ECC0  @S9S_MB_2U_LIB.S9S_MB_2U(SCH_1):M_C_CPU1_SA_CB<0>
  U48  M_C_CPU1_SA_CA<6>  DDR2_SA_CA6  @S9S_MB_2U_LIB.S9S_MB_2U(SCH_1):M_C_CPU1_SA_CA<6>
  W50  M_C_CPU1_SA_CA<5>  DDR2_SA_CA5  @S9S_MB_2U_LIB.S9S_MB_2U(SCH_1):M_C_CPU1_SA_CA<5>
  U50  M_C_CPU1_SA_CA<4>  DDR2_SA_CA4  @S9S_MB_2U_LIB.S9S_MB_2U(SCH_1):M_C_CPU1_SA_CA<4>
  Y51  M_C_CPU1_SA_CA<3>  DDR2_SA_CA3  @S9S_MB_2U_LIB.S9S_MB_2U(SCH_1):M_C_CPU1_SA_CA<3>
  T51  M_C_CPU1_SA_CA<2>  DDR2_SA_CA2  @S9S_MB_2U_LIB.S9S_MB_2U(SCH_1):M_C_CPU1_SA_CA<2>
  AA52  M_C_CPU1_SA_CA<1>  DDR2_SA_CA1  @S9S_MB_2U_LIB.S9S_MB_2U(SCH_1):M_C_CPU1_SA_CA<1>
  R52  M_C_CPU1_SA_CA<0>  DDR2_SA_CA0  @S9S_MB_2U_LIB.S9S_MB_2U(SCH_1):M_C_CPU1_SA_CA<0>
  AH49  M_C_CPU1_CLK_DP<1>  DDR2_CLK_DP1  @S9S_MB_2U_LIB.S9S_MB_2U(SCH_1):M_C_CPU1_CLK_DP<1>
  AD49  M_C_CPU1_CLK_DP<0>  DDR2_CLK_DP0  @S9S_MB_2U_LIB.S9S_MB_2U(SCH_1):M_C_CPU1_CLK_DP<0>
  AF49  M_C_CPU1_CLK_DN<1>  DDR2_CLK_DN1  @S9S_MB_2U_LIB.S9S_MB_2U(SCH_1):M_C_CPU1_CLK_DN<1>
  AB49  M_C_CPU1_CLK_DN<0>  DDR2_CLK_DN0  @S9S_MB_2U_LIB.S9S_MB_2U(SCH_1):M_C_CPU1_CLK_DN<0>
  AT47  M_C_CPU1_ALERT_N  DDR2_ALERT_N  @S9S_MB_2U_LIB.S9S_MB_2U(SCH_1):M_C_CPU1_ALERT_N

SOCKET4677_AZIFS054P001C01  I91  U1     [SOCKET4677_AZIFS054P001C01-SOCA]
  AP47  M_B_CPU1_SB_RSP<1>  DDR1_B_RSP1  @S9S_MB_2U_LIB.S9S_MB_2U(SCH_1):M_B_CPU1_SB_RSP<1>
  AN48  M_B_CPU1_SB_RSP<0>  DDR1_B_RSP0  @S9S_MB_2U_LIB.S9S_MB_2U(SCH_1):M_B_CPU1_SB_RSP<0>
  P42  M_B_CPU1_SB_PAR  DDR1_SB_PAR  @S9S_MB_2U_LIB.S9S_MB_2U(SCH_1):M_B_CPU1_SB_PAR
  H36  M_B_CPU1_SB_DQS_DP<9>  DDR1_SB_DQS_DP9  @S9S_MB_2U_LIB.S9S_MB_2U(SCH_1):M_B_CPU1_SB_DQS_DP<9>
  G15  M_B_CPU1_SB_DQS_DP<8>  DDR1_SB_DQS_DP8  @S9S_MB_2U_LIB.S9S_MB_2U(SCH_1):M_B_CPU1_SB_DQS_DP<8>
  P18  M_B_CPU1_SB_DQS_DP<7>  DDR1_SB_DQS_DP7  @S9S_MB_2U_LIB.S9S_MB_2U(SCH_1):M_B_CPU1_SB_DQS_DP<7>
  P24  M_B_CPU1_SB_DQS_DP<6>  DDR1_SB_DQS_DP6  @S9S_MB_2U_LIB.S9S_MB_2U(SCH_1):M_B_CPU1_SB_DQS_DP<6>
  AA27  M_B_CPU1_SB_DQS_DP<5>  DDR1_SB_DQS_DP5  @S9S_MB_2U_LIB.S9S_MB_2U(SCH_1):M_B_CPU1_SB_DQS_DP<5>
  M36  M_B_CPU1_SB_DQS_DP<4>  DDR1_SB_DQS_DP4  @S9S_MB_2U_LIB.S9S_MB_2U(SCH_1):M_B_CPU1_SB_DQS_DP<4>
  C15  M_B_CPU1_SB_DQS_DP<3>  DDR1_SB_DQS_DP3  @S9S_MB_2U_LIB.S9S_MB_2U(SCH_1):M_B_CPU1_SB_DQS_DP<3>
  K18  M_B_CPU1_SB_DQS_DP<2>  DDR1_SB_DQS_DP2  @S9S_MB_2U_LIB.S9S_MB_2U(SCH_1):M_B_CPU1_SB_DQS_DP<2>
  K24  M_B_CPU1_SB_DQS_DP<1>  DDR1_SB_DQS_DP1  @S9S_MB_2U_LIB.S9S_MB_2U(SCH_1):M_B_CPU1_SB_DQS_DP<1>
  U27  M_B_CPU1_SB_DQS_DP<0>  DDR1_SB_DQS_DP0  @S9S_MB_2U_LIB.S9S_MB_2U(SCH_1):M_B_CPU1_SB_DQS_DP<0>
  K36  M_B_CPU1_SB_DQS_DN<9>  DDR1_SB_DQS_DN9  @S9S_MB_2U_LIB.S9S_MB_2U(SCH_1):M_B_CPU1_SB_DQS_DN<9>
  E15  M_B_CPU1_SB_DQS_DN<8>  DDR1_SB_DQS_DN8  @S9S_MB_2U_LIB.S9S_MB_2U(SCH_1):M_B_CPU1_SB_DQS_DN<8>
  M18  M_B_CPU1_SB_DQS_DN<7>  DDR1_SB_DQS_DN7  @S9S_MB_2U_LIB.S9S_MB_2U(SCH_1):M_B_CPU1_SB_DQS_DN<7>
  M24  M_B_CPU1_SB_DQS_DN<6>  DDR1_SB_DQS_DN6  @S9S_MB_2U_LIB.S9S_MB_2U(SCH_1):M_B_CPU1_SB_DQS_DN<6>
  W27  M_B_CPU1_SB_DQS_DN<5>  DDR1_SB_DQS_DN5  @S9S_MB_2U_LIB.S9S_MB_2U(SCH_1):M_B_CPU1_SB_DQS_DN<5>
  P36  M_B_CPU1_SB_DQS_DN<4>  DDR1_SB_DQS_DN4  @S9S_MB_2U_LIB.S9S_MB_2U(SCH_1):M_B_CPU1_SB_DQS_DN<4>
  A15  M_B_CPU1_SB_DQS_DN<3>  DDR1_SB_DQS_DN3  @S9S_MB_2U_LIB.S9S_MB_2U(SCH_1):M_B_CPU1_SB_DQS_DN<3>
  H18  M_B_CPU1_SB_DQS_DN<2>  DDR1_SB_DQS_DN2  @S9S_MB_2U_LIB.S9S_MB_2U(SCH_1):M_B_CPU1_SB_DQS_DN<2>
  H24  M_B_CPU1_SB_DQS_DN<1>  DDR1_SB_DQS_DN1  @S9S_MB_2U_LIB.S9S_MB_2U(SCH_1):M_B_CPU1_SB_DQS_DN<1>
  R27  M_B_CPU1_SB_DQS_DN<0>  DDR1_SB_DQS_DN0  @S9S_MB_2U_LIB.S9S_MB_2U(SCH_1):M_B_CPU1_SB_DQS_DN<0>
  J25  M_B_CPU1_SB_DQ<9>  DDR1_SB_DQ9  @S9S_MB_2U_LIB.S9S_MB_2U(SCH_1):M_B_CPU1_SB_DQ<9>
  K26  M_B_CPU1_SB_DQ<8>  DDR1_SB_DQ8  @S9S_MB_2U_LIB.S9S_MB_2U(SCH_1):M_B_CPU1_SB_DQ<8>
  W25  M_B_CPU1_SB_DQ<7>  DDR1_SB_DQ7  @S9S_MB_2U_LIB.S9S_MB_2U(SCH_1):M_B_CPU1_SB_DQ<7>
  Y26  M_B_CPU1_SB_DQ<6>  DDR1_SB_DQ6  @S9S_MB_2U_LIB.S9S_MB_2U(SCH_1):M_B_CPU1_SB_DQ<6>
  U25  M_B_CPU1_SB_DQ<5>  DDR1_SB_DQ5  @S9S_MB_2U_LIB.S9S_MB_2U(SCH_1):M_B_CPU1_SB_DQ<5>
  T26  M_B_CPU1_SB_DQ<4>  DDR1_SB_DQ4  @S9S_MB_2U_LIB.S9S_MB_2U(SCH_1):M_B_CPU1_SB_DQ<4>
  Y28  M_B_CPU1_SB_DQ<3>  DDR1_SB_DQ3  @S9S_MB_2U_LIB.S9S_MB_2U(SCH_1):M_B_CPU1_SB_DQ<3>
  F14  M_B_CPU1_SB_DQ<31>  DDR1_SB_DQ31  @S9S_MB_2U_LIB.S9S_MB_2U(SCH_1):M_B_CPU1_SB_DQ<31>
  B14  M_B_CPU1_SB_DQ<30>  DDR1_SB_DQ30  @S9S_MB_2U_LIB.S9S_MB_2U(SCH_1):M_B_CPU1_SB_DQ<30>
  W29  M_B_CPU1_SB_DQ<2>  DDR1_SB_DQ2  @S9S_MB_2U_LIB.S9S_MB_2U(SCH_1):M_B_CPU1_SB_DQ<2>
  E13  M_B_CPU1_SB_DQ<29>  DDR1_SB_DQ29  @S9S_MB_2U_LIB.S9S_MB_2U(SCH_1):M_B_CPU1_SB_DQ<29>
  C13  M_B_CPU1_SB_DQ<28>  DDR1_SB_DQ28  @S9S_MB_2U_LIB.S9S_MB_2U(SCH_1):M_B_CPU1_SB_DQ<28>
  F16  M_B_CPU1_SB_DQ<27>  DDR1_SB_DQ27  @S9S_MB_2U_LIB.S9S_MB_2U(SCH_1):M_B_CPU1_SB_DQ<27>
  E17  M_B_CPU1_SB_DQ<26>  DDR1_SB_DQ26  @S9S_MB_2U_LIB.S9S_MB_2U(SCH_1):M_B_CPU1_SB_DQ<26>
  B16  M_B_CPU1_SB_DQ<25>  DDR1_SB_DQ25  @S9S_MB_2U_LIB.S9S_MB_2U(SCH_1):M_B_CPU1_SB_DQ<25>
  C17  M_B_CPU1_SB_DQ<24>  DDR1_SB_DQ24  @S9S_MB_2U_LIB.S9S_MB_2U(SCH_1):M_B_CPU1_SB_DQ<24>
  M16  M_B_CPU1_SB_DQ<23>  DDR1_SB_DQ23  @S9S_MB_2U_LIB.S9S_MB_2U(SCH_1):M_B_CPU1_SB_DQ<23>
  N17  M_B_CPU1_SB_DQ<22>  DDR1_SB_DQ22  @S9S_MB_2U_LIB.S9S_MB_2U(SCH_1):M_B_CPU1_SB_DQ<22>
  K16  M_B_CPU1_SB_DQ<21>  DDR1_SB_DQ21  @S9S_MB_2U_LIB.S9S_MB_2U(SCH_1):M_B_CPU1_SB_DQ<21>
  J17  M_B_CPU1_SB_DQ<20>  DDR1_SB_DQ20  @S9S_MB_2U_LIB.S9S_MB_2U(SCH_1):M_B_CPU1_SB_DQ<20>
  T28  M_B_CPU1_SB_DQ<1>  DDR1_SB_DQ1  @S9S_MB_2U_LIB.S9S_MB_2U(SCH_1):M_B_CPU1_SB_DQ<1>
  N19  M_B_CPU1_SB_DQ<19>  DDR1_SB_DQ19  @S9S_MB_2U_LIB.S9S_MB_2U(SCH_1):M_B_CPU1_SB_DQ<19>
  M20  M_B_CPU1_SB_DQ<18>  DDR1_SB_DQ18  @S9S_MB_2U_LIB.S9S_MB_2U(SCH_1):M_B_CPU1_SB_DQ<18>
  J19  M_B_CPU1_SB_DQ<17>  DDR1_SB_DQ17  @S9S_MB_2U_LIB.S9S_MB_2U(SCH_1):M_B_CPU1_SB_DQ<17>
  K20  M_B_CPU1_SB_DQ<16>  DDR1_SB_DQ16  @S9S_MB_2U_LIB.S9S_MB_2U(SCH_1):M_B_CPU1_SB_DQ<16>
  M22  M_B_CPU1_SB_DQ<15>  DDR1_SB_DQ15  @S9S_MB_2U_LIB.S9S_MB_2U(SCH_1):M_B_CPU1_SB_DQ<15>
  N23  M_B_CPU1_SB_DQ<14>  DDR1_SB_DQ14  @S9S_MB_2U_LIB.S9S_MB_2U(SCH_1):M_B_CPU1_SB_DQ<14>
  K22  M_B_CPU1_SB_DQ<13>  DDR1_SB_DQ13  @S9S_MB_2U_LIB.S9S_MB_2U(SCH_1):M_B_CPU1_SB_DQ<13>
  J23  M_B_CPU1_SB_DQ<12>  DDR1_SB_DQ12  @S9S_MB_2U_LIB.S9S_MB_2U(SCH_1):M_B_CPU1_SB_DQ<12>
  N25  M_B_CPU1_SB_DQ<11>  DDR1_SB_DQ11  @S9S_MB_2U_LIB.S9S_MB_2U(SCH_1):M_B_CPU1_SB_DQ<11>
  M26  M_B_CPU1_SB_DQ<10>  DDR1_SB_DQ10  @S9S_MB_2U_LIB.S9S_MB_2U(SCH_1):M_B_CPU1_SB_DQ<10>
  U29  M_B_CPU1_SB_DQ<0>  DDR1_SB_DQ0  @S9S_MB_2U_LIB.S9S_MB_2U(SCH_1):M_B_CPU1_SB_DQ<0>
  M40  M_B_CPU1_SB_CS_N<3>  DDR1_SB_CS3_N  @S9S_MB_2U_LIB.S9S_MB_2U(SCH_1):M_B_CPU1_SB_CS_N<3>
  N41  M_B_CPU1_SB_CS_N<2>  DDR1_SB_CS2_N  @S9S_MB_2U_LIB.S9S_MB_2U(SCH_1):M_B_CPU1_SB_CS_N<2>
  K40  M_B_CPU1_SB_CS_N<1>  DDR1_SB_CS1_N  @S9S_MB_2U_LIB.S9S_MB_2U(SCH_1):M_B_CPU1_SB_CS_N<1>
  J41  M_B_CPU1_SB_CS_N<0>  DDR1_SB_CS0_N  @S9S_MB_2U_LIB.S9S_MB_2U(SCH_1):M_B_CPU1_SB_CS_N<0>
  N37  M_B_CPU1_SB_CB<7>  DDR1_SB_ECC7  @S9S_MB_2U_LIB.S9S_MB_2U(SCH_1):M_B_CPU1_SB_CB<7>
  M38  M_B_CPU1_SB_CB<6>  DDR1_SB_ECC6  @S9S_MB_2U_LIB.S9S_MB_2U(SCH_1):M_B_CPU1_SB_CB<6>
  J37  M_B_CPU1_SB_CB<5>  DDR1_SB_ECC5  @S9S_MB_2U_LIB.S9S_MB_2U(SCH_1):M_B_CPU1_SB_CB<5>
  K38  M_B_CPU1_SB_CB<4>  DDR1_SB_ECC4  @S9S_MB_2U_LIB.S9S_MB_2U(SCH_1):M_B_CPU1_SB_CB<4>
  M34  M_B_CPU1_SB_CB<3>  DDR1_SB_ECC3  @S9S_MB_2U_LIB.S9S_MB_2U(SCH_1):M_B_CPU1_SB_CB<3>
  N35  M_B_CPU1_SB_CB<2>  DDR1_SB_ECC2  @S9S_MB_2U_LIB.S9S_MB_2U(SCH_1):M_B_CPU1_SB_CB<2>
  K34  M_B_CPU1_SB_CB<1>  DDR1_SB_ECC1  @S9S_MB_2U_LIB.S9S_MB_2U(SCH_1):M_B_CPU1_SB_CB<1>
  J35  M_B_CPU1_SB_CB<0>  DDR1_SB_ECC0  @S9S_MB_2U_LIB.S9S_MB_2U(SCH_1):M_B_CPU1_SB_CB<0>
  H42  M_B_CPU1_SB_CA<6>  DDR1_SB_CA6  @S9S_MB_2U_LIB.S9S_MB_2U(SCH_1):M_B_CPU1_SB_CA<6>
  N43  M_B_CPU1_SB_CA<5>  DDR1_SB_CA5  @S9S_MB_2U_LIB.S9S_MB_2U(SCH_1):M_B_CPU1_SB_CA<5>
  J43  M_B_CPU1_SB_CA<4>  DDR1_SB_CA4  @S9S_MB_2U_LIB.S9S_MB_2U(SCH_1):M_B_CPU1_SB_CA<4>
  M44  M_B_CPU1_SB_CA<3>  DDR1_SB_CA3  @S9S_MB_2U_LIB.S9S_MB_2U(SCH_1):M_B_CPU1_SB_CA<3>
  K44  M_B_CPU1_SB_CA<2>  DDR1_SB_CA2  @S9S_MB_2U_LIB.S9S_MB_2U(SCH_1):M_B_CPU1_SB_CA<2>
  U43  M_B_CPU1_SB_CA<1>  DDR1_SB_CA1  @S9S_MB_2U_LIB.S9S_MB_2U(SCH_1):M_B_CPU1_SB_CA<1>
  T44  M_B_CPU1_SB_CA<0>  DDR1_SB_CA0  @S9S_MB_2U_LIB.S9S_MB_2U(SCH_1):M_B_CPU1_SB_CA<0>
  AK47  M_B_CPU1_SA_RSP<1>  DDR1_A_RSP1  @S9S_MB_2U_LIB.S9S_MB_2U(SCH_1):M_B_CPU1_SA_RSP<1>
  AL48  M_B_CPU1_SA_RSP<0>  DDR1_A_RSP0  @S9S_MB_2U_LIB.S9S_MB_2U(SCH_1):M_B_CPU1_SA_RSP<0>
  W43  M_B_CPU1_SA_PAR  DDR1_SA_PAR  @S9S_MB_2U_LIB.S9S_MB_2U(SCH_1):M_B_CPU1_SA_PAR
  P55  M_B_CPU1_SA_DQS_DP<9>  DDR1_SA_DQS_DP9  @S9S_MB_2U_LIB.S9S_MB_2U(SCH_1):M_B_CPU1_SA_DQS_DP<9>
  W58  M_B_CPU1_SA_DQS_DP<8>  DDR1_SA_DQS_DP8  @S9S_MB_2U_LIB.S9S_MB_2U(SCH_1):M_B_CPU1_SA_DQS_DP<8>
  P61  M_B_CPU1_SA_DQS_DP<7>  DDR1_SA_DQS_DP7  @S9S_MB_2U_LIB.S9S_MB_2U(SCH_1):M_B_CPU1_SA_DQS_DP<7>
  W70  M_B_CPU1_SA_DQS_DP<6>  DDR1_SA_DQS_DP6  @S9S_MB_2U_LIB.S9S_MB_2U(SCH_1):M_B_CPU1_SA_DQS_DP<6>
  P73  M_B_CPU1_SA_DQS_DP<5>  DDR1_SA_DQS_DP5  @S9S_MB_2U_LIB.S9S_MB_2U(SCH_1):M_B_CPU1_SA_DQS_DP<5>
  K55  M_B_CPU1_SA_DQS_DP<4>  DDR1_SA_DQS_DP4  @S9S_MB_2U_LIB.S9S_MB_2U(SCH_1):M_B_CPU1_SA_DQS_DP<4>
  U58  M_B_CPU1_SA_DQS_DP<3>  DDR1_SA_DQS_DP3  @S9S_MB_2U_LIB.S9S_MB_2U(SCH_1):M_B_CPU1_SA_DQS_DP<3>
  K61  M_B_CPU1_SA_DQS_DP<2>  DDR1_SA_DQS_DP2  @S9S_MB_2U_LIB.S9S_MB_2U(SCH_1):M_B_CPU1_SA_DQS_DP<2>
  U70  M_B_CPU1_SA_DQS_DP<1>  DDR1_SA_DQS_DP1  @S9S_MB_2U_LIB.S9S_MB_2U(SCH_1):M_B_CPU1_SA_DQS_DP<1>
  K73  M_B_CPU1_SA_DQS_DP<0>  DDR1_SA_DQS_DP0  @S9S_MB_2U_LIB.S9S_MB_2U(SCH_1):M_B_CPU1_SA_DQS_DP<0>
  M55  M_B_CPU1_SA_DQS_DN<9>  DDR1_SA_DQS_DN9  @S9S_MB_2U_LIB.S9S_MB_2U(SCH_1):M_B_CPU1_SA_DQS_DN<9>
  AA58  M_B_CPU1_SA_DQS_DN<8>  DDR1_SA_DQS_DN8  @S9S_MB_2U_LIB.S9S_MB_2U(SCH_1):M_B_CPU1_SA_DQS_DN<8>
  M61  M_B_CPU1_SA_DQS_DN<7>  DDR1_SA_DQS_DN7  @S9S_MB_2U_LIB.S9S_MB_2U(SCH_1):M_B_CPU1_SA_DQS_DN<7>
  AA70  M_B_CPU1_SA_DQS_DN<6>  DDR1_SA_DQS_DN6  @S9S_MB_2U_LIB.S9S_MB_2U(SCH_1):M_B_CPU1_SA_DQS_DN<6>
  M73  M_B_CPU1_SA_DQS_DN<5>  DDR1_SA_DQS_DN5  @S9S_MB_2U_LIB.S9S_MB_2U(SCH_1):M_B_CPU1_SA_DQS_DN<5>
  H55  M_B_CPU1_SA_DQS_DN<4>  DDR1_SA_DQS_DN4  @S9S_MB_2U_LIB.S9S_MB_2U(SCH_1):M_B_CPU1_SA_DQS_DN<4>
  R58  M_B_CPU1_SA_DQS_DN<3>  DDR1_SA_DQS_DN3  @S9S_MB_2U_LIB.S9S_MB_2U(SCH_1):M_B_CPU1_SA_DQS_DN<3>
  H61  M_B_CPU1_SA_DQS_DN<2>  DDR1_SA_DQS_DN2  @S9S_MB_2U_LIB.S9S_MB_2U(SCH_1):M_B_CPU1_SA_DQS_DN<2>
  R70  M_B_CPU1_SA_DQS_DN<1>  DDR1_SA_DQS_DN1  @S9S_MB_2U_LIB.S9S_MB_2U(SCH_1):M_B_CPU1_SA_DQS_DN<1>
  H73  M_B_CPU1_SA_DQS_DN<0>  DDR1_SA_DQS_DN0  @S9S_MB_2U_LIB.S9S_MB_2U(SCH_1):M_B_CPU1_SA_DQS_DN<0>
  T71  M_B_CPU1_SA_DQ<9>  DDR1_SA_DQ9  @S9S_MB_2U_LIB.S9S_MB_2U(SCH_1):M_B_CPU1_SA_DQ<9>
  U72  M_B_CPU1_SA_DQ<8>  DDR1_SA_DQ8  @S9S_MB_2U_LIB.S9S_MB_2U(SCH_1):M_B_CPU1_SA_DQ<8>
  M71  M_B_CPU1_SA_DQ<7>  DDR1_SA_DQ7  @S9S_MB_2U_LIB.S9S_MB_2U(SCH_1):M_B_CPU1_SA_DQ<7>
  N72  M_B_CPU1_SA_DQ<6>  DDR1_SA_DQ6  @S9S_MB_2U_LIB.S9S_MB_2U(SCH_1):M_B_CPU1_SA_DQ<6>
  K71  M_B_CPU1_SA_DQ<5>  DDR1_SA_DQ5  @S9S_MB_2U_LIB.S9S_MB_2U(SCH_1):M_B_CPU1_SA_DQ<5>
  J72  M_B_CPU1_SA_DQ<4>  DDR1_SA_DQ4  @S9S_MB_2U_LIB.S9S_MB_2U(SCH_1):M_B_CPU1_SA_DQ<4>
  N74  M_B_CPU1_SA_DQ<3>  DDR1_SA_DQ3  @S9S_MB_2U_LIB.S9S_MB_2U(SCH_1):M_B_CPU1_SA_DQ<3>
  W56  M_B_CPU1_SA_DQ<31>  DDR1_SA_DQ31  @S9S_MB_2U_LIB.S9S_MB_2U(SCH_1):M_B_CPU1_SA_DQ<31>
  Y57  M_B_CPU1_SA_DQ<30>  DDR1_SA_DQ30  @S9S_MB_2U_LIB.S9S_MB_2U(SCH_1):M_B_CPU1_SA_DQ<30>
  M75  M_B_CPU1_SA_DQ<2>  DDR1_SA_DQ2  @S9S_MB_2U_LIB.S9S_MB_2U(SCH_1):M_B_CPU1_SA_DQ<2>
  U56  M_B_CPU1_SA_DQ<29>  DDR1_SA_DQ29  @S9S_MB_2U_LIB.S9S_MB_2U(SCH_1):M_B_CPU1_SA_DQ<29>
  T57  M_B_CPU1_SA_DQ<28>  DDR1_SA_DQ28  @S9S_MB_2U_LIB.S9S_MB_2U(SCH_1):M_B_CPU1_SA_DQ<28>
  Y59  M_B_CPU1_SA_DQ<27>  DDR1_SA_DQ27  @S9S_MB_2U_LIB.S9S_MB_2U(SCH_1):M_B_CPU1_SA_DQ<27>
  W60  M_B_CPU1_SA_DQ<26>  DDR1_SA_DQ26  @S9S_MB_2U_LIB.S9S_MB_2U(SCH_1):M_B_CPU1_SA_DQ<26>
  T59  M_B_CPU1_SA_DQ<25>  DDR1_SA_DQ25  @S9S_MB_2U_LIB.S9S_MB_2U(SCH_1):M_B_CPU1_SA_DQ<25>
  U60  M_B_CPU1_SA_DQ<24>  DDR1_SA_DQ24  @S9S_MB_2U_LIB.S9S_MB_2U(SCH_1):M_B_CPU1_SA_DQ<24>
  M59  M_B_CPU1_SA_DQ<23>  DDR1_SA_DQ23  @S9S_MB_2U_LIB.S9S_MB_2U(SCH_1):M_B_CPU1_SA_DQ<23>
  N60  M_B_CPU1_SA_DQ<22>  DDR1_SA_DQ22  @S9S_MB_2U_LIB.S9S_MB_2U(SCH_1):M_B_CPU1_SA_DQ<22>
  K59  M_B_CPU1_SA_DQ<21>  DDR1_SA_DQ21  @S9S_MB_2U_LIB.S9S_MB_2U(SCH_1):M_B_CPU1_SA_DQ<21>
  J60  M_B_CPU1_SA_DQ<20>  DDR1_SA_DQ20  @S9S_MB_2U_LIB.S9S_MB_2U(SCH_1):M_B_CPU1_SA_DQ<20>
  J74  M_B_CPU1_SA_DQ<1>  DDR1_SA_DQ1  @S9S_MB_2U_LIB.S9S_MB_2U(SCH_1):M_B_CPU1_SA_DQ<1>
  N62  M_B_CPU1_SA_DQ<19>  DDR1_SA_DQ19  @S9S_MB_2U_LIB.S9S_MB_2U(SCH_1):M_B_CPU1_SA_DQ<19>
  M63  M_B_CPU1_SA_DQ<18>  DDR1_SA_DQ18  @S9S_MB_2U_LIB.S9S_MB_2U(SCH_1):M_B_CPU1_SA_DQ<18>
  J62  M_B_CPU1_SA_DQ<17>  DDR1_SA_DQ17  @S9S_MB_2U_LIB.S9S_MB_2U(SCH_1):M_B_CPU1_SA_DQ<17>
  K63  M_B_CPU1_SA_DQ<16>  DDR1_SA_DQ16  @S9S_MB_2U_LIB.S9S_MB_2U(SCH_1):M_B_CPU1_SA_DQ<16>
  W68  M_B_CPU1_SA_DQ<15>  DDR1_SA_DQ15  @S9S_MB_2U_LIB.S9S_MB_2U(SCH_1):M_B_CPU1_SA_DQ<15>
  Y69  M_B_CPU1_SA_DQ<14>  DDR1_SA_DQ14  @S9S_MB_2U_LIB.S9S_MB_2U(SCH_1):M_B_CPU1_SA_DQ<14>
  U68  M_B_CPU1_SA_DQ<13>  DDR1_SA_DQ13  @S9S_MB_2U_LIB.S9S_MB_2U(SCH_1):M_B_CPU1_SA_DQ<13>
  T69  M_B_CPU1_SA_DQ<12>  DDR1_SA_DQ12  @S9S_MB_2U_LIB.S9S_MB_2U(SCH_1):M_B_CPU1_SA_DQ<12>
  Y71  M_B_CPU1_SA_DQ<11>  DDR1_SA_DQ11  @S9S_MB_2U_LIB.S9S_MB_2U(SCH_1):M_B_CPU1_SA_DQ<11>
  W72  M_B_CPU1_SA_DQ<10>  DDR1_SA_DQ10  @S9S_MB_2U_LIB.S9S_MB_2U(SCH_1):M_B_CPU1_SA_DQ<10>
  K75  M_B_CPU1_SA_DQ<0>  DDR1_SA_DQ0  @S9S_MB_2U_LIB.S9S_MB_2U(SCH_1):M_B_CPU1_SA_DQ<0>
  N50  M_B_CPU1_SA_CS_N<3>  DDR1_SA_CS3_N  @S9S_MB_2U_LIB.S9S_MB_2U(SCH_1):M_B_CPU1_SA_CS_N<3>
  M51  M_B_CPU1_SA_CS_N<2>  DDR1_SA_CS2_N  @S9S_MB_2U_LIB.S9S_MB_2U(SCH_1):M_B_CPU1_SA_CS_N<2>
  J50  M_B_CPU1_SA_CS_N<1>  DDR1_SA_CS1_N  @S9S_MB_2U_LIB.S9S_MB_2U(SCH_1):M_B_CPU1_SA_CS_N<1>
  K51  M_B_CPU1_SA_CS_N<0>  DDR1_SA_CS0_N  @S9S_MB_2U_LIB.S9S_MB_2U(SCH_1):M_B_CPU1_SA_CS_N<0>
  M53  M_B_CPU1_SA_CB<7>  DDR1_SA_ECC7  @S9S_MB_2U_LIB.S9S_MB_2U(SCH_1):M_B_CPU1_SA_CB<7>
  N54  M_B_CPU1_SA_CB<6>  DDR1_SA_ECC6  @S9S_MB_2U_LIB.S9S_MB_2U(SCH_1):M_B_CPU1_SA_CB<6>
  K53  M_B_CPU1_SA_CB<5>  DDR1_SA_ECC5  @S9S_MB_2U_LIB.S9S_MB_2U(SCH_1):M_B_CPU1_SA_CB<5>
  J54  M_B_CPU1_SA_CB<4>  DDR1_SA_ECC4  @S9S_MB_2U_LIB.S9S_MB_2U(SCH_1):M_B_CPU1_SA_CB<4>
  N56  M_B_CPU1_SA_CB<3>  DDR1_SA_ECC3  @S9S_MB_2U_LIB.S9S_MB_2U(SCH_1):M_B_CPU1_SA_CB<3>
  M57  M_B_CPU1_SA_CB<2>  DDR1_SA_ECC2  @S9S_MB_2U_LIB.S9S_MB_2U(SCH_1):M_B_CPU1_SA_CB<2>
  J56  M_B_CPU1_SA_CB<1>  DDR1_SA_ECC1  @S9S_MB_2U_LIB.S9S_MB_2U(SCH_1):M_B_CPU1_SA_CB<1>
  K57  M_B_CPU1_SA_CB<0>  DDR1_SA_ECC0  @S9S_MB_2U_LIB.S9S_MB_2U(SCH_1):M_B_CPU1_SA_CB<0>
  Y44  M_B_CPU1_SA_CA<6>  DDR1_SA_CA6  @S9S_MB_2U_LIB.S9S_MB_2U(SCH_1):M_B_CPU1_SA_CA<6>
  M47  M_B_CPU1_SA_CA<5>  DDR1_SA_CA5  @S9S_MB_2U_LIB.S9S_MB_2U(SCH_1):M_B_CPU1_SA_CA<5>
  K47  M_B_CPU1_SA_CA<4>  DDR1_SA_CA4  @S9S_MB_2U_LIB.S9S_MB_2U(SCH_1):M_B_CPU1_SA_CA<4>
  N48  M_B_CPU1_SA_CA<3>  DDR1_SA_CA3  @S9S_MB_2U_LIB.S9S_MB_2U(SCH_1):M_B_CPU1_SA_CA<3>
  J48  M_B_CPU1_SA_CA<2>  DDR1_SA_CA2  @S9S_MB_2U_LIB.S9S_MB_2U(SCH_1):M_B_CPU1_SA_CA<2>
  P49  M_B_CPU1_SA_CA<1>  DDR1_SA_CA1  @S9S_MB_2U_LIB.S9S_MB_2U(SCH_1):M_B_CPU1_SA_CA<1>
  H49  M_B_CPU1_SA_CA<0>  DDR1_SA_CA0  @S9S_MB_2U_LIB.S9S_MB_2U(SCH_1):M_B_CPU1_SA_CA<0>
  AA45  M_B_CPU1_CLK_DP<1>  DDR1_CLK_DP1  @S9S_MB_2U_LIB.S9S_MB_2U(SCH_1):M_B_CPU1_CLK_DP<1>
  U45  M_B_CPU1_CLK_DP<0>  DDR1_CLK_DP0  @S9S_MB_2U_LIB.S9S_MB_2U(SCH_1):M_B_CPU1_CLK_DP<0>
  W45  M_B_CPU1_CLK_DN<1>  DDR1_CLK_DN1  @S9S_MB_2U_LIB.S9S_MB_2U(SCH_1):M_B_CPU1_CLK_DN<1>
  R45  M_B_CPU1_CLK_DN<0>  DDR1_CLK_DN0  @S9S_MB_2U_LIB.S9S_MB_2U(SCH_1):M_B_CPU1_CLK_DN<0>
  AV49  M_B_CPU1_ALERT_N  DDR1_ALERT_N  @S9S_MB_2U_LIB.S9S_MB_2U(SCH_1):M_B_CPU1_ALERT_N

SOCKET4677_AZIFS054P001C01  I2   U1     [SOCKET4677_AZIFS054P001C01-SOCA]
  AV42  M_A_CPU1_SB_RSP<1>  DDR0_B_RSP1  @S9S_MB_2U_LIB.S9S_MB_2U(SCH_1):M_A_CPU1_SB_RSP<1>
  AV44  M_A_CPU1_SB_RSP<0>  DDR0_B_RSP0  @S9S_MB_2U_LIB.S9S_MB_2U(SCH_1):M_A_CPU1_SB_RSP<0>
  G39  M_A_CPU1_SB_PAR  DDR0_SB_PAR  @S9S_MB_2U_LIB.S9S_MB_2U(SCH_1):M_A_CPU1_SB_PAR
  C33  M_A_CPU1_SB_DQS_DP<9>  DDR0_SB_DQS_DP9  @S9S_MB_2U_LIB.S9S_MB_2U(SCH_1):M_A_CPU1_SB_DQS_DP<9>
   E9  M_A_CPU1_SB_DQS_DP<8>  DDR0_SB_DQS_DP8  @S9S_MB_2U_LIB.S9S_MB_2U(SCH_1):M_A_CPU1_SB_DQS_DP<8>
  E21  M_A_CPU1_SB_DQS_DP<7>  DDR0_SB_DQS_DP7  @S9S_MB_2U_LIB.S9S_MB_2U(SCH_1):M_A_CPU1_SB_DQS_DP<7>
  E27  M_A_CPU1_SB_DQS_DP<6>  DDR0_SB_DQS_DP6  @S9S_MB_2U_LIB.S9S_MB_2U(SCH_1):M_A_CPU1_SB_DQS_DP<6>
  P30  M_A_CPU1_SB_DQS_DP<5>  DDR0_SB_DQS_DP5  @S9S_MB_2U_LIB.S9S_MB_2U(SCH_1):M_A_CPU1_SB_DQS_DP<5>
  E33  M_A_CPU1_SB_DQS_DP<4>  DDR0_SB_DQS_DP4  @S9S_MB_2U_LIB.S9S_MB_2U(SCH_1):M_A_CPU1_SB_DQS_DP<4>
   C9  M_A_CPU1_SB_DQS_DP<3>  DDR0_SB_DQS_DP3  @S9S_MB_2U_LIB.S9S_MB_2U(SCH_1):M_A_CPU1_SB_DQS_DP<3>
  C21  M_A_CPU1_SB_DQS_DP<2>  DDR0_SB_DQS_DP2  @S9S_MB_2U_LIB.S9S_MB_2U(SCH_1):M_A_CPU1_SB_DQS_DP<2>
  C27  M_A_CPU1_SB_DQS_DP<1>  DDR0_SB_DQS_DP1  @S9S_MB_2U_LIB.S9S_MB_2U(SCH_1):M_A_CPU1_SB_DQS_DP<1>
  K30  M_A_CPU1_SB_DQS_DP<0>  DDR0_SB_DQS_DP0  @S9S_MB_2U_LIB.S9S_MB_2U(SCH_1):M_A_CPU1_SB_DQS_DP<0>
  A33  M_A_CPU1_SB_DQS_DN<9>  DDR0_SB_DQS_DN9  @S9S_MB_2U_LIB.S9S_MB_2U(SCH_1):M_A_CPU1_SB_DQS_DN<9>
   G9  M_A_CPU1_SB_DQS_DN<8>  DDR0_SB_DQS_DN8  @S9S_MB_2U_LIB.S9S_MB_2U(SCH_1):M_A_CPU1_SB_DQS_DN<8>
  G21  M_A_CPU1_SB_DQS_DN<7>  DDR0_SB_DQS_DN7  @S9S_MB_2U_LIB.S9S_MB_2U(SCH_1):M_A_CPU1_SB_DQS_DN<7>
  G27  M_A_CPU1_SB_DQS_DN<6>  DDR0_SB_DQS_DN6  @S9S_MB_2U_LIB.S9S_MB_2U(SCH_1):M_A_CPU1_SB_DQS_DN<6>
  M30  M_A_CPU1_SB_DQS_DN<5>  DDR0_SB_DQS_DN5  @S9S_MB_2U_LIB.S9S_MB_2U(SCH_1):M_A_CPU1_SB_DQS_DN<5>
  G33  M_A_CPU1_SB_DQS_DN<4>  DDR0_SB_DQS_DN4  @S9S_MB_2U_LIB.S9S_MB_2U(SCH_1):M_A_CPU1_SB_DQS_DN<4>
   A9  M_A_CPU1_SB_DQS_DN<3>  DDR0_SB_DQS_DN3  @S9S_MB_2U_LIB.S9S_MB_2U(SCH_1):M_A_CPU1_SB_DQS_DN<3>
  A21  M_A_CPU1_SB_DQS_DN<2>  DDR0_SB_DQS_DN2  @S9S_MB_2U_LIB.S9S_MB_2U(SCH_1):M_A_CPU1_SB_DQS_DN<2>
  A27  M_A_CPU1_SB_DQS_DN<1>  DDR0_SB_DQS_DN1  @S9S_MB_2U_LIB.S9S_MB_2U(SCH_1):M_A_CPU1_SB_DQS_DN<1>
  H30  M_A_CPU1_SB_DQS_DN<0>  DDR0_SB_DQS_DN0  @S9S_MB_2U_LIB.S9S_MB_2U(SCH_1):M_A_CPU1_SB_DQS_DN<0>
  B28  M_A_CPU1_SB_DQ<9>  DDR0_SB_DQ9  @S9S_MB_2U_LIB.S9S_MB_2U(SCH_1):M_A_CPU1_SB_DQ<9>
  C29  M_A_CPU1_SB_DQ<8>  DDR0_SB_DQ8  @S9S_MB_2U_LIB.S9S_MB_2U(SCH_1):M_A_CPU1_SB_DQ<8>
  M28  M_A_CPU1_SB_DQ<7>  DDR0_SB_DQ7  @S9S_MB_2U_LIB.S9S_MB_2U(SCH_1):M_A_CPU1_SB_DQ<7>
  N29  M_A_CPU1_SB_DQ<6>  DDR0_SB_DQ6  @S9S_MB_2U_LIB.S9S_MB_2U(SCH_1):M_A_CPU1_SB_DQ<6>
  K28  M_A_CPU1_SB_DQ<5>  DDR0_SB_DQ5  @S9S_MB_2U_LIB.S9S_MB_2U(SCH_1):M_A_CPU1_SB_DQ<5>
  J29  M_A_CPU1_SB_DQ<4>  DDR0_SB_DQ4  @S9S_MB_2U_LIB.S9S_MB_2U(SCH_1):M_A_CPU1_SB_DQ<4>
  N31  M_A_CPU1_SB_DQ<3>  DDR0_SB_DQ3  @S9S_MB_2U_LIB.S9S_MB_2U(SCH_1):M_A_CPU1_SB_DQ<3>
   E7  M_A_CPU1_SB_DQ<31>  DDR0_SB_DQ31  @S9S_MB_2U_LIB.S9S_MB_2U(SCH_1):M_A_CPU1_SB_DQ<31>
   F8  M_A_CPU1_SB_DQ<30>  DDR0_SB_DQ30  @S9S_MB_2U_LIB.S9S_MB_2U(SCH_1):M_A_CPU1_SB_DQ<30>
  M32  M_A_CPU1_SB_DQ<2>  DDR0_SB_DQ2  @S9S_MB_2U_LIB.S9S_MB_2U(SCH_1):M_A_CPU1_SB_DQ<2>
   C7  M_A_CPU1_SB_DQ<29>  DDR0_SB_DQ29  @S9S_MB_2U_LIB.S9S_MB_2U(SCH_1):M_A_CPU1_SB_DQ<29>
   B8  M_A_CPU1_SB_DQ<28>  DDR0_SB_DQ28  @S9S_MB_2U_LIB.S9S_MB_2U(SCH_1):M_A_CPU1_SB_DQ<28>
  F10  M_A_CPU1_SB_DQ<27>  DDR0_SB_DQ27  @S9S_MB_2U_LIB.S9S_MB_2U(SCH_1):M_A_CPU1_SB_DQ<27>
  E11  M_A_CPU1_SB_DQ<26>  DDR0_SB_DQ26  @S9S_MB_2U_LIB.S9S_MB_2U(SCH_1):M_A_CPU1_SB_DQ<26>
  B10  M_A_CPU1_SB_DQ<25>  DDR0_SB_DQ25  @S9S_MB_2U_LIB.S9S_MB_2U(SCH_1):M_A_CPU1_SB_DQ<25>
  C11  M_A_CPU1_SB_DQ<24>  DDR0_SB_DQ24  @S9S_MB_2U_LIB.S9S_MB_2U(SCH_1):M_A_CPU1_SB_DQ<24>
  E19  M_A_CPU1_SB_DQ<23>  DDR0_SB_DQ23  @S9S_MB_2U_LIB.S9S_MB_2U(SCH_1):M_A_CPU1_SB_DQ<23>
  F20  M_A_CPU1_SB_DQ<22>  DDR0_SB_DQ22  @S9S_MB_2U_LIB.S9S_MB_2U(SCH_1):M_A_CPU1_SB_DQ<22>
  C19  M_A_CPU1_SB_DQ<21>  DDR0_SB_DQ21  @S9S_MB_2U_LIB.S9S_MB_2U(SCH_1):M_A_CPU1_SB_DQ<21>
  B20  M_A_CPU1_SB_DQ<20>  DDR0_SB_DQ20  @S9S_MB_2U_LIB.S9S_MB_2U(SCH_1):M_A_CPU1_SB_DQ<20>
  J31  M_A_CPU1_SB_DQ<1>  DDR0_SB_DQ1  @S9S_MB_2U_LIB.S9S_MB_2U(SCH_1):M_A_CPU1_SB_DQ<1>
  F22  M_A_CPU1_SB_DQ<19>  DDR0_SB_DQ19  @S9S_MB_2U_LIB.S9S_MB_2U(SCH_1):M_A_CPU1_SB_DQ<19>
  E23  M_A_CPU1_SB_DQ<18>  DDR0_SB_DQ18  @S9S_MB_2U_LIB.S9S_MB_2U(SCH_1):M_A_CPU1_SB_DQ<18>
  B22  M_A_CPU1_SB_DQ<17>  DDR0_SB_DQ17  @S9S_MB_2U_LIB.S9S_MB_2U(SCH_1):M_A_CPU1_SB_DQ<17>
  C23  M_A_CPU1_SB_DQ<16>  DDR0_SB_DQ16  @S9S_MB_2U_LIB.S9S_MB_2U(SCH_1):M_A_CPU1_SB_DQ<16>
  E25  M_A_CPU1_SB_DQ<15>  DDR0_SB_DQ15  @S9S_MB_2U_LIB.S9S_MB_2U(SCH_1):M_A_CPU1_SB_DQ<15>
  F26  M_A_CPU1_SB_DQ<14>  DDR0_SB_DQ14  @S9S_MB_2U_LIB.S9S_MB_2U(SCH_1):M_A_CPU1_SB_DQ<14>
  C25  M_A_CPU1_SB_DQ<13>  DDR0_SB_DQ13  @S9S_MB_2U_LIB.S9S_MB_2U(SCH_1):M_A_CPU1_SB_DQ<13>
  B26  M_A_CPU1_SB_DQ<12>  DDR0_SB_DQ12  @S9S_MB_2U_LIB.S9S_MB_2U(SCH_1):M_A_CPU1_SB_DQ<12>
  F28  M_A_CPU1_SB_DQ<11>  DDR0_SB_DQ11  @S9S_MB_2U_LIB.S9S_MB_2U(SCH_1):M_A_CPU1_SB_DQ<11>
  E29  M_A_CPU1_SB_DQ<10>  DDR0_SB_DQ10  @S9S_MB_2U_LIB.S9S_MB_2U(SCH_1):M_A_CPU1_SB_DQ<10>
  K32  M_A_CPU1_SB_DQ<0>  DDR0_SB_DQ0  @S9S_MB_2U_LIB.S9S_MB_2U(SCH_1):M_A_CPU1_SB_DQ<0>
  E37  M_A_CPU1_SB_CS_N<3>  DDR0_SB_CS3_N  @S9S_MB_2U_LIB.S9S_MB_2U(SCH_1):M_A_CPU1_SB_CS_N<3>
  F38  M_A_CPU1_SB_CS_N<2>  DDR0_SB_CS2_N  @S9S_MB_2U_LIB.S9S_MB_2U(SCH_1):M_A_CPU1_SB_CS_N<2>
  C37  M_A_CPU1_SB_CS_N<1>  DDR0_SB_CS1_N  @S9S_MB_2U_LIB.S9S_MB_2U(SCH_1):M_A_CPU1_SB_CS_N<1>
  B38  M_A_CPU1_SB_CS_N<0>  DDR0_SB_CS0_N  @S9S_MB_2U_LIB.S9S_MB_2U(SCH_1):M_A_CPU1_SB_CS_N<0>
  F34  M_A_CPU1_SB_CB<7>  DDR0_SB_ECC7  @S9S_MB_2U_LIB.S9S_MB_2U(SCH_1):M_A_CPU1_SB_CB<7>
  E35  M_A_CPU1_SB_CB<6>  DDR0_SB_ECC6  @S9S_MB_2U_LIB.S9S_MB_2U(SCH_1):M_A_CPU1_SB_CB<6>
  B34  M_A_CPU1_SB_CB<5>  DDR0_SB_ECC5  @S9S_MB_2U_LIB.S9S_MB_2U(SCH_1):M_A_CPU1_SB_CB<5>
  C35  M_A_CPU1_SB_CB<4>  DDR0_SB_ECC4  @S9S_MB_2U_LIB.S9S_MB_2U(SCH_1):M_A_CPU1_SB_CB<4>
  E31  M_A_CPU1_SB_CB<3>  DDR0_SB_ECC3  @S9S_MB_2U_LIB.S9S_MB_2U(SCH_1):M_A_CPU1_SB_CB<3>
  F32  M_A_CPU1_SB_CB<2>  DDR0_SB_ECC2  @S9S_MB_2U_LIB.S9S_MB_2U(SCH_1):M_A_CPU1_SB_CB<2>
  C31  M_A_CPU1_SB_CB<1>  DDR0_SB_ECC1  @S9S_MB_2U_LIB.S9S_MB_2U(SCH_1):M_A_CPU1_SB_CB<1>
  B32  M_A_CPU1_SB_CB<0>  DDR0_SB_ECC0  @S9S_MB_2U_LIB.S9S_MB_2U(SCH_1):M_A_CPU1_SB_CB<0>
  A39  M_A_CPU1_SB_CA<6>  DDR0_SB_CA6  @S9S_MB_2U_LIB.S9S_MB_2U(SCH_1):M_A_CPU1_SB_CA<6>
  F40  M_A_CPU1_SB_CA<5>  DDR0_SB_CA5  @S9S_MB_2U_LIB.S9S_MB_2U(SCH_1):M_A_CPU1_SB_CA<5>
  B40  M_A_CPU1_SB_CA<4>  DDR0_SB_CA4  @S9S_MB_2U_LIB.S9S_MB_2U(SCH_1):M_A_CPU1_SB_CA<4>
  E41  M_A_CPU1_SB_CA<3>  DDR0_SB_CA3  @S9S_MB_2U_LIB.S9S_MB_2U(SCH_1):M_A_CPU1_SB_CA<3>
  C41  M_A_CPU1_SB_CA<2>  DDR0_SB_CA2  @S9S_MB_2U_LIB.S9S_MB_2U(SCH_1):M_A_CPU1_SB_CA<2>
  F44  M_A_CPU1_SB_CA<1>  DDR0_SB_CA1  @S9S_MB_2U_LIB.S9S_MB_2U(SCH_1):M_A_CPU1_SB_CA<1>
  E43  M_A_CPU1_SB_CA<0>  DDR0_SB_CA0  @S9S_MB_2U_LIB.S9S_MB_2U(SCH_1):M_A_CPU1_SB_CA<0>
  AU43  M_A_CPU1_SA_RSP<1>  DDR0_A_RSP1  @S9S_MB_2U_LIB.S9S_MB_2U(SCH_1):M_A_CPU1_SA_RSP<1>
  AT42  M_A_CPU1_SA_RSP<0>  DDR0_A_RSP0  @S9S_MB_2U_LIB.S9S_MB_2U(SCH_1):M_A_CPU1_SA_RSP<0>
  E48  M_A_CPU1_SA_PAR  DDR0_SA_PAR  @S9S_MB_2U_LIB.S9S_MB_2U(SCH_1):M_A_CPU1_SA_PAR
  E58  M_A_CPU1_SA_DQS_DP<9>  DDR0_SA_DQS_DP9  @S9S_MB_2U_LIB.S9S_MB_2U(SCH_1):M_A_CPU1_SA_DQS_DP<9>
  E64  M_A_CPU1_SA_DQS_DP<8>  DDR0_SA_DQS_DP8  @S9S_MB_2U_LIB.S9S_MB_2U(SCH_1):M_A_CPU1_SA_DQS_DP<8>
  E70  M_A_CPU1_SA_DQS_DP<7>  DDR0_SA_DQS_DP7  @S9S_MB_2U_LIB.S9S_MB_2U(SCH_1):M_A_CPU1_SA_DQS_DP<7>
  M67  M_A_CPU1_SA_DQS_DP<6>  DDR0_SA_DQS_DP6  @S9S_MB_2U_LIB.S9S_MB_2U(SCH_1):M_A_CPU1_SA_DQS_DP<6>
  F77  M_A_CPU1_SA_DQS_DP<5>  DDR0_SA_DQS_DP5  @S9S_MB_2U_LIB.S9S_MB_2U(SCH_1):M_A_CPU1_SA_DQS_DP<5>
  C58  M_A_CPU1_SA_DQS_DP<4>  DDR0_SA_DQS_DP4  @S9S_MB_2U_LIB.S9S_MB_2U(SCH_1):M_A_CPU1_SA_DQS_DP<4>
  C64  M_A_CPU1_SA_DQS_DP<3>  DDR0_SA_DQS_DP3  @S9S_MB_2U_LIB.S9S_MB_2U(SCH_1):M_A_CPU1_SA_DQS_DP<3>
  C70  M_A_CPU1_SA_DQS_DP<2>  DDR0_SA_DQS_DP2  @S9S_MB_2U_LIB.S9S_MB_2U(SCH_1):M_A_CPU1_SA_DQS_DP<2>
  K67  M_A_CPU1_SA_DQS_DP<1>  DDR0_SA_DQS_DP1  @S9S_MB_2U_LIB.S9S_MB_2U(SCH_1):M_A_CPU1_SA_DQS_DP<1>
  D77  M_A_CPU1_SA_DQS_DP<0>  DDR0_SA_DQS_DP0  @S9S_MB_2U_LIB.S9S_MB_2U(SCH_1):M_A_CPU1_SA_DQS_DP<0>
  G58  M_A_CPU1_SA_DQS_DN<9>  DDR0_SA_DQS_DN9  @S9S_MB_2U_LIB.S9S_MB_2U(SCH_1):M_A_CPU1_SA_DQS_DN<9>
  G64  M_A_CPU1_SA_DQS_DN<8>  DDR0_SA_DQS_DN8  @S9S_MB_2U_LIB.S9S_MB_2U(SCH_1):M_A_CPU1_SA_DQS_DN<8>
  G70  M_A_CPU1_SA_DQS_DN<7>  DDR0_SA_DQS_DN7  @S9S_MB_2U_LIB.S9S_MB_2U(SCH_1):M_A_CPU1_SA_DQS_DN<7>
  P67  M_A_CPU1_SA_DQS_DN<6>  DDR0_SA_DQS_DN6  @S9S_MB_2U_LIB.S9S_MB_2U(SCH_1):M_A_CPU1_SA_DQS_DN<6>
  H77  M_A_CPU1_SA_DQS_DN<5>  DDR0_SA_DQS_DN5  @S9S_MB_2U_LIB.S9S_MB_2U(SCH_1):M_A_CPU1_SA_DQS_DN<5>
  A58  M_A_CPU1_SA_DQS_DN<4>  DDR0_SA_DQS_DN4  @S9S_MB_2U_LIB.S9S_MB_2U(SCH_1):M_A_CPU1_SA_DQS_DN<4>
  A64  M_A_CPU1_SA_DQS_DN<3>  DDR0_SA_DQS_DN3  @S9S_MB_2U_LIB.S9S_MB_2U(SCH_1):M_A_CPU1_SA_DQS_DN<3>
  B71  M_A_CPU1_SA_DQS_DN<2>  DDR0_SA_DQS_DN2  @S9S_MB_2U_LIB.S9S_MB_2U(SCH_1):M_A_CPU1_SA_DQS_DN<2>
  H67  M_A_CPU1_SA_DQS_DN<1>  DDR0_SA_DQS_DN1  @S9S_MB_2U_LIB.S9S_MB_2U(SCH_1):M_A_CPU1_SA_DQS_DN<1>
  B77  M_A_CPU1_SA_DQS_DN<0>  DDR0_SA_DQS_DN0  @S9S_MB_2U_LIB.S9S_MB_2U(SCH_1):M_A_CPU1_SA_DQS_DN<0>
  J68  M_A_CPU1_SA_DQ<9>  DDR0_SA_DQ9  @S9S_MB_2U_LIB.S9S_MB_2U(SCH_1):M_A_CPU1_SA_DQ<9>
  K69  M_A_CPU1_SA_DQ<8>  DDR0_SA_DQ8  @S9S_MB_2U_LIB.S9S_MB_2U(SCH_1):M_A_CPU1_SA_DQ<8>
  F75  M_A_CPU1_SA_DQ<7>  DDR0_SA_DQ7  @S9S_MB_2U_LIB.S9S_MB_2U(SCH_1):M_A_CPU1_SA_DQ<7>
  G76  M_A_CPU1_SA_DQ<6>  DDR0_SA_DQ6  @S9S_MB_2U_LIB.S9S_MB_2U(SCH_1):M_A_CPU1_SA_DQ<6>
  D75  M_A_CPU1_SA_DQ<5>  DDR0_SA_DQ5  @S9S_MB_2U_LIB.S9S_MB_2U(SCH_1):M_A_CPU1_SA_DQ<5>
  C76  M_A_CPU1_SA_DQ<4>  DDR0_SA_DQ4  @S9S_MB_2U_LIB.S9S_MB_2U(SCH_1):M_A_CPU1_SA_DQ<4>
  G78  M_A_CPU1_SA_DQ<3>  DDR0_SA_DQ3  @S9S_MB_2U_LIB.S9S_MB_2U(SCH_1):M_A_CPU1_SA_DQ<3>
  E62  M_A_CPU1_SA_DQ<31>  DDR0_SA_DQ31  @S9S_MB_2U_LIB.S9S_MB_2U(SCH_1):M_A_CPU1_SA_DQ<31>
  F63  M_A_CPU1_SA_DQ<30>  DDR0_SA_DQ30  @S9S_MB_2U_LIB.S9S_MB_2U(SCH_1):M_A_CPU1_SA_DQ<30>
  M77  M_A_CPU1_SA_DQ<2>  DDR0_SA_DQ2  @S9S_MB_2U_LIB.S9S_MB_2U(SCH_1):M_A_CPU1_SA_DQ<2>
  C62  M_A_CPU1_SA_DQ<29>  DDR0_SA_DQ29  @S9S_MB_2U_LIB.S9S_MB_2U(SCH_1):M_A_CPU1_SA_DQ<29>
  B63  M_A_CPU1_SA_DQ<28>  DDR0_SA_DQ28  @S9S_MB_2U_LIB.S9S_MB_2U(SCH_1):M_A_CPU1_SA_DQ<28>
  F65  M_A_CPU1_SA_DQ<27>  DDR0_SA_DQ27  @S9S_MB_2U_LIB.S9S_MB_2U(SCH_1):M_A_CPU1_SA_DQ<27>
  E66  M_A_CPU1_SA_DQ<26>  DDR0_SA_DQ26  @S9S_MB_2U_LIB.S9S_MB_2U(SCH_1):M_A_CPU1_SA_DQ<26>
  B65  M_A_CPU1_SA_DQ<25>  DDR0_SA_DQ25  @S9S_MB_2U_LIB.S9S_MB_2U(SCH_1):M_A_CPU1_SA_DQ<25>
  C66  M_A_CPU1_SA_DQ<24>  DDR0_SA_DQ24  @S9S_MB_2U_LIB.S9S_MB_2U(SCH_1):M_A_CPU1_SA_DQ<24>
  E68  M_A_CPU1_SA_DQ<23>  DDR0_SA_DQ23  @S9S_MB_2U_LIB.S9S_MB_2U(SCH_1):M_A_CPU1_SA_DQ<23>
  F69  M_A_CPU1_SA_DQ<22>  DDR0_SA_DQ22  @S9S_MB_2U_LIB.S9S_MB_2U(SCH_1):M_A_CPU1_SA_DQ<22>
  C68  M_A_CPU1_SA_DQ<21>  DDR0_SA_DQ21  @S9S_MB_2U_LIB.S9S_MB_2U(SCH_1):M_A_CPU1_SA_DQ<21>
  B69  M_A_CPU1_SA_DQ<20>  DDR0_SA_DQ20  @S9S_MB_2U_LIB.S9S_MB_2U(SCH_1):M_A_CPU1_SA_DQ<20>
  B79  M_A_CPU1_SA_DQ<1>  DDR0_SA_DQ1  @S9S_MB_2U_LIB.S9S_MB_2U(SCH_1):M_A_CPU1_SA_DQ<1>
  F71  M_A_CPU1_SA_DQ<19>  DDR0_SA_DQ19  @S9S_MB_2U_LIB.S9S_MB_2U(SCH_1):M_A_CPU1_SA_DQ<19>
  D73  M_A_CPU1_SA_DQ<18>  DDR0_SA_DQ18  @S9S_MB_2U_LIB.S9S_MB_2U(SCH_1):M_A_CPU1_SA_DQ<18>
  E72  M_A_CPU1_SA_DQ<17>  DDR0_SA_DQ17  @S9S_MB_2U_LIB.S9S_MB_2U(SCH_1):M_A_CPU1_SA_DQ<17>
  B73  M_A_CPU1_SA_DQ<16>  DDR0_SA_DQ16  @S9S_MB_2U_LIB.S9S_MB_2U(SCH_1):M_A_CPU1_SA_DQ<16>
  M65  M_A_CPU1_SA_DQ<15>  DDR0_SA_DQ15  @S9S_MB_2U_LIB.S9S_MB_2U(SCH_1):M_A_CPU1_SA_DQ<15>
  N66  M_A_CPU1_SA_DQ<14>  DDR0_SA_DQ14  @S9S_MB_2U_LIB.S9S_MB_2U(SCH_1):M_A_CPU1_SA_DQ<14>
  K65  M_A_CPU1_SA_DQ<13>  DDR0_SA_DQ13  @S9S_MB_2U_LIB.S9S_MB_2U(SCH_1):M_A_CPU1_SA_DQ<13>
  J66  M_A_CPU1_SA_DQ<12>  DDR0_SA_DQ12  @S9S_MB_2U_LIB.S9S_MB_2U(SCH_1):M_A_CPU1_SA_DQ<12>
  N68  M_A_CPU1_SA_DQ<11>  DDR0_SA_DQ11  @S9S_MB_2U_LIB.S9S_MB_2U(SCH_1):M_A_CPU1_SA_DQ<11>
  M69  M_A_CPU1_SA_DQ<10>  DDR0_SA_DQ10  @S9S_MB_2U_LIB.S9S_MB_2U(SCH_1):M_A_CPU1_SA_DQ<10>
  B81  M_A_CPU1_SA_DQ<0>  DDR0_SA_DQ0  @S9S_MB_2U_LIB.S9S_MB_2U(SCH_1):M_A_CPU1_SA_DQ<0>
  F53  M_A_CPU1_SA_CS_N<3>  DDR0_SA_CS3_N  @S9S_MB_2U_LIB.S9S_MB_2U(SCH_1):M_A_CPU1_SA_CS_N<3>
  E54  M_A_CPU1_SA_CS_N<2>  DDR0_SA_CS2_N  @S9S_MB_2U_LIB.S9S_MB_2U(SCH_1):M_A_CPU1_SA_CS_N<2>
  B53  M_A_CPU1_SA_CS_N<1>  DDR0_SA_CS1_N  @S9S_MB_2U_LIB.S9S_MB_2U(SCH_1):M_A_CPU1_SA_CS_N<1>
  C54  M_A_CPU1_SA_CS_N<0>  DDR0_SA_CS0_N  @S9S_MB_2U_LIB.S9S_MB_2U(SCH_1):M_A_CPU1_SA_CS_N<0>
  E56  M_A_CPU1_SA_CB<7>  DDR0_SA_ECC7  @S9S_MB_2U_LIB.S9S_MB_2U(SCH_1):M_A_CPU1_SA_CB<7>
  F57  M_A_CPU1_SA_CB<6>  DDR0_SA_ECC6  @S9S_MB_2U_LIB.S9S_MB_2U(SCH_1):M_A_CPU1_SA_CB<6>
  C56  M_A_CPU1_SA_CB<5>  DDR0_SA_ECC5  @S9S_MB_2U_LIB.S9S_MB_2U(SCH_1):M_A_CPU1_SA_CB<5>
  B57  M_A_CPU1_SA_CB<4>  DDR0_SA_ECC4  @S9S_MB_2U_LIB.S9S_MB_2U(SCH_1):M_A_CPU1_SA_CB<4>
  F59  M_A_CPU1_SA_CB<3>  DDR0_SA_ECC3  @S9S_MB_2U_LIB.S9S_MB_2U(SCH_1):M_A_CPU1_SA_CB<3>
  E60  M_A_CPU1_SA_CB<2>  DDR0_SA_ECC2  @S9S_MB_2U_LIB.S9S_MB_2U(SCH_1):M_A_CPU1_SA_CB<2>
  B59  M_A_CPU1_SA_CB<1>  DDR0_SA_ECC1  @S9S_MB_2U_LIB.S9S_MB_2U(SCH_1):M_A_CPU1_SA_CB<1>
  C60  M_A_CPU1_SA_CB<0>  DDR0_SA_ECC0  @S9S_MB_2U_LIB.S9S_MB_2U(SCH_1):M_A_CPU1_SA_CB<0>
  C48  M_A_CPU1_SA_CA<6>  DDR0_SA_CA6  @S9S_MB_2U_LIB.S9S_MB_2U(SCH_1):M_A_CPU1_SA_CA<6>
  E50  M_A_CPU1_SA_CA<5>  DDR0_SA_CA5  @S9S_MB_2U_LIB.S9S_MB_2U(SCH_1):M_A_CPU1_SA_CA<5>
  C50  M_A_CPU1_SA_CA<4>  DDR0_SA_CA4  @S9S_MB_2U_LIB.S9S_MB_2U(SCH_1):M_A_CPU1_SA_CA<4>
  F51  M_A_CPU1_SA_CA<3>  DDR0_SA_CA3  @S9S_MB_2U_LIB.S9S_MB_2U(SCH_1):M_A_CPU1_SA_CA<3>
  B51  M_A_CPU1_SA_CA<2>  DDR0_SA_CA2  @S9S_MB_2U_LIB.S9S_MB_2U(SCH_1):M_A_CPU1_SA_CA<2>
  G52  M_A_CPU1_SA_CA<1>  DDR0_SA_CA1  @S9S_MB_2U_LIB.S9S_MB_2U(SCH_1):M_A_CPU1_SA_CA<1>
  A52  M_A_CPU1_SA_CA<0>  DDR0_SA_CA0  @S9S_MB_2U_LIB.S9S_MB_2U(SCH_1):M_A_CPU1_SA_CA<0>
  E45  M_A_CPU1_CLK_DP<1>  DDR0_CLK_DP1  @S9S_MB_2U_LIB.S9S_MB_2U(SCH_1):M_A_CPU1_CLK_DP<1>
  C43  M_A_CPU1_CLK_DP<0>  DDR0_CLK_DP0  @S9S_MB_2U_LIB.S9S_MB_2U(SCH_1):M_A_CPU1_CLK_DP<0>
  G45  M_A_CPU1_CLK_DN<1>  DDR0_CLK_DN1  @S9S_MB_2U_LIB.S9S_MB_2U(SCH_1):M_A_CPU1_CLK_DN<1>
  B44  M_A_CPU1_CLK_DN<0>  DDR0_CLK_DN0  @S9S_MB_2U_LIB.S9S_MB_2U(SCH_1):M_A_CPU1_CLK_DN<0>
  AT49  M_A_CPU1_ALERT_N  DDR0_ALERT_N  @S9S_MB_2U_LIB.S9S_MB_2U(SCH_1):M_A_CPU1_ALERT_N

SOCKET4677_AZIFS054P001C01  I23  U1     [SOCKET4677_AZIFS054P001C01-SOCA]
  BT28  NC             PTI_DIE009  NC
  BU27  NC             PTI_DIE008  NC
  BV28  NC             PTI_DIE007  NC
  CA27  NC             PTI_DIE006  NC
  BV30  NC             PTI_DIE005  NC
  CA29  NC             PTI_DIE004  NC
  BY30  NC             PTI_DIE003  NC
  BN66  NC             PTI_DIE0115  NC
  BM67  NC             PTI_DIE0114  NC
  CC27  NC             PTI_DIE002  NC
  BL66  NC             PTI_DIE0113  NC
  BJ66  NC             PTI_DIE0112  NC
  BG66  NC             PTI_DIE0111  NC
  BN68  NC             PTI_DIE0110  NC
  BM69  NC             PTI_DIE019  NC
  BK69  NC             PTI_DIE018  NC
  BD67  NC             PTI_DIE017  NC
  BG68  NC             PTI_DIE016  NC
  BC68  NC             PTI_DIE015  NC
  BH69  NC             PTI_DIE014  NC
  CD28  NC             PTI_DIE001  NC
  BF69  NC             PTI_DIE013  NC
  BD69  NC             PTI_DIE012  NC
  BE70  NC             PTI_DIE011  NC
  BC70  NC             PTI_DIE010  NC
  BP30  NC             PTI_DIE0015  NC
  BN29  NC             PTI_DIE0014  NC
  BP28  NC             PTI_DIE0013  NC
  BN27  NC             PTI_DIE0012  NC
  BT30  NC             PTI_DIE0011  NC
  BU29  NC             PTI_DIE0010  NC
  CC29  NC             PTI_DIE000  NC
  BK67  NC             PTI_DIE01_STB_1  NC
  BF67  NC             PTI_DIE01_STB_0  NC
  BY28  NC             PTI_DIE00_STB_1  NC
  CB30  NC             PTI_DIE00_STB_0  NC
  CK71  PU_CPU1_UPI3_AC_COUPLING  UPI3_AC_COUPLING  @S9S_MB_2U_LIB.S9S_MB_2U(SCH_1):PU_CPU1_UPI3_AC_COUPLING
  BB65  PU_CPU1_UPI2_AC_COUPLING  UPI2_AC_COUPLING  @S9S_MB_2U_LIB.S9S_MB_2U(SCH_1):PU_CPU1_UPI2_AC_COUPLING
  CW19  PU_CPU1_UPI1_AC_COUPLING  UPI1_AC_COUPLING  @S9S_MB_2U_LIB.S9S_MB_2U(SCH_1):PU_CPU1_UPI1_AC_COUPLING
  BA23  PU_CPU1_UPI0_AC_COUPLING  UPI0_AC_COUPLING  @S9S_MB_2U_LIB.S9S_MB_2U(SCH_1):PU_CPU1_UPI0_AC_COUPLING
  CR68  NC             UPI3_APROBE_1  NC
  CP69  NC             UPI3_APROBE_0  NC
  AT67  NC             UPI2_APROBE_1  NC
  AU68  NC             UPI2_APROBE_0  NC
  CA23  NC             UPI1_APROBE_1  NC
  BV22  NC             UPI1_APROBE_0  NC
  AR17  NC             UPI0_APROBE_1  NC
  AN17  NC             UPI0_APROBE_0  NC
  AU66  NC             PE4_APROBE_1  NC
  AV67  NC             PE4_APROBE_0  NC
  CM69  NC             PE3_APROBE_1  NC
  CL68  NC             PE3_APROBE_0  NC
  BW23  NC             PE2_APROBE_1  NC
  CC23  NC             PE2_APROBE_0  NC
  CC21  NC             PE1_APROBE_1  NC
  CE21  NC             PE1_APROBE_0  NC
  BL21  NC             PE0_APROBE_1  NC
  BN21  NC             PE0_APROBE_0  NC
  BW21  NC             DMI_APROBE_1  NC
  CA21  NC             DMI_APROBE_0  NC

SOCKET4677_AZIFS054P001C01  I2   U1     [SOCKET4677_AZIFS054P001C01-SOCA]
  CH61  NC             OVERCLK_BCLK0_DP  NC
  CK61  NC             OVERCLK_BCLK1_DN  NC
  CL60  NC             OVERCLK_BCLK1_DP  NC
  CW43  NC             SPARE_3  NC
  AU52  NC             SPARE_1  NC
  DA70  NC             SPARE_0  NC
  BD77  NC             SPARE_10  NC
  CL70  NC             SPARE_5  NC
  CD69  NC             OVERCLK_ENABLE  NC
  CG60  NC             OVERCLK_BCLK0_DN  NC
  J13  NC             SMBALERT_N  NC

SOCKET4677_AZIFS054P001C01  I1   U1     [SOCKET4677_AZIFS054P001C01-SOCA]
  BE21  NC             DIE_HVM  NC
  CY57  NC             SOC_SPARE1_DIE11  NC
  CR25  NC             SOC_SPARE1_DIE10  NC
  CW58  NC             SOC_SPARE0_DIE11  NC
  CT26  NC             SOC_SPARE0_DIE10  NC
  BP65  NC             SOC_SPARE1_DIE01  NC
  BA25  NC             SOC_SPARE1_DIE00  NC
  BM65  NC             SOC_SPARE0_DIE01  NC
  AY24  NC             SOC_SPARE0_DIE00  NC
  CK67  NC             MDFI_VIEW_DIE11_NS_1  NC
  CJ68  NC             MDFI_VIEW_DIE11_NS_0  NC
  CH69  NC             MDFI_VIEW_DIE11_EW_1  NC
  CJ70  NC             MDFI_VIEW_DIE11_EW_0  NC
  CD22  NC             MDFI_VIEW_DIE10_NS_1  NC
  CF22  NC             MDFI_VIEW_DIE10_NS_0  NC
  CD30  NC             MDFI_VIEW_DIE10_EW_1  NC
  CD26  NC             MDFI_VIEW_DIE10_EW_0  NC
  BD71  NC             MDFI_VIEW_DIE01_NS_1  NC
  BF71  NC             MDFI_VIEW_DIE01_NS_0  NC
  CC66  NC             MDFI_VIEW_DIE01_EW_1  NC
  AV65  NC             MDFI_VIEW_DIE01_EW_0  NC
  BJ21  NC             MDFI_VIEW_DIE00_NS_1  NC
  BK22  NC             MDFI_VIEW_DIE00_NS_0  NC
  BR21  NC             MDFI_VIEW_DIE00_EW_1  NC
  BP22  NC             MDFI_VIEW_DIE00_EW_0  NC
  BL60  NC             HBM3_VIEWPIN_1  NC
  BG78  NC             HBM3_VIEWPIN_0  NC
  AD77  NC             HBM2_VIEWPIN_1  NC
  AC78  NC             HBM2_VIEWPIN_0  NC
  CW41  NC             HBM1_VIEWPIN_1  NC
  W17  NC             HBM1_VIEWPIN_0  NC
  EG17  NC             HBM0_VIEWPIN_1  NC
  U17  NC             HBM0_VIEWPIN_0  NC

SOCKET4677_AZIFS054P001C01  I16  U1     [SOCKET4677_AZIFS054P001C01-SOCA]
  BD87  VSENSE_PVCCIN_CPU1_DP  VCCIN_SENSE  @S9S_MB_2U_LIB.S9S_MB_2U(SCH_1):VSENSE_PVCCIN_CPU1_DP
  BC90  VSENSE_PVCCIN_CPU1_DN  VSS_VCCIN_SENSE  @S9S_MB_2U_LIB.S9S_MB_2U(SCH_1):VSENSE_PVCCIN_CPU1_DN
  CA11  VSENSE_PVCCINFAON_CPU1_DP  VCCINFAON_SENSE  @S9S_MB_2U_LIB.S9S_MB_2U(SCH_1):VSENSE_PVCCINFAON_CPU1_DP
  CE11  VSENSE_PVCCINFAON_CPU1_DN  VSS_VCCINFAON_SENSE  @S9S_MB_2U_LIB.S9S_MB_2U(SCH_1):VSENSE_PVCCINFAON_CPU1_DN
  AY85  VSENSE_PVCCFA_EHV_FIVRA_CPU1_DP  VCCFA_EHV_FIVRA_SENSE  @S9S_MB_2U_LIB.S9S_MB_2U(SCH_1):VSENSE_PVCCFA_EHV_FIVRA_CPU1_DP
  AT85  VSENSE_PVCCFA_EHV_FIVRA_CPU1_DN  VSS_VCCFA_EHV_FIVRA_SENSE  @S9S_MB_2U_LIB.S9S_MB_2U(SCH_1):VSENSE_PVCCFA_EHV_FIVRA_CPU1_DN
  AU11  VSENSE_PVCCFA_EHV_CPU1_DP  VCCFA_EHV_SENSE  @S9S_MB_2U_LIB.S9S_MB_2U(SCH_1):VSENSE_PVCCFA_EHV_CPU1_DP
  BA11  VSENSE_PVCCFA_EHV_CPU1_DN  VSS_VCCFA_EHV_SENSE  @S9S_MB_2U_LIB.S9S_MB_2U(SCH_1):VSENSE_PVCCFA_EHV_CPU1_DN
  BU11  VSENSE_PVCCD_HV_CPU1_DP  VCCD_HV_SENSE  @S9S_MB_2U_LIB.S9S_MB_2U(SCH_1):VSENSE_PVCCD_HV_CPU1_DP
  BN11  VSENSE_PVCCD_HV_CPU1_DN  VSS_VCCD_HV_SENSE  @S9S_MB_2U_LIB.S9S_MB_2U(SCH_1):VSENSE_PVCCD_HV_CPU1_DN
  BF24  NC             IFST_TRIG  NC
  BE23  NC             IFST_KOT  NC
  BC23  NC             IFST_DONE  NC
  H12  NC             A0_DEBUG  NC
  AV38  NC             MAS_THERMADC  NC
  AV40  NC             MAS_THERMADA  NC
  CP61  NC             LGSPARE_5  NC
  CC64  NC             LGSPARE_4  NC
  CE62  NC             LGSPARE_3  NC
  CU62  NC             LGSPARE_2  NC
  CN60  NC             LGSPARE_1  NC
  CR60  NC             LGSPARE_0  NC
  CY49  NC             DDR67_VIEWDIG_1  NC
  DA45  NC             DDR67_VIEWDIG_0  NC
  CY38  NC             DDR45_VIEWDIG_1  NC
  CY24  NC             DDR45_VIEWDIG_0  NC
  AU33  NC             DDR23_VIEWDIG_1  NC
  AV32  NC             DDR23_VIEWDIG_0  NC
  AU56  NC             DDR01_VIEWDIG_1  NC
  AU58  NC             DDR01_VIEWDIG_0  NC
  BD24  H_PMAX_TRIGGER_IO_CPU1  PMAX_TRIGGER_IO  @S9S_MB_2U_LIB.S9S_MB_2U(SCH_1):H_PMAX_TRIGGER_IO_CPU1
  BH22  H_CPU1_RMCA_LVC1_R_N  RMCA_N  @S9S_MB_2U_LIB.S9S_MB_2U(SCH_1):H_CPU1_RMCA_LVC1_R_N
  BN25  DBP_CPU1_MBP1_GTL_R_N  MBP1_N  @S9S_MB_2U_LIB.S9S_MB_2U(SCH_1):DBP_CPU1_MBP1_GTL_R_N
  BL23  DBP_CPU1_MBP0_GTL_R_N  MBP0_N  @S9S_MB_2U_LIB.S9S_MB_2U(SCH_1):DBP_CPU1_MBP0_GTL_R_N
  BK24  DBP_CPU1_HOOK9_MBP3_GTL_QS_R_N  MBP3_N  @S9S_MB_2U_LIB.S9S_MB_2U(SCH_1):DBP_CPU1_HOOK9_MBP3_GTL_QS_R_N
  BJ23  DBP_CPU1_HOOK8_MBP2_GTL_QS_R_N  MBP2_N  @S9S_MB_2U_LIB.S9S_MB_2U(SCH_1):DBP_CPU1_HOOK8_MBP2_GTL_QS_R_N

SOCKET4677_AZIFS054P001C01  I5   U1     [SOCKET4677_AZIFS054P001C01-SOCA]
  CD65  NC             GSXRESET_N  NC
  CF65  NC             GSXDOUT  NC
  CJ66  NC             GSXDLOAD  NC
  CH63  NC             GSXDIN  NC
  CF63  NC             GSXSCLK  NC
  CV22  NC             CPLD_TMS  NC
  CP22  NC             CPLD_TDO  NC
  CT22  NC             CPLD_TDI  NC
  BC25  NC             I3C_MNG_SDA  NC
  BE25  NC             I3C_MNG_SCL  NC
  CJ23  NC             I2C_RTC_SDA  NC
  CL23  NC             I2C_RTC_SCL  NC
  CJ25  NC             I2C_RTC_ALERT_N  NC
  AW19  NC             PLT_WAKE_N  NC
  CK22  NC             PLT_SYS_RESET_N  NC
  CW21  NC             PLT_SLP_S5_N  NC
  CN21  NC             PLT_SLP_S4_N  NC
  CR21  NC             PLT_SLP_S3_N  NC
  CK24  NC             PLT_PWRBUTTON_N  NC
  CL66  NC             SSC_SYNC  NC
  CJ21  NC             PLT_GLB_RST_WARN_N  NC
  CD63  SMB_S3M_CPU1_SDA  SMB_DATA  @S9S_MB_2U_LIB.S9S_MB_2U(SCH_1):SMB_S3M_CPU1_SDA
  CE64  SMB_S3M_CPU1_SCL  SMB_CLK  @S9S_MB_2U_LIB.S9S_MB_2U(SCH_1):SMB_S3M_CPU1_SCL
  CH71  PWRGD_S0_PWROK_CPU1_LVC1  S0_PWROK  @S9S_MB_2U_LIB.S9S_MB_2U(SCH_1):PWRGD_S0_PWROK_CPU1_LVC1
  CV20  PWRGD_PLT_AUX_CPU1_LVT3  PLT_AUX_PWRGOOD  @S9S_MB_2U_LIB.S9S_MB_2U(SCH_1):PWRGD_PLT_AUX_CPU1_LVT3
  CH65  PU_S3M_CPU1_CPLD_STATUS  CPLD_NSTATUS  @S9S_MB_2U_LIB.S9S_MB_2U(SCH_1):PU_S3M_CPU1_CPLD_STATUS
  CJ64  PU_S3M_CPU1_CPLD_CONFD  CPLD_CONF_DONE  @S9S_MB_2U_LIB.S9S_MB_2U(SCH_1):PU_S3M_CPU1_CPLD_CONFD
  CF61  PUD_PCH_BOOT_MODE_CPU1  PCH_BOOT_MODE  @S9S_MB_2U_LIB.S9S_MB_2U(SCH_1):PUD_PCH_BOOT_MODE_CPU1
  CY22  PD_JTAG_CPU1_PLD_TCK  CPLD_TCK  @S9S_MB_2U_LIB.S9S_MB_2U(SCH_1):PD_JTAG_CPU1_PLD_TCK
  CV69  NC             UART_RXD  NC
  CY69  NC             UART_TXD  NC
  CY71  NC             UART_RTS  NC
  CV71  NC             UART_CTS  NC
  BA68  NC             SPI_OE_N  NC
  BD61  NC             SPI_IO_3  NC
  BD65  NC             SPI_IO_2  NC
  AW64  NC             SPI_MISO_IO1  NC
  BA62  NC             SPI_MOSI_IO0  NC
  AV63  NC             SPI_CS1_N  NC
  BB61  NC             SPI_CS0_N  NC
  BC64  NC             SPI_CLK  NC
  BB67  NC             SPI_TPM_OE_N  NC
  AY61  NC             SPI_TPM_MISO_IO1  NC
  BA66  NC             SPI_TPM_MOSI_IO0  NC
  AY67  NC             SPI_TPM_CS0_N  NC
  AU62  NC             SPI_TPM_CLK  NC
  CT24  NC             ADR_TRIGGER  NC
  CP24  NC             ADR_COMPLETE  NC
  CN23  NC             ADR_ACK  NC
  BG64  NC             ESPI_RESET_N  NC
  BH63  NC             ESPI_OE_N  NC
  BM63  NC             ESPI_IO_3  NC
  AU64  NC             ESPI_IO_2  NC
  BJ64  NC             ESPI_IO_1  NC
  BK63  NC             ESPI_IO_0  NC
  BH65  NC             ESPI_CS1_N  NC
  BF65  NC             ESPI_CS0_N  NC
  BG62  NC             ESPI_CLK  NC
  BD63  NC             ESPI_ALERT1_N  NC
  BE62  NC             ESPI_ALERT0_N  NC
  AW70  FM_S3M_CPU1_LVC1_GPIO_4  GPIO_4  @S9S_MB_2U_LIB.S9S_MB_2U(SCH_1):FM_S3M_CPU1_LVC1_GPIO_4
  AY69  FM_S3M_CPU1_LVC1_GPIO_3  GPIO_3  @S9S_MB_2U_LIB.S9S_MB_2U(SCH_1):FM_S3M_CPU1_LVC1_GPIO_3
  AV69  FM_S3M_CPU1_LVC1_GPIO_2  GPIO_2  @S9S_MB_2U_LIB.S9S_MB_2U(SCH_1):FM_S3M_CPU1_LVC1_GPIO_2
  AV71  FM_S3M_CPU1_LVC1_GPIO_1  GPIO_1  @S9S_MB_2U_LIB.S9S_MB_2U(SCH_1):FM_S3M_CPU1_LVC1_GPIO_1
  BA70  FM_S3M_CPU1_LVC1_GPIO_0  GPIO_0  @S9S_MB_2U_LIB.S9S_MB_2U(SCH_1):FM_S3M_CPU1_LVC1_GPIO_0
  CY20  FM_S3M_CPU1_CPLD_CRC_ERROR  CPLD_CRC_ERROR  @S9S_MB_2U_LIB.S9S_MB_2U(SCH_1):FM_S3M_CPU1_CPLD_CRC_ERROR
  CK65  FM_S3M_CPU1_CPLD_CONFIG_N  CPLD_NCONFIG  @S9S_MB_2U_LIB.S9S_MB_2U(SCH_1):FM_S3M_CPU1_CPLD_CONFIG_N

SOCKET4677_AZIFS054P001C01  I29  U1     [SOCKET4677_AZIFS054P001C01-SOCA]
  CF24  NC             PMSYNC6  NC
  CC25  NC             PMDOWN6  NC
  CH24  NC             PMSYNC5  NC
  CE23  NC             PMDOWN5  NC
  CR19  NC             PMSYNC4  NC
  CV18  NC             PMDOWN4  NC
  CE25  NC             PMSYNC3  NC
  CD24  NC             PMDOWN3  NC
  CH26  NC             PMSYNC2  NC
  CM26  NC             PMDOWN2  NC
  CL25  NC             PMSYNC1  NC
  CP26  NC             PMDOWN1  NC
  DA39  NC             PMSYNC_PCH  NC
  CY40  NC             PMDOWN_PCH  NC
  AV59  NC             MAS_EXT_BGREF  NC
  BL25  SVID_DIO1_CPU1  SVIDDATA1  @S9S_MB_2U_LIB.S9S_MB_2U(SCH_1):SVID_DIO1_CPU1
  BD26  SVID_DIO0_CPU1  SVIDDATA0  @S9S_MB_2U_LIB.S9S_MB_2U(SCH_1):SVID_DIO0_CPU1
  BF26  SVID_CLK1_CPU1  SVIDCLK1  @S9S_MB_2U_LIB.S9S_MB_2U(SCH_1):SVID_CLK1_CPU1
  BH26  SVID_CLK0_CPU1  SVIDCLK0  @S9S_MB_2U_LIB.S9S_MB_2U(SCH_1):SVID_CLK0_CPU1
  BJ25  SVID_ALERT1_CPU1_N  SVIDALERT1_N  @S9S_MB_2U_LIB.S9S_MB_2U(SCH_1):SVID_ALERT1_CPU1_N
  BK26  SVID_ALERT0_CPU1_N  SVIDALERT0_N  @S9S_MB_2U_LIB.S9S_MB_2U(SCH_1):SVID_ALERT0_CPU1_N
  BY26  SMB_PEHPCPU1_GTL_SDA  CXPSMBUSSDA  @S9S_MB_2U_LIB.S9S_MB_2U(SCH_1):SMB_PEHPCPU1_GTL_SDA
  CA25  SMB_PEHPCPU1_GTL_SCL  CXPSMBUSSCL  @S9S_MB_2U_LIB.S9S_MB_2U(SCH_1):SMB_PEHPCPU1_GTL_SCL
  CM71  SMB_CPU1_PIROM_3V3AUX_SDA_R  I2C_PIROM_SDA  @S9S_MB_2U_LIB.S9S_MB_2U(SCH_1):SMB_CPU1_PIROM_3V3AUX_SDA_R
  CU70  SMB_CPU1_PIROM_3V3AUX_SCL_R  I2C_PIROM_SCL  @S9S_MB_2U_LIB.S9S_MB_2U(SCH_1):SMB_CPU1_PIROM_3V3AUX_SCL_R
  BH61  RST_CPU1_LVC1_N  RESET_N  @S9S_MB_2U_LIB.S9S_MB_2U(SCH_1):RST_CPU1_LVC1_N
  CW45  PWRGD_DRAMPWRGD_CPU1_GH_LVC1_R  DDR67_DRAM_PWR_OK  @S9S_MB_2U_LIB.S9S_MB_2U(SCH_1):PWRGD_DRAMPWRGD_CPU1_GH_LVC1_R
  CY44  PWRGD_DRAMPWRGD_CPU1_EF_LVC1_R  DDR45_DRAM_PWR_OK  @S9S_MB_2U_LIB.S9S_MB_2U(SCH_1):PWRGD_DRAMPWRGD_CPU1_EF_LVC1_R
  F47  PWRGD_DRAMPWRGD_CPU1_CD_LVC1_R  DDR23_DRAM_PWR_OK  @S9S_MB_2U_LIB.S9S_MB_2U(SCH_1):PWRGD_DRAMPWRGD_CPU1_CD_LVC1_R
  A43  PWRGD_DRAMPWRGD_CPU1_AB_LVC1_R  DDR01_DRAM_PWR_OK  @S9S_MB_2U_LIB.S9S_MB_2U(SCH_1):PWRGD_DRAMPWRGD_CPU1_AB_LVC1_R
  AV20  PWRGD_CPU1_LVC1  CPUPWRGOOD  @S9S_MB_2U_LIB.S9S_MB_2U(SCH_1):PWRGD_CPU1_LVC1
  AY20  PU_TAP_ODT_CPU1_EN  TAP_ODT_EN  @S9S_MB_2U_LIB.S9S_MB_2U(SCH_1):PU_TAP_ODT_CPU1_EN
  CR72  PU_PIROM_CPU1_SM_WP  I2C_PIROM_SM_WP  @S9S_MB_2U_LIB.S9S_MB_2U(SCH_1):PU_PIROM_CPU1_SM_WP
  CR70  PU_PIROM_CPU1_ADDR0  I2C_PIROM_AD_0  @S9S_MB_2U_LIB.S9S_MB_2U(SCH_1):PU_PIROM_CPU1_ADDR0
  CP71  PD_PIROM_CPU1_ADDR2  I2C_PIROM_AD_2  @S9S_MB_2U_LIB.S9S_MB_2U(SCH_1):PD_PIROM_CPU1_ADDR2
  CT71  PD_PIROM_CPU1_ADDR1  I2C_PIROM_AD_1  @S9S_MB_2U_LIB.S9S_MB_2U(SCH_1):PD_PIROM_CPU1_ADDR1
  CH22  PD_CPU1_ENH_MCECC_DIS  ENH_MCECC_DIS  @S9S_MB_2U_LIB.S9S_MB_2U(SCH_1):PD_CPU1_ENH_MCECC_DIS
  BL62  H_CPU1_THERMTRIP_LVC1_R_N  THERMTRIP_N  @S9S_MB_2U_LIB.S9S_MB_2U(SCH_1):H_CPU1_THERMTRIP_LVC1_R_N
  AU19  H_CPU1_PROCHOT_LVC1_N  PROCHOT_N  @S9S_MB_2U_LIB.S9S_MB_2U(SCH_1):H_CPU1_PROCHOT_LVC1_N
  CP20  H_CPU1_PM_FAST_WAKE_N  PMFAST_WAKE_N  @S9S_MB_2U_LIB.S9S_MB_2U(SCH_1):H_CPU1_PM_FAST_WAKE_N
  AV18  H_CPU1_NMI_LVC1_N    NMI  @S9S_MB_2U_LIB.S9S_MB_2U(SCH_1):H_CPU1_NMI_LVC1_N
  AV24  H_CPU1_MEMTRIP_LVC1_R_N  MEMTRIP_N  @S9S_MB_2U_LIB.S9S_MB_2U(SCH_1):H_CPU1_MEMTRIP_LVC1_R_N
  CF26  H_CPU1_MEMHOT_OUT_LVC1_R_N  MEMHOT_OUT_N  @S9S_MB_2U_LIB.S9S_MB_2U(SCH_1):H_CPU1_MEMHOT_OUT_LVC1_R_N
  AU21  H_CPU1_MEMHOT_IN_LVC1_N  MEMHOT_IN_N  @S9S_MB_2U_LIB.S9S_MB_2U(SCH_1):H_CPU1_MEMHOT_IN_LVC1_N
  BD22  H_CPU1_ERR2_LVC1_R_N  ERROR2_N  @S9S_MB_2U_LIB.S9S_MB_2U(SCH_1):H_CPU1_ERR2_LVC1_R_N
  AY22  H_CPU1_ERR1_LVC1_R_N  ERROR1_N  @S9S_MB_2U_LIB.S9S_MB_2U(SCH_1):H_CPU1_ERR1_LVC1_R_N
  BF22  H_CPU1_ERR0_LVC1_R_N  ERROR0_N  @S9S_MB_2U_LIB.S9S_MB_2U(SCH_1):H_CPU1_ERR0_LVC1_R_N
  BP24  H_CPU1_CATERR_LVC1_R_N  CATERR_N  @S9S_MB_2U_LIB.S9S_MB_2U(SCH_1):H_CPU1_CATERR_LVC1_R_N
  CW39  H_CPU0_PMSYNC_CPU1  PMDOWN0  @S9S_MB_2U_LIB.S9S_MB_2U(SCH_1):H_CPU0_PMSYNC_CPU1
  CN25  H_CPU0_PMDOWN_CPU1  PMSYNC0  @S9S_MB_2U_LIB.S9S_MB_2U(SCH_1):H_CPU0_PMDOWN_CPU1
  BV26  FM_PEHPCPU1_ALERT_N  CXPSMBUS_ALERT_N  @S9S_MB_2U_LIB.S9S_MB_2U(SCH_1):FM_PEHPCPU1_ALERT_N
  AV57  FM_CPU_FBRK_DEBUG_R_N  FBRK_N  @S9S_MB_2U_LIB.S9S_MB_2U(SCH_1):FM_CPU_FBRK_DEBUG_R_N
  CG66  FM_CPU1_SKTOCC_LVT3_N  SKTOCC_N  @S9S_MB_2U_LIB.S9S_MB_2U(SCH_1):FM_CPU1_SKTOCC_LVT3_N
  CJ62  NC             VIEWPIN_DIE11_0  NC
  AU25  NC             VIEWPIN_DIE00_2  NC
  BP69  NC             VIEWPIN_DIE01_0  NC
  BP67  NC             VIEWPIN_DIE01_1  NC
  BJ70  NC             VIEWPIN_DIE01_3  NC
  AT24  NC             VIEWPIN_DIE00_1  NC
  AY65  NC             VIEWPIN_DIE01_2  NC
  AY26  NC             VIEWPIN_DIE00_0  NC
  AV26  NC             VIEWPIN_DIE00_3  NC
  CW68  NC             FIVR_CLKREF  NC
  CW25  NC             VIEWPIN_DIE10_1  NC
  CW23  NC             VIEWPIN_DIE10_3  NC
  CV24  NC             VIEWPIN_DIE10_2  NC
  CR23  NC             VIEWPIN_DIE10_0  NC
  CN62  NC             VIEWPIN_DIE11_1  NC
  CM63  NC             VIEWPIN_DIE11_2  NC
  CL64  NC             VIEWPIN_DIE11_3  NC
  CL21  NC             PLT_PLTRST_SYNC_N  NC

SOCKET4677_AZIFS054P001C01  I51  U1     [SOCKET4677_AZIFS054P001C01-SOCA]
  CY55  RST_CPU1_DRAM_GH_N  DDR67_RESET_N  @S9S_MB_2U_LIB.S9S_MB_2U(SCH_1):RST_CPU1_DRAM_GH_N
  CY42  RST_CPU1_DRAM_EF_N  DDR45_RESET_N  @S9S_MB_2U_LIB.S9S_MB_2U(SCH_1):RST_CPU1_DRAM_EF_N
  AV51  RST_CPU1_DRAM_CD_N  DDR23_RESET_N  @S9S_MB_2U_LIB.S9S_MB_2U(SCH_1):RST_CPU1_DRAM_CD_N
  AU50  RST_CPU1_DRAM_AB_N  DDR01_RESET_N  @S9S_MB_2U_LIB.S9S_MB_2U(SCH_1):RST_CPU1_DRAM_AB_N
  BT26  PU_CPU1_TXT_AGENT  TXT_AGENT  @S9S_MB_2U_LIB.S9S_MB_2U(SCH_1):PU_CPU1_TXT_AGENT
  CT61  PU_CPU1_SOCKET_ID2  SOCKET_ID2  @S9S_MB_2U_LIB.S9S_MB_2U(SCH_1):PU_CPU1_SOCKET_ID2
  CY61  PU_CPU1_SOCKET_ID1  SOCKET_ID1  @S9S_MB_2U_LIB.S9S_MB_2U(SCH_1):PU_CPU1_SOCKET_ID1
  CW60  PU_CPU1_SOCKET_ID0  SOCKET_ID0  @S9S_MB_2U_LIB.S9S_MB_2U(SCH_1):PU_CPU1_SOCKET_ID0
  AU23  PU_CPU1_SAFE_MODE_BOOT  SAFE_MODE_BOOT  @S9S_MB_2U_LIB.S9S_MB_2U(SCH_1):PU_CPU1_SAFE_MODE_BOOT
  CY59  PU_CPU1_LEGACY_SKT  LEGACY_SKT  @S9S_MB_2U_LIB.S9S_MB_2U(SCH_1):PU_CPU1_LEGACY_SKT
  AU17  PU_CPU1_FRMAGENT  FRMAGENT  @S9S_MB_2U_LIB.S9S_MB_2U(SCH_1):PU_CPU1_FRMAGENT
  CJ72  PUD_XTAL_CPU1_MODE1  XTAL_MODE_1  @S9S_MB_2U_LIB.S9S_MB_2U(SCH_1):PUD_XTAL_CPU1_MODE1
  CL72  PUD_XTAL_CPU1_MODE0  XTAL_MODE_0  @S9S_MB_2U_LIB.S9S_MB_2U(SCH_1):PUD_XTAL_CPU1_MODE0
  BH24  PECI_CPU1_GTL_R   PECI  @S9S_MB_2U_LIB.S9S_MB_2U(SCH_1):PECI_CPU1_GTL_R
  BY24  PD_EXT_CLK_SEL_CPU1  EXT_CLK_SEL  @S9S_MB_2U_LIB.S9S_MB_2U(SCH_1):PD_EXT_CLK_SEL_CPU1
  CT20  PD_CPU1_TXT_PLTEN  TXT_PLTEN  @S9S_MB_2U_LIB.S9S_MB_2U(SCH_1):PD_CPU1_TXT_PLTEN
  DA52  PD_CPU1_PROCDIS_COD_GTL_N  PROCDIS_N  @S9S_MB_2U_LIB.S9S_MB_2U(SCH_1):PD_CPU1_PROCDIS_COD_GTL_N
  AW17  PD_CPU1_DMIMODE_OVERRIDE  DMIMODE_OVERRIDE  @S9S_MB_2U_LIB.S9S_MB_2U(SCH_1):PD_CPU1_DMIMODE_OVERRIDE
  AT18  PD_CPU1_BIST_ENABLE  BIST_ENABLE  @S9S_MB_2U_LIB.S9S_MB_2U(SCH_1):PD_CPU1_BIST_ENABLE
  BR25  JTAG_DBP_CPU1_QS_GTL_R_TMS    TMS  @S9S_MB_2U_LIB.S9S_MB_2U(SCH_1):JTAG_DBP_CPU1_QS_GTL_R_TMS
  BV24  JTAG_DBP_CPU1_GTL_R_TDI    TDI  @S9S_MB_2U_LIB.S9S_MB_2U(SCH_1):JTAG_DBP_CPU1_GTL_R_TDI
  BT24  JTAG_DBP_CPU1_GTL_R_TCK    TCK  @S9S_MB_2U_LIB.S9S_MB_2U(SCH_1):JTAG_DBP_CPU1_GTL_R_TCK
  BW25  JTAG_CPU1_MUX_GTL_TDO    TDO  @S9S_MB_2U_LIB.S9S_MB_2U(SCH_1):JTAG_CPU1_MUX_GTL_TDO
  CT18  I3C_SPD_DDREFGH_CPU1_SDA  SPD_I2CBUS_SDA1  @S9S_MB_2U_LIB.S9S_MB_2U(SCH_1):I3C_SPD_DDREFGH_CPU1_SDA
  CU17  I3C_SPD_DDREFGH_CPU1_SCL  SPD_I2CBUS_SCL1  @S9S_MB_2U_LIB.S9S_MB_2U(SCH_1):I3C_SPD_DDREFGH_CPU1_SCL
  BY22  I3C_SPD_DDRABCD_CPU1_SDA  SPD_I2CBUS_SDA0  @S9S_MB_2U_LIB.S9S_MB_2U(SCH_1):I3C_SPD_DDRABCD_CPU1_SDA
  BT22  I3C_SPD_DDRABCD_CPU1_SCL  SPD_I2CBUS_SCL0  @S9S_MB_2U_LIB.S9S_MB_2U(SCH_1):I3C_SPD_DDRABCD_CPU1_SCL
  AV22  H_CPU1_PREQ_QS_GTL_R_N  PREQ_N  @S9S_MB_2U_LIB.S9S_MB_2U(SCH_1):H_CPU1_PREQ_QS_GTL_R_N
  BP26  H_CPU1_PRDY_QS_GTL_R_N  PRDY_N  @S9S_MB_2U_LIB.S9S_MB_2U(SCH_1):H_CPU1_PRDY_QS_GTL_R_N
  BR23  H_CPU1_MON_FAIL_LVC1_R_N  MON_FAIL_N  @S9S_MB_2U_LIB.S9S_MB_2U(SCH_1):H_CPU1_MON_FAIL_LVC1_R_N
  BN23  H_CPU1_BMCINIT_LVC1  BMCINIT  @S9S_MB_2U_LIB.S9S_MB_2U(SCH_1):H_CPU1_BMCINIT_LVC1
  BH71  FM_CPU1_PROC_ID1  PROC_ID1  @S9S_MB_2U_LIB.S9S_MB_2U(SCH_1):FM_CPU1_PROC_ID1
  BG72  FM_CPU1_PROC_ID0  PROC_ID0  @S9S_MB_2U_LIB.S9S_MB_2U(SCH_1):FM_CPU1_PROC_ID0
  BN64  FM_CPU1_PKGID2  PKG_ID2  @S9S_MB_2U_LIB.S9S_MB_2U(SCH_1):FM_CPU1_PKGID2
  AY63  FM_CPU1_PKGID1  PKG_ID1  @S9S_MB_2U_LIB.S9S_MB_2U(SCH_1):FM_CPU1_PKGID1
  BL64  FM_CPU1_PKGID0  PKG_ID0  @S9S_MB_2U_LIB.S9S_MB_2U(SCH_1):FM_CPU1_PKGID0
  CE70  NC             PFT_OUT_DN  NC
  CD71  NC             PFT_OUT_DP  NC
   G5  NC             XTAL_IN  NC
   D4  NC             XTAL_OUT  NC
  CY32  CLK_25M_NSSC_CPU1_DP  XTAL_CLK_DP  @S9S_MB_2U_LIB.S9S_MB_2U(SCH_1):CLK_25M_NSSC_CPU1_DP
  CW31  CLK_25M_NSSC_CPU1_DN  XTAL_CLK_DN  @S9S_MB_2U_LIB.S9S_MB_2U(SCH_1):CLK_25M_NSSC_CPU1_DN
  DA27  CLK_100M_DB2000_CPU1_BCLK3_DP  BCLK3_DP  @S9S_MB_2U_LIB.S9S_MB_2U(SCH_1):CLK_100M_DB2000_CPU1_BCLK3_DP
  CW27  CLK_100M_DB2000_CPU1_BCLK3_DN  BCLK3_DN  @S9S_MB_2U_LIB.S9S_MB_2U(SCH_1):CLK_100M_DB2000_CPU1_BCLK3_DN
  AV28  CLK_100M_DB2000_CPU1_BCLK2_DP  BCLK2_DP  @S9S_MB_2U_LIB.S9S_MB_2U(SCH_1):CLK_100M_DB2000_CPU1_BCLK2_DP
  AU29  CLK_100M_DB2000_CPU1_BCLK2_DN  BCLK2_DN  @S9S_MB_2U_LIB.S9S_MB_2U(SCH_1):CLK_100M_DB2000_CPU1_BCLK2_DN
  CW29  CLK_100M_DB2000_CPU1_BCLK1_DP  BCLK1_DP  @S9S_MB_2U_LIB.S9S_MB_2U(SCH_1):CLK_100M_DB2000_CPU1_BCLK1_DP
  CY28  CLK_100M_DB2000_CPU1_BCLK1_DN  BCLK1_DN  @S9S_MB_2U_LIB.S9S_MB_2U(SCH_1):CLK_100M_DB2000_CPU1_BCLK1_DN
  AV30  CLK_100M_DB2000_CPU1_BCLK0_DP  BCLK0_DP  @S9S_MB_2U_LIB.S9S_MB_2U(SCH_1):CLK_100M_DB2000_CPU1_BCLK0_DP
  AT30  CLK_100M_DB2000_CPU1_BCLK0_DN  BCLK0_DN  @S9S_MB_2U_LIB.S9S_MB_2U(SCH_1):CLK_100M_DB2000_CPU1_BCLK0_DN

SOCKET4677_AZIFS054P001C01  I12  U2     [SOCKET4677_AZIFS054P001C01-SOCA]
  E39  GND            VSS1271  @S9S_MB_2U_LIB.S9S_MB_2U(SCH_1):GND
   E5  GND            VSS1125  @S9S_MB_2U_LIB.S9S_MB_2U(SCH_1):GND
  D83  GND            VSS907  @S9S_MB_2U_LIB.S9S_MB_2U(SCH_1):GND
  D81  GND            VSS906  @S9S_MB_2U_LIB.S9S_MB_2U(SCH_1):GND
  D71  GND            VSS902  @S9S_MB_2U_LIB.S9S_MB_2U(SCH_1):GND
  D69  GND            VSS901  @S9S_MB_2U_LIB.S9S_MB_2U(SCH_1):GND
  D61  GND            VSS900  @S9S_MB_2U_LIB.S9S_MB_2U(SCH_1):GND
   D6  GND            VSS899  @S9S_MB_2U_LIB.S9S_MB_2U(SCH_1):GND
  D59  GND            VSS898  @S9S_MB_2U_LIB.S9S_MB_2U(SCH_1):GND
  D57  GND            VSS897  @S9S_MB_2U_LIB.S9S_MB_2U(SCH_1):GND
  D55  GND            VSS896  @S9S_MB_2U_LIB.S9S_MB_2U(SCH_1):GND
  D53  GND            VSS895  @S9S_MB_2U_LIB.S9S_MB_2U(SCH_1):GND
  D51  GND            VSS892  @S9S_MB_2U_LIB.S9S_MB_2U(SCH_1):GND
  D49  GND            VSS891  @S9S_MB_2U_LIB.S9S_MB_2U(SCH_1):GND
  D47  GND            VSS889  @S9S_MB_2U_LIB.S9S_MB_2U(SCH_1):GND
  D44  GND            VSS888  @S9S_MB_2U_LIB.S9S_MB_2U(SCH_1):GND
  D42  GND            VSS886  @S9S_MB_2U_LIB.S9S_MB_2U(SCH_1):GND
  D40  GND            VSS885  @S9S_MB_2U_LIB.S9S_MB_2U(SCH_1):GND
  D38  GND            VSS884  @S9S_MB_2U_LIB.S9S_MB_2U(SCH_1):GND
  D36  GND            VSS881  @S9S_MB_2U_LIB.S9S_MB_2U(SCH_1):GND
  D34  GND            VSS879  @S9S_MB_2U_LIB.S9S_MB_2U(SCH_1):GND
  D32  GND            VSS878  @S9S_MB_2U_LIB.S9S_MB_2U(SCH_1):GND
  D30  GND            VSS877  @S9S_MB_2U_LIB.S9S_MB_2U(SCH_1):GND
  D28  GND            VSS876  @S9S_MB_2U_LIB.S9S_MB_2U(SCH_1):GND
  D26  GND            VSS875  @S9S_MB_2U_LIB.S9S_MB_2U(SCH_1):GND
  D24  GND            VSS874  @S9S_MB_2U_LIB.S9S_MB_2U(SCH_1):GND
  D22  GND            VSS873  @S9S_MB_2U_LIB.S9S_MB_2U(SCH_1):GND
  D20  GND            VSS871  @S9S_MB_2U_LIB.S9S_MB_2U(SCH_1):GND
  D18  GND            VSS869  @S9S_MB_2U_LIB.S9S_MB_2U(SCH_1):GND
  D16  GND            VSS868  @S9S_MB_2U_LIB.S9S_MB_2U(SCH_1):GND
  D14  GND            VSS866  @S9S_MB_2U_LIB.S9S_MB_2U(SCH_1):GND
  D12  GND            VSS865  @S9S_MB_2U_LIB.S9S_MB_2U(SCH_1):GND
  D10  GND            VSS864  @S9S_MB_2U_LIB.S9S_MB_2U(SCH_1):GND
   D8  GND            VSS663  @S9S_MB_2U_LIB.S9S_MB_2U(SCH_1):GND
  D79  GND            VSS662  @S9S_MB_2U_LIB.S9S_MB_2U(SCH_1):GND
  D67  GND            VSS659  @S9S_MB_2U_LIB.S9S_MB_2U(SCH_1):GND
  D65  GND            VSS658  @S9S_MB_2U_LIB.S9S_MB_2U(SCH_1):GND
  D63  GND            VSS657  @S9S_MB_2U_LIB.S9S_MB_2U(SCH_1):GND
  C86  GND            VSS619  @S9S_MB_2U_LIB.S9S_MB_2U(SCH_1):GND
  C82  GND            VSS618  @S9S_MB_2U_LIB.S9S_MB_2U(SCH_1):GND
  C80  GND            VSS617  @S9S_MB_2U_LIB.S9S_MB_2U(SCH_1):GND
  C78  GND            VSS616  @S9S_MB_2U_LIB.S9S_MB_2U(SCH_1):GND
  C74  GND            VSS615  @S9S_MB_2U_LIB.S9S_MB_2U(SCH_1):GND
  C72  GND            VSS614  @S9S_MB_2U_LIB.S9S_MB_2U(SCH_1):GND
  C52  GND            VSS613  @S9S_MB_2U_LIB.S9S_MB_2U(SCH_1):GND
   C5  GND            VSS612  @S9S_MB_2U_LIB.S9S_MB_2U(SCH_1):GND
  C45  GND            VSS610  @S9S_MB_2U_LIB.S9S_MB_2U(SCH_1):GND
  C39  GND            VSS609  @S9S_MB_2U_LIB.S9S_MB_2U(SCH_1):GND
  B87  GND            VSS392  @S9S_MB_2U_LIB.S9S_MB_2U(SCH_1):GND
  B83  GND            VSS391  @S9S_MB_2U_LIB.S9S_MB_2U(SCH_1):GND
  B75  GND            VSS390  @S9S_MB_2U_LIB.S9S_MB_2U(SCH_1):GND
  B67  GND            VSS389  @S9S_MB_2U_LIB.S9S_MB_2U(SCH_1):GND
  B61  GND            VSS388  @S9S_MB_2U_LIB.S9S_MB_2U(SCH_1):GND
   B6  GND            VSS387  @S9S_MB_2U_LIB.S9S_MB_2U(SCH_1):GND
  B55  GND            VSS386  @S9S_MB_2U_LIB.S9S_MB_2U(SCH_1):GND
  B49  GND            VSS385  @S9S_MB_2U_LIB.S9S_MB_2U(SCH_1):GND
  B42  GND            VSS384  @S9S_MB_2U_LIB.S9S_MB_2U(SCH_1):GND
  B36  GND            VSS382  @S9S_MB_2U_LIB.S9S_MB_2U(SCH_1):GND
  B30  GND            VSS381  @S9S_MB_2U_LIB.S9S_MB_2U(SCH_1):GND
  B24  GND            VSS380  @S9S_MB_2U_LIB.S9S_MB_2U(SCH_1):GND
  B18  GND            VSS379  @S9S_MB_2U_LIB.S9S_MB_2U(SCH_1):GND
  B12  GND            VSS378  @S9S_MB_2U_LIB.S9S_MB_2U(SCH_1):GND
  A62  GND            VSS16  @S9S_MB_2U_LIB.S9S_MB_2U(SCH_1):GND
  A60  GND            VSS15  @S9S_MB_2U_LIB.S9S_MB_2U(SCH_1):GND
  A56  GND            VSS14  @S9S_MB_2U_LIB.S9S_MB_2U(SCH_1):GND
  A54  GND            VSS13  @S9S_MB_2U_LIB.S9S_MB_2U(SCH_1):GND
  A50  GND            VSS12  @S9S_MB_2U_LIB.S9S_MB_2U(SCH_1):GND
  A41  GND            VSS11  @S9S_MB_2U_LIB.S9S_MB_2U(SCH_1):GND
  A37  GND            VSS10  @S9S_MB_2U_LIB.S9S_MB_2U(SCH_1):GND
  A35  GND             VSS9  @S9S_MB_2U_LIB.S9S_MB_2U(SCH_1):GND
  A31  GND             VSS8  @S9S_MB_2U_LIB.S9S_MB_2U(SCH_1):GND
  A29  GND             VSS7  @S9S_MB_2U_LIB.S9S_MB_2U(SCH_1):GND
  A25  GND             VSS6  @S9S_MB_2U_LIB.S9S_MB_2U(SCH_1):GND
  A23  GND             VSS5  @S9S_MB_2U_LIB.S9S_MB_2U(SCH_1):GND
  A19  GND             VSS4  @S9S_MB_2U_LIB.S9S_MB_2U(SCH_1):GND
  A17  GND             VSS3  @S9S_MB_2U_LIB.S9S_MB_2U(SCH_1):GND
  A13  GND             VSS2  @S9S_MB_2U_LIB.S9S_MB_2U(SCH_1):GND
  A11  GND             VSS1  @S9S_MB_2U_LIB.S9S_MB_2U(SCH_1):GND

SOCKET4677_AZIFS054P001C01  I11  U2     [SOCKET4677_AZIFS054P001C01-SOCA]
  N70  GND            VSS1695  @S9S_MB_2U_LIB.S9S_MB_2U(SCH_1):GND
  N58  GND            VSS1694  @S9S_MB_2U_LIB.S9S_MB_2U(SCH_1):GND
  N52  GND            VSS1693  @S9S_MB_2U_LIB.S9S_MB_2U(SCH_1):GND
  N45  GND            VSS1692  @S9S_MB_2U_LIB.S9S_MB_2U(SCH_1):GND
  N33  GND            VSS1691  @S9S_MB_2U_LIB.S9S_MB_2U(SCH_1):GND
  N27  GND            VSS1689  @S9S_MB_2U_LIB.S9S_MB_2U(SCH_1):GND
  N15  GND            VSS1688  @S9S_MB_2U_LIB.S9S_MB_2U(SCH_1):GND
  M83  GND            VSS1687  @S9S_MB_2U_LIB.S9S_MB_2U(SCH_1):GND
  M81  GND            VSS1686  @S9S_MB_2U_LIB.S9S_MB_2U(SCH_1):GND
  L78  GND            VSS1685  @S9S_MB_2U_LIB.S9S_MB_2U(SCH_1):GND
  L76  GND            VSS1684  @S9S_MB_2U_LIB.S9S_MB_2U(SCH_1):GND
  L74  GND            VSS1683  @S9S_MB_2U_LIB.S9S_MB_2U(SCH_1):GND
  L72  GND            VSS1682  @S9S_MB_2U_LIB.S9S_MB_2U(SCH_1):GND
  L68  GND            VSS1681  @S9S_MB_2U_LIB.S9S_MB_2U(SCH_1):GND
  L66  GND            VSS1680  @S9S_MB_2U_LIB.S9S_MB_2U(SCH_1):GND
  L64  GND            VSS1679  @S9S_MB_2U_LIB.S9S_MB_2U(SCH_1):GND
  L62  GND            VSS1678  @S9S_MB_2U_LIB.S9S_MB_2U(SCH_1):GND
  L60  GND            VSS1677  @S9S_MB_2U_LIB.S9S_MB_2U(SCH_1):GND
  L56  GND            VSS1676  @S9S_MB_2U_LIB.S9S_MB_2U(SCH_1):GND
  N64  GND            VSS1675  @S9S_MB_2U_LIB.S9S_MB_2U(SCH_1):GND
  L54  GND            VSS1674  @S9S_MB_2U_LIB.S9S_MB_2U(SCH_1):GND
  L52  GND            VSS1673  @S9S_MB_2U_LIB.S9S_MB_2U(SCH_1):GND
  L50  GND            VSS1672  @S9S_MB_2U_LIB.S9S_MB_2U(SCH_1):GND
   L5  GND            VSS1671  @S9S_MB_2U_LIB.S9S_MB_2U(SCH_1):GND
  L48  GND            VSS1670  @S9S_MB_2U_LIB.S9S_MB_2U(SCH_1):GND
  N39  GND            VSS1669  @S9S_MB_2U_LIB.S9S_MB_2U(SCH_1):GND
  L45  GND            VSS1668  @S9S_MB_2U_LIB.S9S_MB_2U(SCH_1):GND
  L43  GND            VSS1667  @S9S_MB_2U_LIB.S9S_MB_2U(SCH_1):GND
  L41  GND            VSS1666  @S9S_MB_2U_LIB.S9S_MB_2U(SCH_1):GND
  L39  GND            VSS1665  @S9S_MB_2U_LIB.S9S_MB_2U(SCH_1):GND
  N21  GND            VSS1664  @S9S_MB_2U_LIB.S9S_MB_2U(SCH_1):GND
  L37  GND            VSS1663  @S9S_MB_2U_LIB.S9S_MB_2U(SCH_1):GND
  L35  GND            VSS1662  @S9S_MB_2U_LIB.S9S_MB_2U(SCH_1):GND
  L33  GND            VSS1661  @S9S_MB_2U_LIB.S9S_MB_2U(SCH_1):GND
  L31  GND            VSS1660  @S9S_MB_2U_LIB.S9S_MB_2U(SCH_1):GND
  L29  GND            VSS1659  @S9S_MB_2U_LIB.S9S_MB_2U(SCH_1):GND
  L27  GND            VSS1658  @S9S_MB_2U_LIB.S9S_MB_2U(SCH_1):GND
   M8  GND            VSS1657  @S9S_MB_2U_LIB.S9S_MB_2U(SCH_1):GND
  L25  GND            VSS1656  @S9S_MB_2U_LIB.S9S_MB_2U(SCH_1):GND
  L23  GND            VSS1655  @S9S_MB_2U_LIB.S9S_MB_2U(SCH_1):GND
  M49  GND            VSS1654  @S9S_MB_2U_LIB.S9S_MB_2U(SCH_1):GND
  M42  GND            VSS1653  @S9S_MB_2U_LIB.S9S_MB_2U(SCH_1):GND
   M4  GND            VSS1652  @S9S_MB_2U_LIB.S9S_MB_2U(SCH_1):GND
  L21  GND            VSS1651  @S9S_MB_2U_LIB.S9S_MB_2U(SCH_1):GND
  L17  GND            VSS1650  @S9S_MB_2U_LIB.S9S_MB_2U(SCH_1):GND
  M12  GND            VSS1649  @S9S_MB_2U_LIB.S9S_MB_2U(SCH_1):GND
  L90  GND            VSS1648  @S9S_MB_2U_LIB.S9S_MB_2U(SCH_1):GND
   L9  GND            VSS1647  @S9S_MB_2U_LIB.S9S_MB_2U(SCH_1):GND
  L88  GND            VSS1646  @S9S_MB_2U_LIB.S9S_MB_2U(SCH_1):GND
  L15  GND            VSS1645  @S9S_MB_2U_LIB.S9S_MB_2U(SCH_1):GND
  L13  GND            VSS1644  @S9S_MB_2U_LIB.S9S_MB_2U(SCH_1):GND
  K85  GND            VSS1643  @S9S_MB_2U_LIB.S9S_MB_2U(SCH_1):GND
  K83  GND            VSS1642  @S9S_MB_2U_LIB.S9S_MB_2U(SCH_1):GND
   K8  GND            VSS1641  @S9S_MB_2U_LIB.S9S_MB_2U(SCH_1):GND
  L70  GND            VSS1640  @S9S_MB_2U_LIB.S9S_MB_2U(SCH_1):GND
  K77  GND            VSS1639  @S9S_MB_2U_LIB.S9S_MB_2U(SCH_1):GND
  J86  GND            VSS1638  @S9S_MB_2U_LIB.S9S_MB_2U(SCH_1):GND
  J84  GND            VSS1637  @S9S_MB_2U_LIB.S9S_MB_2U(SCH_1):GND
  J78  GND            VSS1636  @S9S_MB_2U_LIB.S9S_MB_2U(SCH_1):GND
  J76  GND            VSS1635  @S9S_MB_2U_LIB.S9S_MB_2U(SCH_1):GND
  L58  GND            VSS1634  @S9S_MB_2U_LIB.S9S_MB_2U(SCH_1):GND
  J58  GND            VSS1633  @S9S_MB_2U_LIB.S9S_MB_2U(SCH_1):GND
  J52  GND            VSS1632  @S9S_MB_2U_LIB.S9S_MB_2U(SCH_1):GND
  J45  GND            VSS1631  @S9S_MB_2U_LIB.S9S_MB_2U(SCH_1):GND
  J33  GND            VSS1630  @S9S_MB_2U_LIB.S9S_MB_2U(SCH_1):GND
  J27  GND            VSS1629  @S9S_MB_2U_LIB.S9S_MB_2U(SCH_1):GND
  J15  GND            VSS1628  @S9S_MB_2U_LIB.S9S_MB_2U(SCH_1):GND
  H81  GND            VSS1627  @S9S_MB_2U_LIB.S9S_MB_2U(SCH_1):GND
   H8  GND            VSS1626  @S9S_MB_2U_LIB.S9S_MB_2U(SCH_1):GND
  H79  GND            VSS1625  @S9S_MB_2U_LIB.S9S_MB_2U(SCH_1):GND
  H71  GND            VSS1624  @S9S_MB_2U_LIB.S9S_MB_2U(SCH_1):GND
  H69  GND            VSS1623  @S9S_MB_2U_LIB.S9S_MB_2U(SCH_1):GND
  H63  GND            VSS1622  @S9S_MB_2U_LIB.S9S_MB_2U(SCH_1):GND
   H6  GND            VSS1621  @S9S_MB_2U_LIB.S9S_MB_2U(SCH_1):GND
  H59  GND            VSS1620  @S9S_MB_2U_LIB.S9S_MB_2U(SCH_1):GND
  H53  GND            VSS1619  @S9S_MB_2U_LIB.S9S_MB_2U(SCH_1):GND
  H47  GND            VSS1618  @S9S_MB_2U_LIB.S9S_MB_2U(SCH_1):GND
  H44  GND            VSS1617  @S9S_MB_2U_LIB.S9S_MB_2U(SCH_1):GND
  H40  GND            VSS1616  @S9S_MB_2U_LIB.S9S_MB_2U(SCH_1):GND
   H4  GND            VSS1615  @S9S_MB_2U_LIB.S9S_MB_2U(SCH_1):GND
  L19  GND            VSS1614  @S9S_MB_2U_LIB.S9S_MB_2U(SCH_1):GND
  H38  GND            VSS1613  @S9S_MB_2U_LIB.S9S_MB_2U(SCH_1):GND
  H34  GND            VSS1612  @S9S_MB_2U_LIB.S9S_MB_2U(SCH_1):GND
  H32  GND            VSS1611  @S9S_MB_2U_LIB.S9S_MB_2U(SCH_1):GND
  H28  GND            VSS1610  @S9S_MB_2U_LIB.S9S_MB_2U(SCH_1):GND
  H26  GND            VSS1609  @S9S_MB_2U_LIB.S9S_MB_2U(SCH_1):GND
  H22  GND            VSS1608  @S9S_MB_2U_LIB.S9S_MB_2U(SCH_1):GND
  H20  GND            VSS1607  @S9S_MB_2U_LIB.S9S_MB_2U(SCH_1):GND
  H16  GND            VSS1606  @S9S_MB_2U_LIB.S9S_MB_2U(SCH_1):GND
  H10  GND            VSS1605  @S9S_MB_2U_LIB.S9S_MB_2U(SCH_1):GND
  G90  GND            VSS1604  @S9S_MB_2U_LIB.S9S_MB_2U(SCH_1):GND
  K49  GND            VSS1603  @S9S_MB_2U_LIB.S9S_MB_2U(SCH_1):GND
  K42  GND            VSS1602  @S9S_MB_2U_LIB.S9S_MB_2U(SCH_1):GND
  G88  GND            VSS1601  @S9S_MB_2U_LIB.S9S_MB_2U(SCH_1):GND
  G84  GND            VSS1600  @S9S_MB_2U_LIB.S9S_MB_2U(SCH_1):GND
   K2  GND            VSS1599  @S9S_MB_2U_LIB.S9S_MB_2U(SCH_1):GND
  K14  GND            VSS1598  @S9S_MB_2U_LIB.S9S_MB_2U(SCH_1):GND
  K12  GND            VSS1597  @S9S_MB_2U_LIB.S9S_MB_2U(SCH_1):GND
   J9  GND            VSS1596  @S9S_MB_2U_LIB.S9S_MB_2U(SCH_1):GND
  J88  GND            VSS1595  @S9S_MB_2U_LIB.S9S_MB_2U(SCH_1):GND
  G72  GND            VSS1594  @S9S_MB_2U_LIB.S9S_MB_2U(SCH_1):GND
  G62  GND            VSS1593  @S9S_MB_2U_LIB.S9S_MB_2U(SCH_1):GND
  G56  GND            VSS1592  @S9S_MB_2U_LIB.S9S_MB_2U(SCH_1):GND
  G54  GND            VSS1591  @S9S_MB_2U_LIB.S9S_MB_2U(SCH_1):GND
  G50  GND            VSS1590  @S9S_MB_2U_LIB.S9S_MB_2U(SCH_1):GND
  J70  GND            VSS1589  @S9S_MB_2U_LIB.S9S_MB_2U(SCH_1):GND
  G43  GND            VSS1588  @S9S_MB_2U_LIB.S9S_MB_2U(SCH_1):GND
  J64  GND            VSS1587  @S9S_MB_2U_LIB.S9S_MB_2U(SCH_1):GND
  G41  GND            VSS1586  @S9S_MB_2U_LIB.S9S_MB_2U(SCH_1):GND
  G37  GND            VSS1585  @S9S_MB_2U_LIB.S9S_MB_2U(SCH_1):GND
  G31  GND            VSS1584  @S9S_MB_2U_LIB.S9S_MB_2U(SCH_1):GND
  G29  GND            VSS1583  @S9S_MB_2U_LIB.S9S_MB_2U(SCH_1):GND
   J5  GND            VSS1582  @S9S_MB_2U_LIB.S9S_MB_2U(SCH_1):GND
  G23  GND            VSS1581  @S9S_MB_2U_LIB.S9S_MB_2U(SCH_1):GND
  J39  GND            VSS1580  @S9S_MB_2U_LIB.S9S_MB_2U(SCH_1):GND
  G19  GND            VSS1579  @S9S_MB_2U_LIB.S9S_MB_2U(SCH_1):GND
  G13  GND            VSS1578  @S9S_MB_2U_LIB.S9S_MB_2U(SCH_1):GND
  F89  GND            VSS1577  @S9S_MB_2U_LIB.S9S_MB_2U(SCH_1):GND
  F83  GND            VSS1576  @S9S_MB_2U_LIB.S9S_MB_2U(SCH_1):GND
  J21  GND            VSS1575  @S9S_MB_2U_LIB.S9S_MB_2U(SCH_1):GND
  F49  GND            VSS1574  @S9S_MB_2U_LIB.S9S_MB_2U(SCH_1):GND
   F4  GND            VSS1573  @S9S_MB_2U_LIB.S9S_MB_2U(SCH_1):GND
  F36  GND            VSS1572  @S9S_MB_2U_LIB.S9S_MB_2U(SCH_1):GND
  F30  GND            VSS1571  @S9S_MB_2U_LIB.S9S_MB_2U(SCH_1):GND
  F24  GND            VSS1570  @S9S_MB_2U_LIB.S9S_MB_2U(SCH_1):GND
  H75  GND            VSS1567  @S9S_MB_2U_LIB.S9S_MB_2U(SCH_1):GND
  H65  GND            VSS1564  @S9S_MB_2U_LIB.S9S_MB_2U(SCH_1):GND
  H57  GND            VSS1560  @S9S_MB_2U_LIB.S9S_MB_2U(SCH_1):GND
  H51  GND            VSS1558  @S9S_MB_2U_LIB.S9S_MB_2U(SCH_1):GND
   H2  GND            VSS1546  @S9S_MB_2U_LIB.S9S_MB_2U(SCH_1):GND
  H14  GND            VSS1544  @S9S_MB_2U_LIB.S9S_MB_2U(SCH_1):GND
  G74  GND            VSS1538  @S9S_MB_2U_LIB.S9S_MB_2U(SCH_1):GND
   G7  GND            VSS1536  @S9S_MB_2U_LIB.S9S_MB_2U(SCH_1):GND
  G68  GND            VSS1535  @S9S_MB_2U_LIB.S9S_MB_2U(SCH_1):GND
  G66  GND            VSS1534  @S9S_MB_2U_LIB.S9S_MB_2U(SCH_1):GND
  G60  GND            VSS1532  @S9S_MB_2U_LIB.S9S_MB_2U(SCH_1):GND
  G48  GND            VSS1527  @S9S_MB_2U_LIB.S9S_MB_2U(SCH_1):GND
  G35  GND            VSS1523  @S9S_MB_2U_LIB.S9S_MB_2U(SCH_1):GND
   G3  GND            VSS1521  @S9S_MB_2U_LIB.S9S_MB_2U(SCH_1):GND
  G25  GND            VSS1519  @S9S_MB_2U_LIB.S9S_MB_2U(SCH_1):GND
  G17  GND            VSS1516  @S9S_MB_2U_LIB.S9S_MB_2U(SCH_1):GND
  G11  GND            VSS1514  @S9S_MB_2U_LIB.S9S_MB_2U(SCH_1):GND
  F79  GND            VSS1511  @S9S_MB_2U_LIB.S9S_MB_2U(SCH_1):GND
  F73  GND            VSS1510  @S9S_MB_2U_LIB.S9S_MB_2U(SCH_1):GND
  F67  GND            VSS1509  @S9S_MB_2U_LIB.S9S_MB_2U(SCH_1):GND
  F61  GND            VSS1508  @S9S_MB_2U_LIB.S9S_MB_2U(SCH_1):GND
   F6  GND            VSS1507  @S9S_MB_2U_LIB.S9S_MB_2U(SCH_1):GND
  F55  GND            VSS1504  @S9S_MB_2U_LIB.S9S_MB_2U(SCH_1):GND
  F42  GND            VSS1502  @S9S_MB_2U_LIB.S9S_MB_2U(SCH_1):GND
  F18  GND            VSS1495  @S9S_MB_2U_LIB.S9S_MB_2U(SCH_1):GND
  F12  GND            VSS1494  @S9S_MB_2U_LIB.S9S_MB_2U(SCH_1):GND
  E86  GND            VSS1273  @S9S_MB_2U_LIB.S9S_MB_2U(SCH_1):GND
  E76  GND            VSS1272  @S9S_MB_2U_LIB.S9S_MB_2U(SCH_1):GND
  E78  GND            VSS1131  @S9S_MB_2U_LIB.S9S_MB_2U(SCH_1):GND
  E74  GND            VSS1129  @S9S_MB_2U_LIB.S9S_MB_2U(SCH_1):GND
  E52  GND            VSS1126  @S9S_MB_2U_LIB.S9S_MB_2U(SCH_1):GND

SOCKET4677_AZIFS054P001C01  I10  U2     [SOCKET4677_AZIFS054P001C01-SOCA]
  Y73  GND            VSS1833  @S9S_MB_2U_LIB.S9S_MB_2U(SCH_1):GND
   Y8  GND            VSS1832  @S9S_MB_2U_LIB.S9S_MB_2U(SCH_1):GND
  Y55  GND            VSS1831  @S9S_MB_2U_LIB.S9S_MB_2U(SCH_1):GND
  Y49  GND            VSS1830  @S9S_MB_2U_LIB.S9S_MB_2U(SCH_1):GND
  Y67  GND            VSS1829  @S9S_MB_2U_LIB.S9S_MB_2U(SCH_1):GND
  Y61  GND            VSS1828  @S9S_MB_2U_LIB.S9S_MB_2U(SCH_1):GND
  Y42  GND            VSS1827  @S9S_MB_2U_LIB.S9S_MB_2U(SCH_1):GND
   Y4  GND            VSS1826  @S9S_MB_2U_LIB.S9S_MB_2U(SCH_1):GND
  Y36  GND            VSS1825  @S9S_MB_2U_LIB.S9S_MB_2U(SCH_1):GND
  Y30  GND            VSS1824  @S9S_MB_2U_LIB.S9S_MB_2U(SCH_1):GND
  Y24  GND            VSS1823  @S9S_MB_2U_LIB.S9S_MB_2U(SCH_1):GND
  Y18  GND            VSS1822  @S9S_MB_2U_LIB.S9S_MB_2U(SCH_1):GND
  Y16  GND            VSS1821  @S9S_MB_2U_LIB.S9S_MB_2U(SCH_1):GND
  Y12  GND            VSS1820  @S9S_MB_2U_LIB.S9S_MB_2U(SCH_1):GND
   W9  GND            VSS1819  @S9S_MB_2U_LIB.S9S_MB_2U(SCH_1):GND
  W88  GND            VSS1818  @S9S_MB_2U_LIB.S9S_MB_2U(SCH_1):GND
  W84  GND            VSS1817  @S9S_MB_2U_LIB.S9S_MB_2U(SCH_1):GND
  W39  GND            VSS1816  @S9S_MB_2U_LIB.S9S_MB_2U(SCH_1):GND
  W52  GND            VSS1815  @S9S_MB_2U_LIB.S9S_MB_2U(SCH_1):GND
   W5  GND            VSS1814  @S9S_MB_2U_LIB.S9S_MB_2U(SCH_1):GND
  V87  GND            VSS1813  @S9S_MB_2U_LIB.S9S_MB_2U(SCH_1):GND
   V8  GND            VSS1812  @S9S_MB_2U_LIB.S9S_MB_2U(SCH_1):GND
  V79  GND            VSS1811  @S9S_MB_2U_LIB.S9S_MB_2U(SCH_1):GND
  V77  GND            VSS1810  @S9S_MB_2U_LIB.S9S_MB_2U(SCH_1):GND
  W13  GND            VSS1809  @S9S_MB_2U_LIB.S9S_MB_2U(SCH_1):GND
   W1  GND            VSS1808  @S9S_MB_2U_LIB.S9S_MB_2U(SCH_1):GND
  V91  GND            VSS1807  @S9S_MB_2U_LIB.S9S_MB_2U(SCH_1):GND
  V75  GND            VSS1806  @S9S_MB_2U_LIB.S9S_MB_2U(SCH_1):GND
  V69  GND            VSS1805  @S9S_MB_2U_LIB.S9S_MB_2U(SCH_1):GND
  V67  GND            VSS1804  @S9S_MB_2U_LIB.S9S_MB_2U(SCH_1):GND
  V65  GND            VSS1803  @S9S_MB_2U_LIB.S9S_MB_2U(SCH_1):GND
  V63  GND            VSS1802  @S9S_MB_2U_LIB.S9S_MB_2U(SCH_1):GND
  V73  GND            VSS1801  @S9S_MB_2U_LIB.S9S_MB_2U(SCH_1):GND
  V71  GND            VSS1800  @S9S_MB_2U_LIB.S9S_MB_2U(SCH_1):GND
  V61  GND            VSS1799  @S9S_MB_2U_LIB.S9S_MB_2U(SCH_1):GND
  V59  GND            VSS1798  @S9S_MB_2U_LIB.S9S_MB_2U(SCH_1):GND
  V57  GND            VSS1797  @S9S_MB_2U_LIB.S9S_MB_2U(SCH_1):GND
  V55  GND            VSS1796  @S9S_MB_2U_LIB.S9S_MB_2U(SCH_1):GND
  V53  GND            VSS1795  @S9S_MB_2U_LIB.S9S_MB_2U(SCH_1):GND
  V51  GND            VSS1794  @S9S_MB_2U_LIB.S9S_MB_2U(SCH_1):GND
  V47  GND            VSS1793  @S9S_MB_2U_LIB.S9S_MB_2U(SCH_1):GND
  V44  GND            VSS1792  @S9S_MB_2U_LIB.S9S_MB_2U(SCH_1):GND
  V42  GND            VSS1791  @S9S_MB_2U_LIB.S9S_MB_2U(SCH_1):GND
  V40  GND            VSS1790  @S9S_MB_2U_LIB.S9S_MB_2U(SCH_1):GND
  V49  GND            VSS1789  @S9S_MB_2U_LIB.S9S_MB_2U(SCH_1):GND
   V4  GND            VSS1788  @S9S_MB_2U_LIB.S9S_MB_2U(SCH_1):GND
  V38  GND            VSS1787  @S9S_MB_2U_LIB.S9S_MB_2U(SCH_1):GND
  V36  GND            VSS1786  @S9S_MB_2U_LIB.S9S_MB_2U(SCH_1):GND
  V34  GND            VSS1785  @S9S_MB_2U_LIB.S9S_MB_2U(SCH_1):GND
  V32  GND            VSS1784  @S9S_MB_2U_LIB.S9S_MB_2U(SCH_1):GND
  V30  GND            VSS1783  @S9S_MB_2U_LIB.S9S_MB_2U(SCH_1):GND
  V28  GND            VSS1782  @S9S_MB_2U_LIB.S9S_MB_2U(SCH_1):GND
  V26  GND            VSS1781  @S9S_MB_2U_LIB.S9S_MB_2U(SCH_1):GND
  V24  GND            VSS1780  @S9S_MB_2U_LIB.S9S_MB_2U(SCH_1):GND
  V22  GND            VSS1779  @S9S_MB_2U_LIB.S9S_MB_2U(SCH_1):GND
  V20  GND            VSS1778  @S9S_MB_2U_LIB.S9S_MB_2U(SCH_1):GND
  V18  GND            VSS1777  @S9S_MB_2U_LIB.S9S_MB_2U(SCH_1):GND
  V16  GND            VSS1776  @S9S_MB_2U_LIB.S9S_MB_2U(SCH_1):GND
  V12  GND            VSS1775  @S9S_MB_2U_LIB.S9S_MB_2U(SCH_1):GND
  U88  GND            VSS1774  @S9S_MB_2U_LIB.S9S_MB_2U(SCH_1):GND
  U84  GND            VSS1773  @S9S_MB_2U_LIB.S9S_MB_2U(SCH_1):GND
  U82  GND            VSS1772  @S9S_MB_2U_LIB.S9S_MB_2U(SCH_1):GND
  U39  GND            VSS1771  @S9S_MB_2U_LIB.S9S_MB_2U(SCH_1):GND
  T83  GND            VSS1770  @S9S_MB_2U_LIB.S9S_MB_2U(SCH_1):GND
   T8  GND            VSS1769  @S9S_MB_2U_LIB.S9S_MB_2U(SCH_1):GND
  T79  GND            VSS1768  @S9S_MB_2U_LIB.S9S_MB_2U(SCH_1):GND
  T73  GND            VSS1767  @S9S_MB_2U_LIB.S9S_MB_2U(SCH_1):GND
  U52  GND            VSS1766  @S9S_MB_2U_LIB.S9S_MB_2U(SCH_1):GND
  T67  GND            VSS1765  @S9S_MB_2U_LIB.S9S_MB_2U(SCH_1):GND
  T61  GND            VSS1764  @S9S_MB_2U_LIB.S9S_MB_2U(SCH_1):GND
  T42  GND            VSS1763  @S9S_MB_2U_LIB.S9S_MB_2U(SCH_1):GND
   T4  GND            VSS1762  @S9S_MB_2U_LIB.S9S_MB_2U(SCH_1):GND
  T30  GND            VSS1761  @S9S_MB_2U_LIB.S9S_MB_2U(SCH_1):GND
  T24  GND            VSS1760  @S9S_MB_2U_LIB.S9S_MB_2U(SCH_1):GND
   R9  GND            VSS1759  @S9S_MB_2U_LIB.S9S_MB_2U(SCH_1):GND
  R88  GND            VSS1758  @S9S_MB_2U_LIB.S9S_MB_2U(SCH_1):GND
  R84  GND            VSS1757  @S9S_MB_2U_LIB.S9S_MB_2U(SCH_1):GND
  R78  GND            VSS1756  @S9S_MB_2U_LIB.S9S_MB_2U(SCH_1):GND
  R74  GND            VSS1755  @S9S_MB_2U_LIB.S9S_MB_2U(SCH_1):GND
  R72  GND            VSS1754  @S9S_MB_2U_LIB.S9S_MB_2U(SCH_1):GND
  R68  GND            VSS1753  @S9S_MB_2U_LIB.S9S_MB_2U(SCH_1):GND
  R62  GND            VSS1752  @S9S_MB_2U_LIB.S9S_MB_2U(SCH_1):GND
  R56  GND            VSS1751  @S9S_MB_2U_LIB.S9S_MB_2U(SCH_1):GND
  T55  GND            VSS1750  @S9S_MB_2U_LIB.S9S_MB_2U(SCH_1):GND
  T49  GND            VSS1749  @S9S_MB_2U_LIB.S9S_MB_2U(SCH_1):GND
  R54  GND            VSS1748  @S9S_MB_2U_LIB.S9S_MB_2U(SCH_1):GND
  R50  GND            VSS1747  @S9S_MB_2U_LIB.S9S_MB_2U(SCH_1):GND
  T36  GND            VSS1746  @S9S_MB_2U_LIB.S9S_MB_2U(SCH_1):GND
   R5  GND            VSS1745  @S9S_MB_2U_LIB.S9S_MB_2U(SCH_1):GND
  R43  GND            VSS1744  @S9S_MB_2U_LIB.S9S_MB_2U(SCH_1):GND
  R41  GND            VSS1743  @S9S_MB_2U_LIB.S9S_MB_2U(SCH_1):GND
  R37  GND            VSS1742  @S9S_MB_2U_LIB.S9S_MB_2U(SCH_1):GND
  T18  GND            VSS1741  @S9S_MB_2U_LIB.S9S_MB_2U(SCH_1):GND
  T16  GND            VSS1740  @S9S_MB_2U_LIB.S9S_MB_2U(SCH_1):GND
  T12  GND            VSS1739  @S9S_MB_2U_LIB.S9S_MB_2U(SCH_1):GND
  R35  GND            VSS1738  @S9S_MB_2U_LIB.S9S_MB_2U(SCH_1):GND
  R31  GND            VSS1737  @S9S_MB_2U_LIB.S9S_MB_2U(SCH_1):GND
  R29  GND            VSS1736  @S9S_MB_2U_LIB.S9S_MB_2U(SCH_1):GND
  R25  GND            VSS1735  @S9S_MB_2U_LIB.S9S_MB_2U(SCH_1):GND
  R17  GND            VSS1734  @S9S_MB_2U_LIB.S9S_MB_2U(SCH_1):GND
  R13  GND            VSS1733  @S9S_MB_2U_LIB.S9S_MB_2U(SCH_1):GND
  P91  GND            VSS1732  @S9S_MB_2U_LIB.S9S_MB_2U(SCH_1):GND
  P87  GND            VSS1731  @S9S_MB_2U_LIB.S9S_MB_2U(SCH_1):GND
  R66  GND            VSS1730  @S9S_MB_2U_LIB.S9S_MB_2U(SCH_1):GND
   P8  GND            VSS1729  @S9S_MB_2U_LIB.S9S_MB_2U(SCH_1):GND
  R60  GND            VSS1728  @S9S_MB_2U_LIB.S9S_MB_2U(SCH_1):GND
  P77  GND            VSS1727  @S9S_MB_2U_LIB.S9S_MB_2U(SCH_1):GND
  P75  GND            VSS1726  @S9S_MB_2U_LIB.S9S_MB_2U(SCH_1):GND
  P69  GND            VSS1725  @S9S_MB_2U_LIB.S9S_MB_2U(SCH_1):GND
  P65  GND            VSS1724  @S9S_MB_2U_LIB.S9S_MB_2U(SCH_1):GND
  R48  GND            VSS1723  @S9S_MB_2U_LIB.S9S_MB_2U(SCH_1):GND
  P63  GND            VSS1722  @S9S_MB_2U_LIB.S9S_MB_2U(SCH_1):GND
  P59  GND            VSS1721  @S9S_MB_2U_LIB.S9S_MB_2U(SCH_1):GND
  P53  GND            VSS1720  @S9S_MB_2U_LIB.S9S_MB_2U(SCH_1):GND
  P47  GND            VSS1719  @S9S_MB_2U_LIB.S9S_MB_2U(SCH_1):GND
  P44  GND            VSS1718  @S9S_MB_2U_LIB.S9S_MB_2U(SCH_1):GND
  P40  GND            VSS1717  @S9S_MB_2U_LIB.S9S_MB_2U(SCH_1):GND
   P4  GND            VSS1716  @S9S_MB_2U_LIB.S9S_MB_2U(SCH_1):GND
  R23  GND            VSS1715  @S9S_MB_2U_LIB.S9S_MB_2U(SCH_1):GND
  R19  GND            VSS1714  @S9S_MB_2U_LIB.S9S_MB_2U(SCH_1):GND
  P38  GND            VSS1713  @S9S_MB_2U_LIB.S9S_MB_2U(SCH_1):GND
  P34  GND            VSS1712  @S9S_MB_2U_LIB.S9S_MB_2U(SCH_1):GND
   R1  GND            VSS1711  @S9S_MB_2U_LIB.S9S_MB_2U(SCH_1):GND
  P28  GND            VSS1710  @S9S_MB_2U_LIB.S9S_MB_2U(SCH_1):GND
  P26  GND            VSS1709  @S9S_MB_2U_LIB.S9S_MB_2U(SCH_1):GND
  P22  GND            VSS1708  @S9S_MB_2U_LIB.S9S_MB_2U(SCH_1):GND
  P20  GND            VSS1707  @S9S_MB_2U_LIB.S9S_MB_2U(SCH_1):GND
  P16  GND            VSS1706  @S9S_MB_2U_LIB.S9S_MB_2U(SCH_1):GND
  P12  GND            VSS1705  @S9S_MB_2U_LIB.S9S_MB_2U(SCH_1):GND
  P71  GND            VSS1704  @S9S_MB_2U_LIB.S9S_MB_2U(SCH_1):GND
  N88  GND            VSS1703  @S9S_MB_2U_LIB.S9S_MB_2U(SCH_1):GND
  N84  GND            VSS1702  @S9S_MB_2U_LIB.S9S_MB_2U(SCH_1):GND
  N82  GND            VSS1701  @S9S_MB_2U_LIB.S9S_MB_2U(SCH_1):GND
  N80  GND            VSS1700  @S9S_MB_2U_LIB.S9S_MB_2U(SCH_1):GND
  P57  GND            VSS1699  @S9S_MB_2U_LIB.S9S_MB_2U(SCH_1):GND
  N78  GND            VSS1698  @S9S_MB_2U_LIB.S9S_MB_2U(SCH_1):GND
  P51  GND            VSS1697  @S9S_MB_2U_LIB.S9S_MB_2U(SCH_1):GND
  N76  GND            VSS1696  @S9S_MB_2U_LIB.S9S_MB_2U(SCH_1):GND
  P32  GND            VSS1690  @S9S_MB_2U_LIB.S9S_MB_2U(SCH_1):GND
  AA80  GND            VSS37  @S9S_MB_2U_LIB.S9S_MB_2U(SCH_1):GND
  AA78  GND            VSS36  @S9S_MB_2U_LIB.S9S_MB_2U(SCH_1):GND
  AA74  GND            VSS35  @S9S_MB_2U_LIB.S9S_MB_2U(SCH_1):GND
  AA72  GND            VSS34  @S9S_MB_2U_LIB.S9S_MB_2U(SCH_1):GND
  AA68  GND            VSS33  @S9S_MB_2U_LIB.S9S_MB_2U(SCH_1):GND
  AA66  GND            VSS32  @S9S_MB_2U_LIB.S9S_MB_2U(SCH_1):GND
  AA62  GND            VSS31  @S9S_MB_2U_LIB.S9S_MB_2U(SCH_1):GND
  AA60  GND            VSS30  @S9S_MB_2U_LIB.S9S_MB_2U(SCH_1):GND
  AA56  GND            VSS29  @S9S_MB_2U_LIB.S9S_MB_2U(SCH_1):GND
  AA54  GND            VSS28  @S9S_MB_2U_LIB.S9S_MB_2U(SCH_1):GND
  AA50  GND            VSS27  @S9S_MB_2U_LIB.S9S_MB_2U(SCH_1):GND
  AA48  GND            VSS26  @S9S_MB_2U_LIB.S9S_MB_2U(SCH_1):GND
  AA43  GND            VSS25  @S9S_MB_2U_LIB.S9S_MB_2U(SCH_1):GND
  AA41  GND            VSS24  @S9S_MB_2U_LIB.S9S_MB_2U(SCH_1):GND
  AA37  GND            VSS23  @S9S_MB_2U_LIB.S9S_MB_2U(SCH_1):GND
  AA35  GND            VSS22  @S9S_MB_2U_LIB.S9S_MB_2U(SCH_1):GND
  AA31  GND            VSS21  @S9S_MB_2U_LIB.S9S_MB_2U(SCH_1):GND
  AA29  GND            VSS20  @S9S_MB_2U_LIB.S9S_MB_2U(SCH_1):GND
  AA25  GND            VSS19  @S9S_MB_2U_LIB.S9S_MB_2U(SCH_1):GND
  AA23  GND            VSS18  @S9S_MB_2U_LIB.S9S_MB_2U(SCH_1):GND
  AA19  GND            VSS17  @S9S_MB_2U_LIB.S9S_MB_2U(SCH_1):GND

SOCKET4677_AZIFS054P001C01  I11  U2     [SOCKET4677_AZIFS054P001C01-SOCA]
  AJ88  GND            VSS197  @S9S_MB_2U_LIB.S9S_MB_2U(SCH_1):GND
  AJ84  GND            VSS196  @S9S_MB_2U_LIB.S9S_MB_2U(SCH_1):GND
  AJ78  GND            VSS195  @S9S_MB_2U_LIB.S9S_MB_2U(SCH_1):GND
  AJ74  GND            VSS194  @S9S_MB_2U_LIB.S9S_MB_2U(SCH_1):GND
  AJ72  GND            VSS193  @S9S_MB_2U_LIB.S9S_MB_2U(SCH_1):GND
  AJ68  GND            VSS192  @S9S_MB_2U_LIB.S9S_MB_2U(SCH_1):GND
  AJ66  GND            VSS191  @S9S_MB_2U_LIB.S9S_MB_2U(SCH_1):GND
  AJ62  GND            VSS190  @S9S_MB_2U_LIB.S9S_MB_2U(SCH_1):GND
  AJ60  GND            VSS189  @S9S_MB_2U_LIB.S9S_MB_2U(SCH_1):GND
  AJ56  GND            VSS188  @S9S_MB_2U_LIB.S9S_MB_2U(SCH_1):GND
  AJ54  GND            VSS187  @S9S_MB_2U_LIB.S9S_MB_2U(SCH_1):GND
  AJ50  GND            VSS186  @S9S_MB_2U_LIB.S9S_MB_2U(SCH_1):GND
  AJ48  GND            VSS185  @S9S_MB_2U_LIB.S9S_MB_2U(SCH_1):GND
  AJ43  GND            VSS184  @S9S_MB_2U_LIB.S9S_MB_2U(SCH_1):GND
  AJ41  GND            VSS183  @S9S_MB_2U_LIB.S9S_MB_2U(SCH_1):GND
  AJ37  GND            VSS182  @S9S_MB_2U_LIB.S9S_MB_2U(SCH_1):GND
  AJ35  GND            VSS181  @S9S_MB_2U_LIB.S9S_MB_2U(SCH_1):GND
  AJ31  GND            VSS180  @S9S_MB_2U_LIB.S9S_MB_2U(SCH_1):GND
  AJ29  GND            VSS179  @S9S_MB_2U_LIB.S9S_MB_2U(SCH_1):GND
  AJ25  GND            VSS178  @S9S_MB_2U_LIB.S9S_MB_2U(SCH_1):GND
  AJ23  GND            VSS177  @S9S_MB_2U_LIB.S9S_MB_2U(SCH_1):GND
  AJ19  GND            VSS176  @S9S_MB_2U_LIB.S9S_MB_2U(SCH_1):GND
  AH83  GND            VSS175  @S9S_MB_2U_LIB.S9S_MB_2U(SCH_1):GND
  AH8  GND            VSS174  @S9S_MB_2U_LIB.S9S_MB_2U(SCH_1):GND
  AH79  GND            VSS173  @S9S_MB_2U_LIB.S9S_MB_2U(SCH_1):GND
  AH77  GND            VSS172  @S9S_MB_2U_LIB.S9S_MB_2U(SCH_1):GND
  AH75  GND            VSS171  @S9S_MB_2U_LIB.S9S_MB_2U(SCH_1):GND
  AH71  GND            VSS170  @S9S_MB_2U_LIB.S9S_MB_2U(SCH_1):GND
  AH69  GND            VSS169  @S9S_MB_2U_LIB.S9S_MB_2U(SCH_1):GND
  AH65  GND            VSS168  @S9S_MB_2U_LIB.S9S_MB_2U(SCH_1):GND
  AH63  GND            VSS167  @S9S_MB_2U_LIB.S9S_MB_2U(SCH_1):GND
  AH59  GND            VSS166  @S9S_MB_2U_LIB.S9S_MB_2U(SCH_1):GND
  AH57  GND            VSS165  @S9S_MB_2U_LIB.S9S_MB_2U(SCH_1):GND
  AH53  GND            VSS164  @S9S_MB_2U_LIB.S9S_MB_2U(SCH_1):GND
  AH51  GND            VSS163  @S9S_MB_2U_LIB.S9S_MB_2U(SCH_1):GND
  AH47  GND            VSS162  @S9S_MB_2U_LIB.S9S_MB_2U(SCH_1):GND
  AH44  GND            VSS161  @S9S_MB_2U_LIB.S9S_MB_2U(SCH_1):GND
  AH40  GND            VSS160  @S9S_MB_2U_LIB.S9S_MB_2U(SCH_1):GND
  AH4  GND            VSS159  @S9S_MB_2U_LIB.S9S_MB_2U(SCH_1):GND
  AH38  GND            VSS158  @S9S_MB_2U_LIB.S9S_MB_2U(SCH_1):GND
  AH34  GND            VSS157  @S9S_MB_2U_LIB.S9S_MB_2U(SCH_1):GND
  AH32  GND            VSS156  @S9S_MB_2U_LIB.S9S_MB_2U(SCH_1):GND
  AH28  GND            VSS155  @S9S_MB_2U_LIB.S9S_MB_2U(SCH_1):GND
  AH26  GND            VSS154  @S9S_MB_2U_LIB.S9S_MB_2U(SCH_1):GND
  AH22  GND            VSS153  @S9S_MB_2U_LIB.S9S_MB_2U(SCH_1):GND
  AH20  GND            VSS152  @S9S_MB_2U_LIB.S9S_MB_2U(SCH_1):GND
  AH16  GND            VSS151  @S9S_MB_2U_LIB.S9S_MB_2U(SCH_1):GND
  AH12  GND            VSS150  @S9S_MB_2U_LIB.S9S_MB_2U(SCH_1):GND
  AG9  GND            VSS149  @S9S_MB_2U_LIB.S9S_MB_2U(SCH_1):GND
  AG88  GND            VSS148  @S9S_MB_2U_LIB.S9S_MB_2U(SCH_1):GND
  AG84  GND            VSS147  @S9S_MB_2U_LIB.S9S_MB_2U(SCH_1):GND
  AG76  GND            VSS146  @S9S_MB_2U_LIB.S9S_MB_2U(SCH_1):GND
  AG70  GND            VSS145  @S9S_MB_2U_LIB.S9S_MB_2U(SCH_1):GND
  AG64  GND            VSS144  @S9S_MB_2U_LIB.S9S_MB_2U(SCH_1):GND
  AG58  GND            VSS143  @S9S_MB_2U_LIB.S9S_MB_2U(SCH_1):GND
  AG52  GND            VSS142  @S9S_MB_2U_LIB.S9S_MB_2U(SCH_1):GND
  AG5  GND            VSS141  @S9S_MB_2U_LIB.S9S_MB_2U(SCH_1):GND
  AG45  GND            VSS140  @S9S_MB_2U_LIB.S9S_MB_2U(SCH_1):GND
  AG39  GND            VSS139  @S9S_MB_2U_LIB.S9S_MB_2U(SCH_1):GND
  AG33  GND            VSS138  @S9S_MB_2U_LIB.S9S_MB_2U(SCH_1):GND
  AG27  GND            VSS137  @S9S_MB_2U_LIB.S9S_MB_2U(SCH_1):GND
  AG21  GND            VSS136  @S9S_MB_2U_LIB.S9S_MB_2U(SCH_1):GND
  AG13  GND            VSS135  @S9S_MB_2U_LIB.S9S_MB_2U(SCH_1):GND
  AG1  GND            VSS134  @S9S_MB_2U_LIB.S9S_MB_2U(SCH_1):GND
  AF91  GND            VSS133  @S9S_MB_2U_LIB.S9S_MB_2U(SCH_1):GND
  AF87  GND            VSS132  @S9S_MB_2U_LIB.S9S_MB_2U(SCH_1):GND
  AF81  GND            VSS131  @S9S_MB_2U_LIB.S9S_MB_2U(SCH_1):GND
  AF8  GND            VSS130  @S9S_MB_2U_LIB.S9S_MB_2U(SCH_1):GND
  AF42  GND            VSS129  @S9S_MB_2U_LIB.S9S_MB_2U(SCH_1):GND
  AF4  GND            VSS128  @S9S_MB_2U_LIB.S9S_MB_2U(SCH_1):GND
  AF16  GND            VSS127  @S9S_MB_2U_LIB.S9S_MB_2U(SCH_1):GND
  AF12  GND            VSS126  @S9S_MB_2U_LIB.S9S_MB_2U(SCH_1):GND
  AE88  GND            VSS125  @S9S_MB_2U_LIB.S9S_MB_2U(SCH_1):GND
  AE84  GND            VSS124  @S9S_MB_2U_LIB.S9S_MB_2U(SCH_1):GND
  AE78  GND            VSS123  @S9S_MB_2U_LIB.S9S_MB_2U(SCH_1):GND
  AE76  GND            VSS122  @S9S_MB_2U_LIB.S9S_MB_2U(SCH_1):GND
  AE74  GND            VSS121  @S9S_MB_2U_LIB.S9S_MB_2U(SCH_1):GND
  AE72  GND            VSS120  @S9S_MB_2U_LIB.S9S_MB_2U(SCH_1):GND
  AE70  GND            VSS119  @S9S_MB_2U_LIB.S9S_MB_2U(SCH_1):GND
  AE68  GND            VSS118  @S9S_MB_2U_LIB.S9S_MB_2U(SCH_1):GND
  AE66  GND            VSS117  @S9S_MB_2U_LIB.S9S_MB_2U(SCH_1):GND
  AE64  GND            VSS116  @S9S_MB_2U_LIB.S9S_MB_2U(SCH_1):GND
  AE62  GND            VSS115  @S9S_MB_2U_LIB.S9S_MB_2U(SCH_1):GND
  AE60  GND            VSS114  @S9S_MB_2U_LIB.S9S_MB_2U(SCH_1):GND
  AE58  GND            VSS113  @S9S_MB_2U_LIB.S9S_MB_2U(SCH_1):GND
  AE56  GND            VSS112  @S9S_MB_2U_LIB.S9S_MB_2U(SCH_1):GND
  AE54  GND            VSS111  @S9S_MB_2U_LIB.S9S_MB_2U(SCH_1):GND
  AE52  GND            VSS110  @S9S_MB_2U_LIB.S9S_MB_2U(SCH_1):GND
  AE50  GND            VSS109  @S9S_MB_2U_LIB.S9S_MB_2U(SCH_1):GND
  AE48  GND            VSS108  @S9S_MB_2U_LIB.S9S_MB_2U(SCH_1):GND
  AE45  GND            VSS107  @S9S_MB_2U_LIB.S9S_MB_2U(SCH_1):GND
  AE43  GND            VSS106  @S9S_MB_2U_LIB.S9S_MB_2U(SCH_1):GND
  AE41  GND            VSS105  @S9S_MB_2U_LIB.S9S_MB_2U(SCH_1):GND
  AE39  GND            VSS104  @S9S_MB_2U_LIB.S9S_MB_2U(SCH_1):GND
  AE37  GND            VSS103  @S9S_MB_2U_LIB.S9S_MB_2U(SCH_1):GND
  AE35  GND            VSS102  @S9S_MB_2U_LIB.S9S_MB_2U(SCH_1):GND
  AE33  GND            VSS101  @S9S_MB_2U_LIB.S9S_MB_2U(SCH_1):GND
  AE31  GND            VSS100  @S9S_MB_2U_LIB.S9S_MB_2U(SCH_1):GND
  AE29  GND            VSS99  @S9S_MB_2U_LIB.S9S_MB_2U(SCH_1):GND
  AE27  GND            VSS98  @S9S_MB_2U_LIB.S9S_MB_2U(SCH_1):GND
  AE25  GND            VSS97  @S9S_MB_2U_LIB.S9S_MB_2U(SCH_1):GND
  AE23  GND            VSS96  @S9S_MB_2U_LIB.S9S_MB_2U(SCH_1):GND
  AE21  GND            VSS95  @S9S_MB_2U_LIB.S9S_MB_2U(SCH_1):GND
  AE19  GND            VSS94  @S9S_MB_2U_LIB.S9S_MB_2U(SCH_1):GND
  AE17  GND            VSS93  @S9S_MB_2U_LIB.S9S_MB_2U(SCH_1):GND
  AD83  GND            VSS92  @S9S_MB_2U_LIB.S9S_MB_2U(SCH_1):GND
  AD8  GND            VSS91  @S9S_MB_2U_LIB.S9S_MB_2U(SCH_1):GND
  AD79  GND            VSS90  @S9S_MB_2U_LIB.S9S_MB_2U(SCH_1):GND
  AD42  GND            VSS89  @S9S_MB_2U_LIB.S9S_MB_2U(SCH_1):GND
  AD4  GND            VSS88  @S9S_MB_2U_LIB.S9S_MB_2U(SCH_1):GND
  AD16  GND            VSS87  @S9S_MB_2U_LIB.S9S_MB_2U(SCH_1):GND
  AD12  GND            VSS86  @S9S_MB_2U_LIB.S9S_MB_2U(SCH_1):GND
  AC9  GND            VSS85  @S9S_MB_2U_LIB.S9S_MB_2U(SCH_1):GND
  AC88  GND            VSS84  @S9S_MB_2U_LIB.S9S_MB_2U(SCH_1):GND
  AC84  GND            VSS83  @S9S_MB_2U_LIB.S9S_MB_2U(SCH_1):GND
  AC76  GND            VSS82  @S9S_MB_2U_LIB.S9S_MB_2U(SCH_1):GND
  AC70  GND            VSS81  @S9S_MB_2U_LIB.S9S_MB_2U(SCH_1):GND
  AC64  GND            VSS80  @S9S_MB_2U_LIB.S9S_MB_2U(SCH_1):GND
  AC58  GND            VSS79  @S9S_MB_2U_LIB.S9S_MB_2U(SCH_1):GND
  AC52  GND            VSS78  @S9S_MB_2U_LIB.S9S_MB_2U(SCH_1):GND
  AC5  GND            VSS77  @S9S_MB_2U_LIB.S9S_MB_2U(SCH_1):GND
  AC45  GND            VSS76  @S9S_MB_2U_LIB.S9S_MB_2U(SCH_1):GND
  AC39  GND            VSS75  @S9S_MB_2U_LIB.S9S_MB_2U(SCH_1):GND
  AC33  GND            VSS74  @S9S_MB_2U_LIB.S9S_MB_2U(SCH_1):GND
  AC27  GND            VSS73  @S9S_MB_2U_LIB.S9S_MB_2U(SCH_1):GND
  AC21  GND            VSS72  @S9S_MB_2U_LIB.S9S_MB_2U(SCH_1):GND
  AC13  GND            VSS71  @S9S_MB_2U_LIB.S9S_MB_2U(SCH_1):GND
  AC1  GND            VSS70  @S9S_MB_2U_LIB.S9S_MB_2U(SCH_1):GND
  AB91  GND            VSS69  @S9S_MB_2U_LIB.S9S_MB_2U(SCH_1):GND
  AB87  GND            VSS68  @S9S_MB_2U_LIB.S9S_MB_2U(SCH_1):GND
  AB83  GND            VSS67  @S9S_MB_2U_LIB.S9S_MB_2U(SCH_1):GND
  AB81  GND            VSS66  @S9S_MB_2U_LIB.S9S_MB_2U(SCH_1):GND
  AB8  GND            VSS65  @S9S_MB_2U_LIB.S9S_MB_2U(SCH_1):GND
  AB79  GND            VSS64  @S9S_MB_2U_LIB.S9S_MB_2U(SCH_1):GND
  AB77  GND            VSS63  @S9S_MB_2U_LIB.S9S_MB_2U(SCH_1):GND
  AB75  GND            VSS62  @S9S_MB_2U_LIB.S9S_MB_2U(SCH_1):GND
  AB71  GND            VSS61  @S9S_MB_2U_LIB.S9S_MB_2U(SCH_1):GND
  AB69  GND            VSS60  @S9S_MB_2U_LIB.S9S_MB_2U(SCH_1):GND
  AB65  GND            VSS59  @S9S_MB_2U_LIB.S9S_MB_2U(SCH_1):GND
  AB63  GND            VSS58  @S9S_MB_2U_LIB.S9S_MB_2U(SCH_1):GND
  AB59  GND            VSS57  @S9S_MB_2U_LIB.S9S_MB_2U(SCH_1):GND
  AB57  GND            VSS56  @S9S_MB_2U_LIB.S9S_MB_2U(SCH_1):GND
  AB53  GND            VSS55  @S9S_MB_2U_LIB.S9S_MB_2U(SCH_1):GND
  AB51  GND            VSS54  @S9S_MB_2U_LIB.S9S_MB_2U(SCH_1):GND
  AB47  GND            VSS53  @S9S_MB_2U_LIB.S9S_MB_2U(SCH_1):GND
  AB44  GND            VSS52  @S9S_MB_2U_LIB.S9S_MB_2U(SCH_1):GND
  AB40  GND            VSS51  @S9S_MB_2U_LIB.S9S_MB_2U(SCH_1):GND
  AB4  GND            VSS50  @S9S_MB_2U_LIB.S9S_MB_2U(SCH_1):GND
  AB38  GND            VSS49  @S9S_MB_2U_LIB.S9S_MB_2U(SCH_1):GND
  AB34  GND            VSS48  @S9S_MB_2U_LIB.S9S_MB_2U(SCH_1):GND
  AB32  GND            VSS47  @S9S_MB_2U_LIB.S9S_MB_2U(SCH_1):GND
  AB28  GND            VSS46  @S9S_MB_2U_LIB.S9S_MB_2U(SCH_1):GND
  AB26  GND            VSS45  @S9S_MB_2U_LIB.S9S_MB_2U(SCH_1):GND
  AB22  GND            VSS44  @S9S_MB_2U_LIB.S9S_MB_2U(SCH_1):GND
  AB20  GND            VSS43  @S9S_MB_2U_LIB.S9S_MB_2U(SCH_1):GND
  AB16  GND            VSS42  @S9S_MB_2U_LIB.S9S_MB_2U(SCH_1):GND
  AB12  GND            VSS41  @S9S_MB_2U_LIB.S9S_MB_2U(SCH_1):GND
  AA88  GND            VSS40  @S9S_MB_2U_LIB.S9S_MB_2U(SCH_1):GND
  AA84  GND            VSS39  @S9S_MB_2U_LIB.S9S_MB_2U(SCH_1):GND
  AA82  GND            VSS38  @S9S_MB_2U_LIB.S9S_MB_2U(SCH_1):GND

SOCKET4677_AZIFS054P001C01  I10  U2     [SOCKET4677_AZIFS054P001C01-SOCA]
  AW9  GND            VSS368  @S9S_MB_2U_LIB.S9S_MB_2U(SCH_1):GND
  AW5  GND            VSS359  @S9S_MB_2U_LIB.S9S_MB_2U(SCH_1):GND
  AW13  GND            VSS355  @S9S_MB_2U_LIB.S9S_MB_2U(SCH_1):GND
  AW1  GND            VSS354  @S9S_MB_2U_LIB.S9S_MB_2U(SCH_1):GND
  AV91  GND            VSS353  @S9S_MB_2U_LIB.S9S_MB_2U(SCH_1):GND
  AV87  GND            VSS352  @S9S_MB_2U_LIB.S9S_MB_2U(SCH_1):GND
  AV8  GND            VSS351  @S9S_MB_2U_LIB.S9S_MB_2U(SCH_1):GND
  AV77  GND            VSS350  @S9S_MB_2U_LIB.S9S_MB_2U(SCH_1):GND
  AV4  GND            VSS349  @S9S_MB_2U_LIB.S9S_MB_2U(SCH_1):GND
  AV16  GND            VSS348  @S9S_MB_2U_LIB.S9S_MB_2U(SCH_1):GND
  AV12  GND            VSS347  @S9S_MB_2U_LIB.S9S_MB_2U(SCH_1):GND
  AU88  GND            VSS346  @S9S_MB_2U_LIB.S9S_MB_2U(SCH_1):GND
  AU84  GND            VSS345  @S9S_MB_2U_LIB.S9S_MB_2U(SCH_1):GND
  AU80  GND            VSS344  @S9S_MB_2U_LIB.S9S_MB_2U(SCH_1):GND
  AU76  GND            VSS343  @S9S_MB_2U_LIB.S9S_MB_2U(SCH_1):GND
  AU74  GND            VSS342  @S9S_MB_2U_LIB.S9S_MB_2U(SCH_1):GND
  AU72  GND            VSS341  @S9S_MB_2U_LIB.S9S_MB_2U(SCH_1):GND
  AU70  GND            VSS340  @S9S_MB_2U_LIB.S9S_MB_2U(SCH_1):GND
  AU48  GND            VSS339  @S9S_MB_2U_LIB.S9S_MB_2U(SCH_1):GND
  AU45  GND            VSS338  @S9S_MB_2U_LIB.S9S_MB_2U(SCH_1):GND
  AU41  GND            VSS337  @S9S_MB_2U_LIB.S9S_MB_2U(SCH_1):GND
  AU39  GND            VSS336  @S9S_MB_2U_LIB.S9S_MB_2U(SCH_1):GND
  AU37  GND            VSS335  @S9S_MB_2U_LIB.S9S_MB_2U(SCH_1):GND
  AU31  GND            VSS334  @S9S_MB_2U_LIB.S9S_MB_2U(SCH_1):GND
  AU27  GND            VSS333  @S9S_MB_2U_LIB.S9S_MB_2U(SCH_1):GND
  AT8  GND            VSS332  @S9S_MB_2U_LIB.S9S_MB_2U(SCH_1):GND
  AT79  GND            VSS331  @S9S_MB_2U_LIB.S9S_MB_2U(SCH_1):GND
  AT77  GND            VSS330  @S9S_MB_2U_LIB.S9S_MB_2U(SCH_1):GND
  AT75  GND            VSS329  @S9S_MB_2U_LIB.S9S_MB_2U(SCH_1):GND
  AT71  GND            VSS328  @S9S_MB_2U_LIB.S9S_MB_2U(SCH_1):GND
  AT69  GND            VSS327  @S9S_MB_2U_LIB.S9S_MB_2U(SCH_1):GND
  AT65  GND            VSS326  @S9S_MB_2U_LIB.S9S_MB_2U(SCH_1):GND
  AT63  GND            VSS325  @S9S_MB_2U_LIB.S9S_MB_2U(SCH_1):GND
  AT59  GND            VSS324  @S9S_MB_2U_LIB.S9S_MB_2U(SCH_1):GND
  AT57  GND            VSS323  @S9S_MB_2U_LIB.S9S_MB_2U(SCH_1):GND
  AT53  GND            VSS322  @S9S_MB_2U_LIB.S9S_MB_2U(SCH_1):GND
  AT51  GND            VSS321  @S9S_MB_2U_LIB.S9S_MB_2U(SCH_1):GND
  AT44  GND            VSS320  @S9S_MB_2U_LIB.S9S_MB_2U(SCH_1):GND
  AT40  GND            VSS319  @S9S_MB_2U_LIB.S9S_MB_2U(SCH_1):GND
  AT4  GND            VSS318  @S9S_MB_2U_LIB.S9S_MB_2U(SCH_1):GND
  AT38  GND            VSS317  @S9S_MB_2U_LIB.S9S_MB_2U(SCH_1):GND
  AT34  GND            VSS316  @S9S_MB_2U_LIB.S9S_MB_2U(SCH_1):GND
  AT32  GND            VSS315  @S9S_MB_2U_LIB.S9S_MB_2U(SCH_1):GND
  AT28  GND            VSS314  @S9S_MB_2U_LIB.S9S_MB_2U(SCH_1):GND
  AT26  GND            VSS313  @S9S_MB_2U_LIB.S9S_MB_2U(SCH_1):GND
  AT22  GND            VSS312  @S9S_MB_2U_LIB.S9S_MB_2U(SCH_1):GND
  AT20  GND            VSS311  @S9S_MB_2U_LIB.S9S_MB_2U(SCH_1):GND
  AT16  GND            VSS310  @S9S_MB_2U_LIB.S9S_MB_2U(SCH_1):GND
  AT12  GND            VSS309  @S9S_MB_2U_LIB.S9S_MB_2U(SCH_1):GND
  AR9  GND            VSS308  @S9S_MB_2U_LIB.S9S_MB_2U(SCH_1):GND
  AR88  GND            VSS307  @S9S_MB_2U_LIB.S9S_MB_2U(SCH_1):GND
  AR84  GND            VSS306  @S9S_MB_2U_LIB.S9S_MB_2U(SCH_1):GND
  AR82  GND            VSS305  @S9S_MB_2U_LIB.S9S_MB_2U(SCH_1):GND
  AR78  GND            VSS304  @S9S_MB_2U_LIB.S9S_MB_2U(SCH_1):GND
  AR74  GND            VSS303  @S9S_MB_2U_LIB.S9S_MB_2U(SCH_1):GND
  AR72  GND            VSS302  @S9S_MB_2U_LIB.S9S_MB_2U(SCH_1):GND
  AR68  GND            VSS301  @S9S_MB_2U_LIB.S9S_MB_2U(SCH_1):GND
  AR66  GND            VSS300  @S9S_MB_2U_LIB.S9S_MB_2U(SCH_1):GND
  AR62  GND            VSS299  @S9S_MB_2U_LIB.S9S_MB_2U(SCH_1):GND
  AR60  GND            VSS298  @S9S_MB_2U_LIB.S9S_MB_2U(SCH_1):GND
  AR56  GND            VSS297  @S9S_MB_2U_LIB.S9S_MB_2U(SCH_1):GND
  AR54  GND            VSS296  @S9S_MB_2U_LIB.S9S_MB_2U(SCH_1):GND
  AR50  GND            VSS295  @S9S_MB_2U_LIB.S9S_MB_2U(SCH_1):GND
  AR5  GND            VSS294  @S9S_MB_2U_LIB.S9S_MB_2U(SCH_1):GND
  AR48  GND            VSS293  @S9S_MB_2U_LIB.S9S_MB_2U(SCH_1):GND
  AR43  GND            VSS292  @S9S_MB_2U_LIB.S9S_MB_2U(SCH_1):GND
  AR41  GND            VSS291  @S9S_MB_2U_LIB.S9S_MB_2U(SCH_1):GND
  AR37  GND            VSS290  @S9S_MB_2U_LIB.S9S_MB_2U(SCH_1):GND
  AR35  GND            VSS289  @S9S_MB_2U_LIB.S9S_MB_2U(SCH_1):GND
  AR31  GND            VSS288  @S9S_MB_2U_LIB.S9S_MB_2U(SCH_1):GND
  AR29  GND            VSS287  @S9S_MB_2U_LIB.S9S_MB_2U(SCH_1):GND
  AR25  GND            VSS286  @S9S_MB_2U_LIB.S9S_MB_2U(SCH_1):GND
  AR23  GND            VSS285  @S9S_MB_2U_LIB.S9S_MB_2U(SCH_1):GND
  AR19  GND            VSS284  @S9S_MB_2U_LIB.S9S_MB_2U(SCH_1):GND
  AR13  GND            VSS283  @S9S_MB_2U_LIB.S9S_MB_2U(SCH_1):GND
  AR1  GND            VSS282  @S9S_MB_2U_LIB.S9S_MB_2U(SCH_1):GND
  AP91  GND            VSS281  @S9S_MB_2U_LIB.S9S_MB_2U(SCH_1):GND
  AP87  GND            VSS280  @S9S_MB_2U_LIB.S9S_MB_2U(SCH_1):GND
  AP83  GND            VSS279  @S9S_MB_2U_LIB.S9S_MB_2U(SCH_1):GND
  AP8  GND            VSS278  @S9S_MB_2U_LIB.S9S_MB_2U(SCH_1):GND
  AP79  GND            VSS277  @S9S_MB_2U_LIB.S9S_MB_2U(SCH_1):GND
  AP73  GND            VSS276  @S9S_MB_2U_LIB.S9S_MB_2U(SCH_1):GND
  AP67  GND            VSS275  @S9S_MB_2U_LIB.S9S_MB_2U(SCH_1):GND
  AP61  GND            VSS274  @S9S_MB_2U_LIB.S9S_MB_2U(SCH_1):GND
  AP55  GND            VSS273  @S9S_MB_2U_LIB.S9S_MB_2U(SCH_1):GND
  AP49  GND            VSS272  @S9S_MB_2U_LIB.S9S_MB_2U(SCH_1):GND
  AP42  GND            VSS271  @S9S_MB_2U_LIB.S9S_MB_2U(SCH_1):GND
  AP4  GND            VSS270  @S9S_MB_2U_LIB.S9S_MB_2U(SCH_1):GND
  AP36  GND            VSS269  @S9S_MB_2U_LIB.S9S_MB_2U(SCH_1):GND
  AP30  GND            VSS268  @S9S_MB_2U_LIB.S9S_MB_2U(SCH_1):GND
  AP24  GND            VSS267  @S9S_MB_2U_LIB.S9S_MB_2U(SCH_1):GND
  AP18  GND            VSS266  @S9S_MB_2U_LIB.S9S_MB_2U(SCH_1):GND
  AP16  GND            VSS265  @S9S_MB_2U_LIB.S9S_MB_2U(SCH_1):GND
  AP12  GND            VSS264  @S9S_MB_2U_LIB.S9S_MB_2U(SCH_1):GND
  AN88  GND            VSS263  @S9S_MB_2U_LIB.S9S_MB_2U(SCH_1):GND
  AN84  GND            VSS262  @S9S_MB_2U_LIB.S9S_MB_2U(SCH_1):GND
  AN52  GND            VSS261  @S9S_MB_2U_LIB.S9S_MB_2U(SCH_1):GND
  AM8  GND            VSS260  @S9S_MB_2U_LIB.S9S_MB_2U(SCH_1):GND
  AM77  GND            VSS259  @S9S_MB_2U_LIB.S9S_MB_2U(SCH_1):GND
  AM75  GND            VSS258  @S9S_MB_2U_LIB.S9S_MB_2U(SCH_1):GND
  AM73  GND            VSS257  @S9S_MB_2U_LIB.S9S_MB_2U(SCH_1):GND
  AM71  GND            VSS256  @S9S_MB_2U_LIB.S9S_MB_2U(SCH_1):GND
  AM69  GND            VSS255  @S9S_MB_2U_LIB.S9S_MB_2U(SCH_1):GND
  AM67  GND            VSS254  @S9S_MB_2U_LIB.S9S_MB_2U(SCH_1):GND
  AM65  GND            VSS253  @S9S_MB_2U_LIB.S9S_MB_2U(SCH_1):GND
  AM63  GND            VSS252  @S9S_MB_2U_LIB.S9S_MB_2U(SCH_1):GND
  AM61  GND            VSS251  @S9S_MB_2U_LIB.S9S_MB_2U(SCH_1):GND
  AM59  GND            VSS250  @S9S_MB_2U_LIB.S9S_MB_2U(SCH_1):GND
  AM57  GND            VSS249  @S9S_MB_2U_LIB.S9S_MB_2U(SCH_1):GND
  AM55  GND            VSS248  @S9S_MB_2U_LIB.S9S_MB_2U(SCH_1):GND
  AM53  GND            VSS247  @S9S_MB_2U_LIB.S9S_MB_2U(SCH_1):GND
  AM51  GND            VSS246  @S9S_MB_2U_LIB.S9S_MB_2U(SCH_1):GND
  AM49  GND            VSS245  @S9S_MB_2U_LIB.S9S_MB_2U(SCH_1):GND
  AM47  GND            VSS244  @S9S_MB_2U_LIB.S9S_MB_2U(SCH_1):GND
  AM44  GND            VSS243  @S9S_MB_2U_LIB.S9S_MB_2U(SCH_1):GND
  AM42  GND            VSS242  @S9S_MB_2U_LIB.S9S_MB_2U(SCH_1):GND
  AM40  GND            VSS241  @S9S_MB_2U_LIB.S9S_MB_2U(SCH_1):GND
  AM4  GND            VSS240  @S9S_MB_2U_LIB.S9S_MB_2U(SCH_1):GND
  AM38  GND            VSS239  @S9S_MB_2U_LIB.S9S_MB_2U(SCH_1):GND
  AM36  GND            VSS238  @S9S_MB_2U_LIB.S9S_MB_2U(SCH_1):GND
  AM34  GND            VSS237  @S9S_MB_2U_LIB.S9S_MB_2U(SCH_1):GND
  AM32  GND            VSS236  @S9S_MB_2U_LIB.S9S_MB_2U(SCH_1):GND
  AM30  GND            VSS235  @S9S_MB_2U_LIB.S9S_MB_2U(SCH_1):GND
  AM28  GND            VSS234  @S9S_MB_2U_LIB.S9S_MB_2U(SCH_1):GND
  AM26  GND            VSS233  @S9S_MB_2U_LIB.S9S_MB_2U(SCH_1):GND
  AM24  GND            VSS232  @S9S_MB_2U_LIB.S9S_MB_2U(SCH_1):GND
  AM22  GND            VSS231  @S9S_MB_2U_LIB.S9S_MB_2U(SCH_1):GND
  AM20  GND            VSS230  @S9S_MB_2U_LIB.S9S_MB_2U(SCH_1):GND
  AM18  GND            VSS229  @S9S_MB_2U_LIB.S9S_MB_2U(SCH_1):GND
  AM16  GND            VSS228  @S9S_MB_2U_LIB.S9S_MB_2U(SCH_1):GND
  AM12  GND            VSS227  @S9S_MB_2U_LIB.S9S_MB_2U(SCH_1):GND
  AL9  GND            VSS226  @S9S_MB_2U_LIB.S9S_MB_2U(SCH_1):GND
  AL88  GND            VSS225  @S9S_MB_2U_LIB.S9S_MB_2U(SCH_1):GND
  AL84  GND            VSS224  @S9S_MB_2U_LIB.S9S_MB_2U(SCH_1):GND
  AL82  GND            VSS223  @S9S_MB_2U_LIB.S9S_MB_2U(SCH_1):GND
  AL80  GND            VSS222  @S9S_MB_2U_LIB.S9S_MB_2U(SCH_1):GND
  AL52  GND            VSS221  @S9S_MB_2U_LIB.S9S_MB_2U(SCH_1):GND
  AL5  GND            VSS220  @S9S_MB_2U_LIB.S9S_MB_2U(SCH_1):GND
  AL17  GND            VSS219  @S9S_MB_2U_LIB.S9S_MB_2U(SCH_1):GND
  AL13  GND            VSS218  @S9S_MB_2U_LIB.S9S_MB_2U(SCH_1):GND
  AL1  GND            VSS217  @S9S_MB_2U_LIB.S9S_MB_2U(SCH_1):GND
  AK91  GND            VSS216  @S9S_MB_2U_LIB.S9S_MB_2U(SCH_1):GND
  AK87  GND            VSS215  @S9S_MB_2U_LIB.S9S_MB_2U(SCH_1):GND
  AK83  GND            VSS214  @S9S_MB_2U_LIB.S9S_MB_2U(SCH_1):GND
  AK81  GND            VSS213  @S9S_MB_2U_LIB.S9S_MB_2U(SCH_1):GND
  AK8  GND            VSS212  @S9S_MB_2U_LIB.S9S_MB_2U(SCH_1):GND
  AK79  GND            VSS211  @S9S_MB_2U_LIB.S9S_MB_2U(SCH_1):GND
  AK73  GND            VSS210  @S9S_MB_2U_LIB.S9S_MB_2U(SCH_1):GND
  AK67  GND            VSS209  @S9S_MB_2U_LIB.S9S_MB_2U(SCH_1):GND
  AK61  GND            VSS208  @S9S_MB_2U_LIB.S9S_MB_2U(SCH_1):GND
  AK55  GND            VSS207  @S9S_MB_2U_LIB.S9S_MB_2U(SCH_1):GND
  AK49  GND            VSS206  @S9S_MB_2U_LIB.S9S_MB_2U(SCH_1):GND
  AK42  GND            VSS205  @S9S_MB_2U_LIB.S9S_MB_2U(SCH_1):GND
  AK4  GND            VSS204  @S9S_MB_2U_LIB.S9S_MB_2U(SCH_1):GND
  AK36  GND            VSS203  @S9S_MB_2U_LIB.S9S_MB_2U(SCH_1):GND
  AK30  GND            VSS202  @S9S_MB_2U_LIB.S9S_MB_2U(SCH_1):GND
  AK24  GND            VSS201  @S9S_MB_2U_LIB.S9S_MB_2U(SCH_1):GND
  AK18  GND            VSS200  @S9S_MB_2U_LIB.S9S_MB_2U(SCH_1):GND
  AK16  GND            VSS199  @S9S_MB_2U_LIB.S9S_MB_2U(SCH_1):GND
  AK12  GND            VSS198  @S9S_MB_2U_LIB.S9S_MB_2U(SCH_1):GND

SOCKET4677_AZIFS054P001C01  I9   U2     [SOCKET4677_AZIFS054P001C01-SOCA]
  BR9  GND            VSS572  @S9S_MB_2U_LIB.S9S_MB_2U(SCH_1):GND
  BR33  GND            VSS541  @S9S_MB_2U_LIB.S9S_MB_2U(SCH_1):GND
  BR31  GND            VSS540  @S9S_MB_2U_LIB.S9S_MB_2U(SCH_1):GND
  BR29  GND            VSS539  @S9S_MB_2U_LIB.S9S_MB_2U(SCH_1):GND
  BR27  GND            VSS538  @S9S_MB_2U_LIB.S9S_MB_2U(SCH_1):GND
  BR17  GND            VSS536  @S9S_MB_2U_LIB.S9S_MB_2U(SCH_1):GND
  BR13  GND            VSS535  @S9S_MB_2U_LIB.S9S_MB_2U(SCH_1):GND
  BP8  GND            VSS533  @S9S_MB_2U_LIB.S9S_MB_2U(SCH_1):GND
  BP77  GND            VSS532  @S9S_MB_2U_LIB.S9S_MB_2U(SCH_1):GND
  BP75  GND            VSS531  @S9S_MB_2U_LIB.S9S_MB_2U(SCH_1):GND
  BP73  GND            VSS530  @S9S_MB_2U_LIB.S9S_MB_2U(SCH_1):GND
  BP71  GND            VSS529  @S9S_MB_2U_LIB.S9S_MB_2U(SCH_1):GND
  BP63  GND            VSS528  @S9S_MB_2U_LIB.S9S_MB_2U(SCH_1):GND
  BP4  GND            VSS527  @S9S_MB_2U_LIB.S9S_MB_2U(SCH_1):GND
  BP20  GND            VSS525  @S9S_MB_2U_LIB.S9S_MB_2U(SCH_1):GND
  BP2  GND            VSS524  @S9S_MB_2U_LIB.S9S_MB_2U(SCH_1):GND
  BP16  GND            VSS523  @S9S_MB_2U_LIB.S9S_MB_2U(SCH_1):GND
  BP12  GND            VSS522  @S9S_MB_2U_LIB.S9S_MB_2U(SCH_1):GND
  BN70  GND            VSS520  @S9S_MB_2U_LIB.S9S_MB_2U(SCH_1):GND
  BN62  GND            VSS519  @S9S_MB_2U_LIB.S9S_MB_2U(SCH_1):GND
  BN31  GND            VSS518  @S9S_MB_2U_LIB.S9S_MB_2U(SCH_1):GND
  BM8  GND            VSS517  @S9S_MB_2U_LIB.S9S_MB_2U(SCH_1):GND
  BM77  GND            VSS516  @S9S_MB_2U_LIB.S9S_MB_2U(SCH_1):GND
  BM73  GND            VSS515  @S9S_MB_2U_LIB.S9S_MB_2U(SCH_1):GND
  BM61  GND            VSS513  @S9S_MB_2U_LIB.S9S_MB_2U(SCH_1):GND
  BM4  GND            VSS512  @S9S_MB_2U_LIB.S9S_MB_2U(SCH_1):GND
  BM26  GND            VSS511  @S9S_MB_2U_LIB.S9S_MB_2U(SCH_1):GND
  BM24  GND            VSS510  @S9S_MB_2U_LIB.S9S_MB_2U(SCH_1):GND
  BM22  GND            VSS509  @S9S_MB_2U_LIB.S9S_MB_2U(SCH_1):GND
  BM20  GND            VSS508  @S9S_MB_2U_LIB.S9S_MB_2U(SCH_1):GND
  BM16  GND            VSS507  @S9S_MB_2U_LIB.S9S_MB_2U(SCH_1):GND
  BM12  GND            VSS506  @S9S_MB_2U_LIB.S9S_MB_2U(SCH_1):GND
  BL9  GND            VSS505  @S9S_MB_2U_LIB.S9S_MB_2U(SCH_1):GND
  BL78  GND            VSS504  @S9S_MB_2U_LIB.S9S_MB_2U(SCH_1):GND
  BL72  GND            VSS503  @S9S_MB_2U_LIB.S9S_MB_2U(SCH_1):GND
  BL70  GND            VSS502  @S9S_MB_2U_LIB.S9S_MB_2U(SCH_1):GND
  BL68  GND            VSS501  @S9S_MB_2U_LIB.S9S_MB_2U(SCH_1):GND
  BL5  GND            VSS500  @S9S_MB_2U_LIB.S9S_MB_2U(SCH_1):GND
  BL17  GND            VSS499  @S9S_MB_2U_LIB.S9S_MB_2U(SCH_1):GND
  BL13  GND            VSS498  @S9S_MB_2U_LIB.S9S_MB_2U(SCH_1):GND
  BL1  GND            VSS497  @S9S_MB_2U_LIB.S9S_MB_2U(SCH_1):GND
  BK8  GND            VSS496  @S9S_MB_2U_LIB.S9S_MB_2U(SCH_1):GND
  BK79  GND            VSS495  @S9S_MB_2U_LIB.S9S_MB_2U(SCH_1):GND
  BK75  GND            VSS494  @S9S_MB_2U_LIB.S9S_MB_2U(SCH_1):GND
  BK71  GND            VSS492  @S9S_MB_2U_LIB.S9S_MB_2U(SCH_1):GND
  BK65  GND            VSS491  @S9S_MB_2U_LIB.S9S_MB_2U(SCH_1):GND
  BK4  GND            VSS490  @S9S_MB_2U_LIB.S9S_MB_2U(SCH_1):GND
  BK20  GND            VSS489  @S9S_MB_2U_LIB.S9S_MB_2U(SCH_1):GND
  BK16  GND            VSS488  @S9S_MB_2U_LIB.S9S_MB_2U(SCH_1):GND
  BK12  GND            VSS487  @S9S_MB_2U_LIB.S9S_MB_2U(SCH_1):GND
  BJ90  GND            VSS486  @S9S_MB_2U_LIB.S9S_MB_2U(SCH_1):GND
  BJ88  GND            VSS485  @S9S_MB_2U_LIB.S9S_MB_2U(SCH_1):GND
  BJ86  GND            VSS484  @S9S_MB_2U_LIB.S9S_MB_2U(SCH_1):GND
  BJ84  GND            VSS483  @S9S_MB_2U_LIB.S9S_MB_2U(SCH_1):GND
  BJ82  GND            VSS482  @S9S_MB_2U_LIB.S9S_MB_2U(SCH_1):GND
  BJ80  GND            VSS481  @S9S_MB_2U_LIB.S9S_MB_2U(SCH_1):GND
  BJ68  GND            VSS480  @S9S_MB_2U_LIB.S9S_MB_2U(SCH_1):GND
  BJ62  GND            VSS479  @S9S_MB_2U_LIB.S9S_MB_2U(SCH_1):GND
  BH83  GND            VSS477  @S9S_MB_2U_LIB.S9S_MB_2U(SCH_1):GND
  BH81  GND            VSS476  @S9S_MB_2U_LIB.S9S_MB_2U(SCH_1):GND
  BH8  GND            VSS475  @S9S_MB_2U_LIB.S9S_MB_2U(SCH_1):GND
  BH77  GND            VSS474  @S9S_MB_2U_LIB.S9S_MB_2U(SCH_1):GND
  BH73  GND            VSS473  @S9S_MB_2U_LIB.S9S_MB_2U(SCH_1):GND
  BH67  GND            VSS472  @S9S_MB_2U_LIB.S9S_MB_2U(SCH_1):GND
  BH4  GND            VSS470  @S9S_MB_2U_LIB.S9S_MB_2U(SCH_1):GND
  BH20  GND            VSS469  @S9S_MB_2U_LIB.S9S_MB_2U(SCH_1):GND
  BH16  GND            VSS468  @S9S_MB_2U_LIB.S9S_MB_2U(SCH_1):GND
  BH12  GND            VSS467  @S9S_MB_2U_LIB.S9S_MB_2U(SCH_1):GND
  BG9  GND            VSS466  @S9S_MB_2U_LIB.S9S_MB_2U(SCH_1):GND
  BG70  GND            VSS465  @S9S_MB_2U_LIB.S9S_MB_2U(SCH_1):GND
  BG5  GND            VSS464  @S9S_MB_2U_LIB.S9S_MB_2U(SCH_1):GND
  BG25  GND            VSS463  @S9S_MB_2U_LIB.S9S_MB_2U(SCH_1):GND
  BG23  GND            VSS462  @S9S_MB_2U_LIB.S9S_MB_2U(SCH_1):GND
  BG21  GND            VSS461  @S9S_MB_2U_LIB.S9S_MB_2U(SCH_1):GND
  BG17  GND            VSS460  @S9S_MB_2U_LIB.S9S_MB_2U(SCH_1):GND
  BG13  GND            VSS459  @S9S_MB_2U_LIB.S9S_MB_2U(SCH_1):GND
  BG1  GND            VSS458  @S9S_MB_2U_LIB.S9S_MB_2U(SCH_1):GND
  BF83  GND            VSS457  @S9S_MB_2U_LIB.S9S_MB_2U(SCH_1):GND
  BF8  GND            VSS456  @S9S_MB_2U_LIB.S9S_MB_2U(SCH_1):GND
  BF79  GND            VSS455  @S9S_MB_2U_LIB.S9S_MB_2U(SCH_1):GND
  BF75  GND            VSS454  @S9S_MB_2U_LIB.S9S_MB_2U(SCH_1):GND
  BF73  GND            VSS453  @S9S_MB_2U_LIB.S9S_MB_2U(SCH_1):GND
  BF63  GND            VSS452  @S9S_MB_2U_LIB.S9S_MB_2U(SCH_1):GND
  BF61  GND            VSS451  @S9S_MB_2U_LIB.S9S_MB_2U(SCH_1):GND
  BF4  GND            VSS450  @S9S_MB_2U_LIB.S9S_MB_2U(SCH_1):GND
  BF20  GND            VSS449  @S9S_MB_2U_LIB.S9S_MB_2U(SCH_1):GND
  BF16  GND            VSS448  @S9S_MB_2U_LIB.S9S_MB_2U(SCH_1):GND
  BF12  GND            VSS447  @S9S_MB_2U_LIB.S9S_MB_2U(SCH_1):GND
  BE84  GND            VSS446  @S9S_MB_2U_LIB.S9S_MB_2U(SCH_1):GND
  BE78  GND            VSS445  @S9S_MB_2U_LIB.S9S_MB_2U(SCH_1):GND
  BE76  GND            VSS444  @S9S_MB_2U_LIB.S9S_MB_2U(SCH_1):GND
  BE74  GND            VSS443  @S9S_MB_2U_LIB.S9S_MB_2U(SCH_1):GND
  BE68  GND            VSS442  @S9S_MB_2U_LIB.S9S_MB_2U(SCH_1):GND
  BE66  GND            VSS441  @S9S_MB_2U_LIB.S9S_MB_2U(SCH_1):GND
  BE64  GND            VSS440  @S9S_MB_2U_LIB.S9S_MB_2U(SCH_1):GND
  BD89  GND            VSS439  @S9S_MB_2U_LIB.S9S_MB_2U(SCH_1):GND
  BD85  GND            VSS437  @S9S_MB_2U_LIB.S9S_MB_2U(SCH_1):GND
  BD81  GND            VSS435  @S9S_MB_2U_LIB.S9S_MB_2U(SCH_1):GND
  BD8  GND            VSS434  @S9S_MB_2U_LIB.S9S_MB_2U(SCH_1):GND
  BD4  GND            VSS433  @S9S_MB_2U_LIB.S9S_MB_2U(SCH_1):GND
  BD20  GND            VSS432  @S9S_MB_2U_LIB.S9S_MB_2U(SCH_1):GND
  BD16  GND            VSS431  @S9S_MB_2U_LIB.S9S_MB_2U(SCH_1):GND
  BD12  GND            VSS430  @S9S_MB_2U_LIB.S9S_MB_2U(SCH_1):GND
  BC9  GND            VSS429  @S9S_MB_2U_LIB.S9S_MB_2U(SCH_1):GND
  BC88  GND            VSS428  @S9S_MB_2U_LIB.S9S_MB_2U(SCH_1):GND
  BC86  GND            VSS427  @S9S_MB_2U_LIB.S9S_MB_2U(SCH_1):GND
  BC84  GND            VSS426  @S9S_MB_2U_LIB.S9S_MB_2U(SCH_1):GND
  BC78  GND            VSS425  @S9S_MB_2U_LIB.S9S_MB_2U(SCH_1):GND
  BC76  GND            VSS424  @S9S_MB_2U_LIB.S9S_MB_2U(SCH_1):GND
  BC72  GND            VSS423  @S9S_MB_2U_LIB.S9S_MB_2U(SCH_1):GND
  BC66  GND            VSS422  @S9S_MB_2U_LIB.S9S_MB_2U(SCH_1):GND
  BC62  GND            VSS421  @S9S_MB_2U_LIB.S9S_MB_2U(SCH_1):GND
  BC5  GND            VSS420  @S9S_MB_2U_LIB.S9S_MB_2U(SCH_1):GND
  BC17  GND            VSS419  @S9S_MB_2U_LIB.S9S_MB_2U(SCH_1):GND
  BC13  GND            VSS418  @S9S_MB_2U_LIB.S9S_MB_2U(SCH_1):GND
  BC1  GND            VSS417  @S9S_MB_2U_LIB.S9S_MB_2U(SCH_1):GND
  BB91  GND            VSS416  @S9S_MB_2U_LIB.S9S_MB_2U(SCH_1):GND
  BB87  GND            VSS415  @S9S_MB_2U_LIB.S9S_MB_2U(SCH_1):GND
  BB83  GND            VSS414  @S9S_MB_2U_LIB.S9S_MB_2U(SCH_1):GND
  BB8  GND            VSS413  @S9S_MB_2U_LIB.S9S_MB_2U(SCH_1):GND
  BB79  GND            VSS412  @S9S_MB_2U_LIB.S9S_MB_2U(SCH_1):GND
  BB77  GND            VSS411  @S9S_MB_2U_LIB.S9S_MB_2U(SCH_1):GND
  BB71  GND            VSS410  @S9S_MB_2U_LIB.S9S_MB_2U(SCH_1):GND
  BB69  GND            VSS409  @S9S_MB_2U_LIB.S9S_MB_2U(SCH_1):GND
  BB63  GND            VSS408  @S9S_MB_2U_LIB.S9S_MB_2U(SCH_1):GND
  BB4  GND            VSS407  @S9S_MB_2U_LIB.S9S_MB_2U(SCH_1):GND
  BB26  GND            VSS406  @S9S_MB_2U_LIB.S9S_MB_2U(SCH_1):GND
  BB24  GND            VSS405  @S9S_MB_2U_LIB.S9S_MB_2U(SCH_1):GND
  BB22  GND            VSS404  @S9S_MB_2U_LIB.S9S_MB_2U(SCH_1):GND
  BB20  GND            VSS403  @S9S_MB_2U_LIB.S9S_MB_2U(SCH_1):GND
  BB16  GND            VSS402  @S9S_MB_2U_LIB.S9S_MB_2U(SCH_1):GND
  BB12  GND            VSS401  @S9S_MB_2U_LIB.S9S_MB_2U(SCH_1):GND
  BB10  GND            VSS400  @S9S_MB_2U_LIB.S9S_MB_2U(SCH_1):GND
  BA88  GND            VSS399  @S9S_MB_2U_LIB.S9S_MB_2U(SCH_1):GND
  BA84  GND            VSS398  @S9S_MB_2U_LIB.S9S_MB_2U(SCH_1):GND
  BA74  GND            VSS397  @S9S_MB_2U_LIB.S9S_MB_2U(SCH_1):GND
  BA64  GND            VSS395  @S9S_MB_2U_LIB.S9S_MB_2U(SCH_1):GND
  BA60  GND            VSS394  @S9S_MB_2U_LIB.S9S_MB_2U(SCH_1):GND
  BA17  GND            VSS393  @S9S_MB_2U_LIB.S9S_MB_2U(SCH_1):GND
  AY83  GND            VSS377  @S9S_MB_2U_LIB.S9S_MB_2U(SCH_1):GND
  AY81  GND            VSS376  @S9S_MB_2U_LIB.S9S_MB_2U(SCH_1):GND
  AY8  GND            VSS375  @S9S_MB_2U_LIB.S9S_MB_2U(SCH_1):GND
  AY79  GND            VSS374  @S9S_MB_2U_LIB.S9S_MB_2U(SCH_1):GND
  AY77  GND            VSS373  @S9S_MB_2U_LIB.S9S_MB_2U(SCH_1):GND
  AY71  GND            VSS372  @S9S_MB_2U_LIB.S9S_MB_2U(SCH_1):GND
  AY4  GND            VSS371  @S9S_MB_2U_LIB.S9S_MB_2U(SCH_1):GND
  AY16  GND            VSS370  @S9S_MB_2U_LIB.S9S_MB_2U(SCH_1):GND
  AY12  GND            VSS369  @S9S_MB_2U_LIB.S9S_MB_2U(SCH_1):GND
  AW88  GND            VSS367  @S9S_MB_2U_LIB.S9S_MB_2U(SCH_1):GND
  AW84  GND            VSS366  @S9S_MB_2U_LIB.S9S_MB_2U(SCH_1):GND
  AW82  GND            VSS365  @S9S_MB_2U_LIB.S9S_MB_2U(SCH_1):GND
  AW80  GND            VSS364  @S9S_MB_2U_LIB.S9S_MB_2U(SCH_1):GND
  AW72  GND            VSS363  @S9S_MB_2U_LIB.S9S_MB_2U(SCH_1):GND
  AW68  GND            VSS362  @S9S_MB_2U_LIB.S9S_MB_2U(SCH_1):GND
  AW66  GND            VSS361  @S9S_MB_2U_LIB.S9S_MB_2U(SCH_1):GND
  AW62  GND            VSS360  @S9S_MB_2U_LIB.S9S_MB_2U(SCH_1):GND
  AW25  GND            VSS358  @S9S_MB_2U_LIB.S9S_MB_2U(SCH_1):GND
  AW23  GND            VSS357  @S9S_MB_2U_LIB.S9S_MB_2U(SCH_1):GND
  AW21  GND            VSS356  @S9S_MB_2U_LIB.S9S_MB_2U(SCH_1):GND
  BR5  GND             VSS0  @S9S_MB_2U_LIB.S9S_MB_2U(SCH_1):GND

SOCKET4677_AZIFS054P001C01  I12  U2     [SOCKET4677_AZIFS054P001C01-SOCA]
  CK8  GND            VSS746  @S9S_MB_2U_LIB.S9S_MB_2U(SCH_1):GND
  CK26  GND            VSS743  @S9S_MB_2U_LIB.S9S_MB_2U(SCH_1):GND
  CK20  GND            VSS742  @S9S_MB_2U_LIB.S9S_MB_2U(SCH_1):GND
  CK16  GND            VSS741  @S9S_MB_2U_LIB.S9S_MB_2U(SCH_1):GND
  CK12  GND            VSS740  @S9S_MB_2U_LIB.S9S_MB_2U(SCH_1):GND
  CJ80  GND            VSS737  @S9S_MB_2U_LIB.S9S_MB_2U(SCH_1):GND
  CJ60  GND            VSS736  @S9S_MB_2U_LIB.S9S_MB_2U(SCH_1):GND
  CH89  GND            VSS734  @S9S_MB_2U_LIB.S9S_MB_2U(SCH_1):GND
  CH87  GND            VSS733  @S9S_MB_2U_LIB.S9S_MB_2U(SCH_1):GND
  CH85  GND            VSS732  @S9S_MB_2U_LIB.S9S_MB_2U(SCH_1):GND
  CH83  GND            VSS731  @S9S_MB_2U_LIB.S9S_MB_2U(SCH_1):GND
  CH8  GND            VSS730  @S9S_MB_2U_LIB.S9S_MB_2U(SCH_1):GND
  CH79  GND            VSS729  @S9S_MB_2U_LIB.S9S_MB_2U(SCH_1):GND
  CH73  GND            VSS728  @S9S_MB_2U_LIB.S9S_MB_2U(SCH_1):GND
  CH67  GND            VSS727  @S9S_MB_2U_LIB.S9S_MB_2U(SCH_1):GND
  CH4  GND            VSS722  @S9S_MB_2U_LIB.S9S_MB_2U(SCH_1):GND
  CH20  GND            VSS721  @S9S_MB_2U_LIB.S9S_MB_2U(SCH_1):GND
  CH16  GND            VSS720  @S9S_MB_2U_LIB.S9S_MB_2U(SCH_1):GND
  CH12  GND            VSS718  @S9S_MB_2U_LIB.S9S_MB_2U(SCH_1):GND
  CG9  GND            VSS716  @S9S_MB_2U_LIB.S9S_MB_2U(SCH_1):GND
  CG78  GND            VSS713  @S9S_MB_2U_LIB.S9S_MB_2U(SCH_1):GND
  CG74  GND            VSS710  @S9S_MB_2U_LIB.S9S_MB_2U(SCH_1):GND
  CG72  GND            VSS708  @S9S_MB_2U_LIB.S9S_MB_2U(SCH_1):GND
  CG70  GND            VSS707  @S9S_MB_2U_LIB.S9S_MB_2U(SCH_1):GND
  CG64  GND            VSS706  @S9S_MB_2U_LIB.S9S_MB_2U(SCH_1):GND
  CG62  GND            VSS704  @S9S_MB_2U_LIB.S9S_MB_2U(SCH_1):GND
  CG5  GND            VSS703  @S9S_MB_2U_LIB.S9S_MB_2U(SCH_1):GND
  CG25  GND            VSS701  @S9S_MB_2U_LIB.S9S_MB_2U(SCH_1):GND
  CG23  GND            VSS698  @S9S_MB_2U_LIB.S9S_MB_2U(SCH_1):GND
  CG21  GND            VSS697  @S9S_MB_2U_LIB.S9S_MB_2U(SCH_1):GND
  CG17  GND            VSS696  @S9S_MB_2U_LIB.S9S_MB_2U(SCH_1):GND
  CG13  GND            VSS695  @S9S_MB_2U_LIB.S9S_MB_2U(SCH_1):GND
  CG1  GND            VSS694  @S9S_MB_2U_LIB.S9S_MB_2U(SCH_1):GND
  CF8  GND            VSS693  @S9S_MB_2U_LIB.S9S_MB_2U(SCH_1):GND
  CF71  GND            VSS692  @S9S_MB_2U_LIB.S9S_MB_2U(SCH_1):GND
  CF69  GND            VSS691  @S9S_MB_2U_LIB.S9S_MB_2U(SCH_1):GND
  CF4  GND            VSS689  @S9S_MB_2U_LIB.S9S_MB_2U(SCH_1):GND
  CF20  GND            VSS688  @S9S_MB_2U_LIB.S9S_MB_2U(SCH_1):GND
  CF16  GND            VSS687  @S9S_MB_2U_LIB.S9S_MB_2U(SCH_1):GND
  CF12  GND            VSS686  @S9S_MB_2U_LIB.S9S_MB_2U(SCH_1):GND
  CE78  GND            VSS685  @S9S_MB_2U_LIB.S9S_MB_2U(SCH_1):GND
  CE76  GND            VSS684  @S9S_MB_2U_LIB.S9S_MB_2U(SCH_1):GND
  CE72  GND            VSS683  @S9S_MB_2U_LIB.S9S_MB_2U(SCH_1):GND
  CE66  GND            VSS682  @S9S_MB_2U_LIB.S9S_MB_2U(SCH_1):GND
  CE60  GND            VSS681  @S9S_MB_2U_LIB.S9S_MB_2U(SCH_1):GND
  CE3  GND            VSS680  @S9S_MB_2U_LIB.S9S_MB_2U(SCH_1):GND
  CD8  GND            VSS678  @S9S_MB_2U_LIB.S9S_MB_2U(SCH_1):GND
  CD77  GND            VSS677  @S9S_MB_2U_LIB.S9S_MB_2U(SCH_1):GND
  CD75  GND            VSS676  @S9S_MB_2U_LIB.S9S_MB_2U(SCH_1):GND
  CD61  GND            VSS675  @S9S_MB_2U_LIB.S9S_MB_2U(SCH_1):GND
  CD4  GND            VSS674  @S9S_MB_2U_LIB.S9S_MB_2U(SCH_1):GND
  CD20  GND            VSS673  @S9S_MB_2U_LIB.S9S_MB_2U(SCH_1):GND
  CD16  GND            VSS672  @S9S_MB_2U_LIB.S9S_MB_2U(SCH_1):GND
  CD12  GND            VSS671  @S9S_MB_2U_LIB.S9S_MB_2U(SCH_1):GND
  CC9  GND            VSS670  @S9S_MB_2U_LIB.S9S_MB_2U(SCH_1):GND
  CC74  GND            VSS669  @S9S_MB_2U_LIB.S9S_MB_2U(SCH_1):GND
  CC72  GND            VSS668  @S9S_MB_2U_LIB.S9S_MB_2U(SCH_1):GND
  CC70  GND            VSS667  @S9S_MB_2U_LIB.S9S_MB_2U(SCH_1):GND
  CC62  GND            VSS666  @S9S_MB_2U_LIB.S9S_MB_2U(SCH_1):GND
  CC5  GND            VSS665  @S9S_MB_2U_LIB.S9S_MB_2U(SCH_1):GND
  CC31  GND            VSS664  @S9S_MB_2U_LIB.S9S_MB_2U(SCH_1):GND
  CC17  GND            VSS661  @S9S_MB_2U_LIB.S9S_MB_2U(SCH_1):GND
  CC13  GND            VSS660  @S9S_MB_2U_LIB.S9S_MB_2U(SCH_1):GND
  CB89  GND            VSS656  @S9S_MB_2U_LIB.S9S_MB_2U(SCH_1):GND
  CB87  GND            VSS655  @S9S_MB_2U_LIB.S9S_MB_2U(SCH_1):GND
  CB85  GND            VSS654  @S9S_MB_2U_LIB.S9S_MB_2U(SCH_1):GND
  CB83  GND            VSS653  @S9S_MB_2U_LIB.S9S_MB_2U(SCH_1):GND
  CB81  GND            VSS652  @S9S_MB_2U_LIB.S9S_MB_2U(SCH_1):GND
  CB8  GND            VSS651  @S9S_MB_2U_LIB.S9S_MB_2U(SCH_1):GND
  CB79  GND            VSS650  @S9S_MB_2U_LIB.S9S_MB_2U(SCH_1):GND
  CB73  GND            VSS649  @S9S_MB_2U_LIB.S9S_MB_2U(SCH_1):GND
  CB71  GND            VSS648  @S9S_MB_2U_LIB.S9S_MB_2U(SCH_1):GND
  CB69  GND            VSS647  @S9S_MB_2U_LIB.S9S_MB_2U(SCH_1):GND
  CB67  GND            VSS646  @S9S_MB_2U_LIB.S9S_MB_2U(SCH_1):GND
  CB65  GND            VSS645  @S9S_MB_2U_LIB.S9S_MB_2U(SCH_1):GND
  CB63  GND            VSS644  @S9S_MB_2U_LIB.S9S_MB_2U(SCH_1):GND
  CB59  GND            VSS643  @S9S_MB_2U_LIB.S9S_MB_2U(SCH_1):GND
  CB57  GND            VSS642  @S9S_MB_2U_LIB.S9S_MB_2U(SCH_1):GND
  CB55  GND            VSS641  @S9S_MB_2U_LIB.S9S_MB_2U(SCH_1):GND
  CB53  GND            VSS640  @S9S_MB_2U_LIB.S9S_MB_2U(SCH_1):GND
  CB51  GND            VSS639  @S9S_MB_2U_LIB.S9S_MB_2U(SCH_1):GND
  CB49  GND            VSS638  @S9S_MB_2U_LIB.S9S_MB_2U(SCH_1):GND
  CB47  GND            VSS637  @S9S_MB_2U_LIB.S9S_MB_2U(SCH_1):GND
  CB44  GND            VSS636  @S9S_MB_2U_LIB.S9S_MB_2U(SCH_1):GND
  CB42  GND            VSS635  @S9S_MB_2U_LIB.S9S_MB_2U(SCH_1):GND
  CB40  GND            VSS634  @S9S_MB_2U_LIB.S9S_MB_2U(SCH_1):GND
  CB4  GND            VSS633  @S9S_MB_2U_LIB.S9S_MB_2U(SCH_1):GND
  CB38  GND            VSS632  @S9S_MB_2U_LIB.S9S_MB_2U(SCH_1):GND
  CB36  GND            VSS631  @S9S_MB_2U_LIB.S9S_MB_2U(SCH_1):GND
  CB34  GND            VSS630  @S9S_MB_2U_LIB.S9S_MB_2U(SCH_1):GND
  CB32  GND            VSS629  @S9S_MB_2U_LIB.S9S_MB_2U(SCH_1):GND
  CB28  GND            VSS628  @S9S_MB_2U_LIB.S9S_MB_2U(SCH_1):GND
  CB26  GND            VSS627  @S9S_MB_2U_LIB.S9S_MB_2U(SCH_1):GND
  CB24  GND            VSS626  @S9S_MB_2U_LIB.S9S_MB_2U(SCH_1):GND
  CB22  GND            VSS625  @S9S_MB_2U_LIB.S9S_MB_2U(SCH_1):GND
  CB20  GND            VSS624  @S9S_MB_2U_LIB.S9S_MB_2U(SCH_1):GND
  CB16  GND            VSS623  @S9S_MB_2U_LIB.S9S_MB_2U(SCH_1):GND
  CB12  GND            VSS622  @S9S_MB_2U_LIB.S9S_MB_2U(SCH_1):GND
  CA31  GND            VSS621  @S9S_MB_2U_LIB.S9S_MB_2U(SCH_1):GND
  CA3  GND            VSS620  @S9S_MB_2U_LIB.S9S_MB_2U(SCH_1):GND
  BY8  GND            VSS608  @S9S_MB_2U_LIB.S9S_MB_2U(SCH_1):GND
  BY4  GND            VSS607  @S9S_MB_2U_LIB.S9S_MB_2U(SCH_1):GND
  BY20  GND            VSS606  @S9S_MB_2U_LIB.S9S_MB_2U(SCH_1):GND
  BY16  GND            VSS605  @S9S_MB_2U_LIB.S9S_MB_2U(SCH_1):GND
  BY12  GND            VSS604  @S9S_MB_2U_LIB.S9S_MB_2U(SCH_1):GND
  BW9  GND            VSS603  @S9S_MB_2U_LIB.S9S_MB_2U(SCH_1):GND
  BW5  GND            VSS602  @S9S_MB_2U_LIB.S9S_MB_2U(SCH_1):GND
  BW31  GND            VSS601  @S9S_MB_2U_LIB.S9S_MB_2U(SCH_1):GND
  BW3  GND            VSS600  @S9S_MB_2U_LIB.S9S_MB_2U(SCH_1):GND
  BW29  GND            VSS599  @S9S_MB_2U_LIB.S9S_MB_2U(SCH_1):GND
  BW27  GND            VSS598  @S9S_MB_2U_LIB.S9S_MB_2U(SCH_1):GND
  BW17  GND            VSS597  @S9S_MB_2U_LIB.S9S_MB_2U(SCH_1):GND
  BW13  GND            VSS596  @S9S_MB_2U_LIB.S9S_MB_2U(SCH_1):GND
  BV8  GND            VSS594  @S9S_MB_2U_LIB.S9S_MB_2U(SCH_1):GND
  BV6  GND            VSS593  @S9S_MB_2U_LIB.S9S_MB_2U(SCH_1):GND
  BV4  GND            VSS592  @S9S_MB_2U_LIB.S9S_MB_2U(SCH_1):GND
  BV20  GND            VSS591  @S9S_MB_2U_LIB.S9S_MB_2U(SCH_1):GND
  BV2  GND            VSS590  @S9S_MB_2U_LIB.S9S_MB_2U(SCH_1):GND
  BV18  GND            VSS589  @S9S_MB_2U_LIB.S9S_MB_2U(SCH_1):GND
  BV16  GND            VSS588  @S9S_MB_2U_LIB.S9S_MB_2U(SCH_1):GND
  BV12  GND            VSS587  @S9S_MB_2U_LIB.S9S_MB_2U(SCH_1):GND
  BU7  GND            VSS586  @S9S_MB_2U_LIB.S9S_MB_2U(SCH_1):GND
  BU31  GND            VSS585  @S9S_MB_2U_LIB.S9S_MB_2U(SCH_1):GND
  BU25  GND            VSS584  @S9S_MB_2U_LIB.S9S_MB_2U(SCH_1):GND
  BU23  GND            VSS582  @S9S_MB_2U_LIB.S9S_MB_2U(SCH_1):GND
  BU21  GND            VSS581  @S9S_MB_2U_LIB.S9S_MB_2U(SCH_1):GND
  BU19  GND            VSS580  @S9S_MB_2U_LIB.S9S_MB_2U(SCH_1):GND
  BU15  GND            VSS579  @S9S_MB_2U_LIB.S9S_MB_2U(SCH_1):GND
  BT8  GND            VSS578  @S9S_MB_2U_LIB.S9S_MB_2U(SCH_1):GND
  BT4  GND            VSS577  @S9S_MB_2U_LIB.S9S_MB_2U(SCH_1):GND
  BT20  GND            VSS576  @S9S_MB_2U_LIB.S9S_MB_2U(SCH_1):GND
  BT16  GND            VSS575  @S9S_MB_2U_LIB.S9S_MB_2U(SCH_1):GND
  BT12  GND            VSS574  @S9S_MB_2U_LIB.S9S_MB_2U(SCH_1):GND
  BR90  GND            VSS573  @S9S_MB_2U_LIB.S9S_MB_2U(SCH_1):GND
  BR88  GND            VSS570  @S9S_MB_2U_LIB.S9S_MB_2U(SCH_1):GND
  BR86  GND            VSS569  @S9S_MB_2U_LIB.S9S_MB_2U(SCH_1):GND
  BR84  GND            VSS568  @S9S_MB_2U_LIB.S9S_MB_2U(SCH_1):GND
  BR82  GND            VSS567  @S9S_MB_2U_LIB.S9S_MB_2U(SCH_1):GND
  BR80  GND            VSS566  @S9S_MB_2U_LIB.S9S_MB_2U(SCH_1):GND
  BR76  GND            VSS565  @S9S_MB_2U_LIB.S9S_MB_2U(SCH_1):GND
  BR74  GND            VSS564  @S9S_MB_2U_LIB.S9S_MB_2U(SCH_1):GND
  BR72  GND            VSS563  @S9S_MB_2U_LIB.S9S_MB_2U(SCH_1):GND
  BR70  GND            VSS561  @S9S_MB_2U_LIB.S9S_MB_2U(SCH_1):GND
  BR68  GND            VSS560  @S9S_MB_2U_LIB.S9S_MB_2U(SCH_1):GND
  BR66  GND            VSS559  @S9S_MB_2U_LIB.S9S_MB_2U(SCH_1):GND
  BR64  GND            VSS557  @S9S_MB_2U_LIB.S9S_MB_2U(SCH_1):GND
  BR58  GND            VSS556  @S9S_MB_2U_LIB.S9S_MB_2U(SCH_1):GND
  BR56  GND            VSS555  @S9S_MB_2U_LIB.S9S_MB_2U(SCH_1):GND
  BR54  GND            VSS552  @S9S_MB_2U_LIB.S9S_MB_2U(SCH_1):GND
  BR52  GND            VSS551  @S9S_MB_2U_LIB.S9S_MB_2U(SCH_1):GND
  BR50  GND            VSS550  @S9S_MB_2U_LIB.S9S_MB_2U(SCH_1):GND
  BR48  GND            VSS549  @S9S_MB_2U_LIB.S9S_MB_2U(SCH_1):GND
  BR45  GND            VSS548  @S9S_MB_2U_LIB.S9S_MB_2U(SCH_1):GND
  BR43  GND            VSS547  @S9S_MB_2U_LIB.S9S_MB_2U(SCH_1):GND
  BR41  GND            VSS546  @S9S_MB_2U_LIB.S9S_MB_2U(SCH_1):GND
  BR39  GND            VSS545  @S9S_MB_2U_LIB.S9S_MB_2U(SCH_1):GND
  BR37  GND            VSS543  @S9S_MB_2U_LIB.S9S_MB_2U(SCH_1):GND
  BR35  GND            VSS542  @S9S_MB_2U_LIB.S9S_MB_2U(SCH_1):GND
  CK4  GND            VSS396  @S9S_MB_2U_LIB.S9S_MB_2U(SCH_1):GND
  CJ76  GND            VSS383  @S9S_MB_2U_LIB.S9S_MB_2U(SCH_1):GND

SOCKET4677_AZIFS054P001C01  I11  U2     [SOCKET4677_AZIFS054P001C01-SOCA]
  DB87  GND            VSS948  @S9S_MB_2U_LIB.S9S_MB_2U(SCH_1):GND
  DB8  GND            VSS947  @S9S_MB_2U_LIB.S9S_MB_2U(SCH_1):GND
  DB77  GND            VSS946  @S9S_MB_2U_LIB.S9S_MB_2U(SCH_1):GND
  DB71  GND            VSS944  @S9S_MB_2U_LIB.S9S_MB_2U(SCH_1):GND
  DB65  GND            VSS943  @S9S_MB_2U_LIB.S9S_MB_2U(SCH_1):GND
  DB57  GND            VSS942  @S9S_MB_2U_LIB.S9S_MB_2U(SCH_1):GND
  DB47  GND            VSS941  @S9S_MB_2U_LIB.S9S_MB_2U(SCH_1):GND
  DB40  GND            VSS940  @S9S_MB_2U_LIB.S9S_MB_2U(SCH_1):GND
  DB4  GND            VSS939  @S9S_MB_2U_LIB.S9S_MB_2U(SCH_1):GND
  DB38  GND            VSS938  @S9S_MB_2U_LIB.S9S_MB_2U(SCH_1):GND
  DB32  GND            VSS937  @S9S_MB_2U_LIB.S9S_MB_2U(SCH_1):GND
  DB28  GND            VSS936  @S9S_MB_2U_LIB.S9S_MB_2U(SCH_1):GND
  DB22  GND            VSS935  @S9S_MB_2U_LIB.S9S_MB_2U(SCH_1):GND
  DB12  GND            VSS933  @S9S_MB_2U_LIB.S9S_MB_2U(SCH_1):GND
  DA88  GND            VSS932  @S9S_MB_2U_LIB.S9S_MB_2U(SCH_1):GND
  DA84  GND            VSS931  @S9S_MB_2U_LIB.S9S_MB_2U(SCH_1):GND
  DA82  GND            VSS930  @S9S_MB_2U_LIB.S9S_MB_2U(SCH_1):GND
  DA80  GND            VSS929  @S9S_MB_2U_LIB.S9S_MB_2U(SCH_1):GND
  DA74  GND            VSS928  @S9S_MB_2U_LIB.S9S_MB_2U(SCH_1):GND
  DA72  GND            VSS927  @S9S_MB_2U_LIB.S9S_MB_2U(SCH_1):GND
  DA66  GND            VSS926  @S9S_MB_2U_LIB.S9S_MB_2U(SCH_1):GND
  DA62  GND            VSS925  @S9S_MB_2U_LIB.S9S_MB_2U(SCH_1):GND
  DA60  GND            VSS924  @S9S_MB_2U_LIB.S9S_MB_2U(SCH_1):GND
  DA58  GND            VSS923  @S9S_MB_2U_LIB.S9S_MB_2U(SCH_1):GND
  DA56  GND            VSS922  @S9S_MB_2U_LIB.S9S_MB_2U(SCH_1):GND
  DA54  GND            VSS921  @S9S_MB_2U_LIB.S9S_MB_2U(SCH_1):GND
  DA50  GND            VSS920  @S9S_MB_2U_LIB.S9S_MB_2U(SCH_1):GND
  DA48  GND            VSS919  @S9S_MB_2U_LIB.S9S_MB_2U(SCH_1):GND
  DA41  GND            VSS918  @S9S_MB_2U_LIB.S9S_MB_2U(SCH_1):GND
  DA37  GND            VSS917  @S9S_MB_2U_LIB.S9S_MB_2U(SCH_1):GND
  DA35  GND            VSS916  @S9S_MB_2U_LIB.S9S_MB_2U(SCH_1):GND
  DA33  GND            VSS915  @S9S_MB_2U_LIB.S9S_MB_2U(SCH_1):GND
  DA31  GND            VSS914  @S9S_MB_2U_LIB.S9S_MB_2U(SCH_1):GND
  DA29  GND            VSS913  @S9S_MB_2U_LIB.S9S_MB_2U(SCH_1):GND
  DA25  GND            VSS912  @S9S_MB_2U_LIB.S9S_MB_2U(SCH_1):GND
  DA23  GND            VSS911  @S9S_MB_2U_LIB.S9S_MB_2U(SCH_1):GND
  DA19  GND            VSS910  @S9S_MB_2U_LIB.S9S_MB_2U(SCH_1):GND
  CY83  GND            VSS863  @S9S_MB_2U_LIB.S9S_MB_2U(SCH_1):GND
  CY81  GND            VSS862  @S9S_MB_2U_LIB.S9S_MB_2U(SCH_1):GND
  CY8  GND            VSS860  @S9S_MB_2U_LIB.S9S_MB_2U(SCH_1):GND
  CY77  GND            VSS859  @S9S_MB_2U_LIB.S9S_MB_2U(SCH_1):GND
  CY73  GND            VSS858  @S9S_MB_2U_LIB.S9S_MB_2U(SCH_1):GND
  CY63  GND            VSS856  @S9S_MB_2U_LIB.S9S_MB_2U(SCH_1):GND
  CY30  GND            VSS855  @S9S_MB_2U_LIB.S9S_MB_2U(SCH_1):GND
  CY26  GND            VSS854  @S9S_MB_2U_LIB.S9S_MB_2U(SCH_1):GND
  CY18  GND            VSS853  @S9S_MB_2U_LIB.S9S_MB_2U(SCH_1):GND
  CY16  GND            VSS852  @S9S_MB_2U_LIB.S9S_MB_2U(SCH_1):GND
  CY12  GND            VSS851  @S9S_MB_2U_LIB.S9S_MB_2U(SCH_1):GND
  CW9  GND            VSS850  @S9S_MB_2U_LIB.S9S_MB_2U(SCH_1):GND
  CW88  GND            VSS848  @S9S_MB_2U_LIB.S9S_MB_2U(SCH_1):GND
  CW84  GND            VSS846  @S9S_MB_2U_LIB.S9S_MB_2U(SCH_1):GND
  CW78  GND            VSS843  @S9S_MB_2U_LIB.S9S_MB_2U(SCH_1):GND
  CW72  GND            VSS840  @S9S_MB_2U_LIB.S9S_MB_2U(SCH_1):GND
  CW5  GND            VSS838  @S9S_MB_2U_LIB.S9S_MB_2U(SCH_1):GND
  CW17  GND            VSS837  @S9S_MB_2U_LIB.S9S_MB_2U(SCH_1):GND
  CW13  GND            VSS836  @S9S_MB_2U_LIB.S9S_MB_2U(SCH_1):GND
  CW1  GND            VSS834  @S9S_MB_2U_LIB.S9S_MB_2U(SCH_1):GND
  CV91  GND            VSS833  @S9S_MB_2U_LIB.S9S_MB_2U(SCH_1):GND
  CV87  GND            VSS831  @S9S_MB_2U_LIB.S9S_MB_2U(SCH_1):GND
  CV83  GND            VSS828  @S9S_MB_2U_LIB.S9S_MB_2U(SCH_1):GND
  CV8  GND            VSS827  @S9S_MB_2U_LIB.S9S_MB_2U(SCH_1):GND
  CV75  GND            VSS826  @S9S_MB_2U_LIB.S9S_MB_2U(SCH_1):GND
  CV4  GND            VSS825  @S9S_MB_2U_LIB.S9S_MB_2U(SCH_1):GND
  CV12  GND            VSS824  @S9S_MB_2U_LIB.S9S_MB_2U(SCH_1):GND
  CU88  GND            VSS823  @S9S_MB_2U_LIB.S9S_MB_2U(SCH_1):GND
  CU84  GND            VSS822  @S9S_MB_2U_LIB.S9S_MB_2U(SCH_1):GND
  CU68  GND            VSS819  @S9S_MB_2U_LIB.S9S_MB_2U(SCH_1):GND
  CU66  GND            VSS818  @S9S_MB_2U_LIB.S9S_MB_2U(SCH_1):GND
  CU60  GND            VSS816  @S9S_MB_2U_LIB.S9S_MB_2U(SCH_1):GND
  CU23  GND            VSS815  @S9S_MB_2U_LIB.S9S_MB_2U(SCH_1):GND
  CU21  GND            VSS814  @S9S_MB_2U_LIB.S9S_MB_2U(SCH_1):GND
  CU19  GND            VSS813  @S9S_MB_2U_LIB.S9S_MB_2U(SCH_1):GND
  CT81  GND            VSS812  @S9S_MB_2U_LIB.S9S_MB_2U(SCH_1):GND
  CT73  GND            VSS811  @S9S_MB_2U_LIB.S9S_MB_2U(SCH_1):GND
  CT69  GND            VSS810  @S9S_MB_2U_LIB.S9S_MB_2U(SCH_1):GND
  CT12  GND            VSS805  @S9S_MB_2U_LIB.S9S_MB_2U(SCH_1):GND
  CT10  GND            VSS804  @S9S_MB_2U_LIB.S9S_MB_2U(SCH_1):GND
  CR90  GND            VSS803  @S9S_MB_2U_LIB.S9S_MB_2U(SCH_1):GND
  CR9  GND            VSS801  @S9S_MB_2U_LIB.S9S_MB_2U(SCH_1):GND
  CR88  GND            VSS800  @S9S_MB_2U_LIB.S9S_MB_2U(SCH_1):GND
  CR84  GND            VSS797  @S9S_MB_2U_LIB.S9S_MB_2U(SCH_1):GND
  CR64  GND            VSS796  @S9S_MB_2U_LIB.S9S_MB_2U(SCH_1):GND
  CR62  GND            VSS795  @S9S_MB_2U_LIB.S9S_MB_2U(SCH_1):GND
  CR5  GND            VSS794  @S9S_MB_2U_LIB.S9S_MB_2U(SCH_1):GND
  CR17  GND            VSS793  @S9S_MB_2U_LIB.S9S_MB_2U(SCH_1):GND
  CR13  GND            VSS792  @S9S_MB_2U_LIB.S9S_MB_2U(SCH_1):GND
  CR11  GND            VSS790  @S9S_MB_2U_LIB.S9S_MB_2U(SCH_1):GND
  CR1  GND            VSS789  @S9S_MB_2U_LIB.S9S_MB_2U(SCH_1):GND
  CP91  GND            VSS788  @S9S_MB_2U_LIB.S9S_MB_2U(SCH_1):GND
  CP87  GND            VSS787  @S9S_MB_2U_LIB.S9S_MB_2U(SCH_1):GND
  CP83  GND            VSS786  @S9S_MB_2U_LIB.S9S_MB_2U(SCH_1):GND
  CP8  GND            VSS785  @S9S_MB_2U_LIB.S9S_MB_2U(SCH_1):GND
  CP77  GND            VSS784  @S9S_MB_2U_LIB.S9S_MB_2U(SCH_1):GND
  CP75  GND            VSS783  @S9S_MB_2U_LIB.S9S_MB_2U(SCH_1):GND
  CP4  GND            VSS782  @S9S_MB_2U_LIB.S9S_MB_2U(SCH_1):GND
  CP18  GND            VSS781  @S9S_MB_2U_LIB.S9S_MB_2U(SCH_1):GND
  CP12  GND            VSS780  @S9S_MB_2U_LIB.S9S_MB_2U(SCH_1):GND
  CN86  GND            VSS779  @S9S_MB_2U_LIB.S9S_MB_2U(SCH_1):GND
  CN84  GND            VSS778  @S9S_MB_2U_LIB.S9S_MB_2U(SCH_1):GND
  CN74  GND            VSS777  @S9S_MB_2U_LIB.S9S_MB_2U(SCH_1):GND
  CN72  GND            VSS775  @S9S_MB_2U_LIB.S9S_MB_2U(SCH_1):GND
  CN70  GND            VSS774  @S9S_MB_2U_LIB.S9S_MB_2U(SCH_1):GND
  CN68  GND            VSS773  @S9S_MB_2U_LIB.S9S_MB_2U(SCH_1):GND
  CM85  GND            VSS772  @S9S_MB_2U_LIB.S9S_MB_2U(SCH_1):GND
  CM83  GND            VSS771  @S9S_MB_2U_LIB.S9S_MB_2U(SCH_1):GND
  CM81  GND            VSS770  @S9S_MB_2U_LIB.S9S_MB_2U(SCH_1):GND
  CM8  GND            VSS769  @S9S_MB_2U_LIB.S9S_MB_2U(SCH_1):GND
  CM79  GND            VSS768  @S9S_MB_2U_LIB.S9S_MB_2U(SCH_1):GND
  CM67  GND            VSS767  @S9S_MB_2U_LIB.S9S_MB_2U(SCH_1):GND
  CM65  GND            VSS766  @S9S_MB_2U_LIB.S9S_MB_2U(SCH_1):GND
  CM61  GND            VSS765  @S9S_MB_2U_LIB.S9S_MB_2U(SCH_1):GND
  CM4  GND            VSS764  @S9S_MB_2U_LIB.S9S_MB_2U(SCH_1):GND
  CM24  GND            VSS763  @S9S_MB_2U_LIB.S9S_MB_2U(SCH_1):GND
  CM20  GND            VSS762  @S9S_MB_2U_LIB.S9S_MB_2U(SCH_1):GND
  CM12  GND            VSS761  @S9S_MB_2U_LIB.S9S_MB_2U(SCH_1):GND
  CL9  GND            VSS760  @S9S_MB_2U_LIB.S9S_MB_2U(SCH_1):GND
  CL82  GND            VSS759  @S9S_MB_2U_LIB.S9S_MB_2U(SCH_1):GND
  CL80  GND            VSS758  @S9S_MB_2U_LIB.S9S_MB_2U(SCH_1):GND
  CL78  GND            VSS757  @S9S_MB_2U_LIB.S9S_MB_2U(SCH_1):GND
  CL74  GND            VSS756  @S9S_MB_2U_LIB.S9S_MB_2U(SCH_1):GND
  CL62  GND            VSS755  @S9S_MB_2U_LIB.S9S_MB_2U(SCH_1):GND
  CL5  GND            VSS754  @S9S_MB_2U_LIB.S9S_MB_2U(SCH_1):GND
  CL17  GND            VSS752  @S9S_MB_2U_LIB.S9S_MB_2U(SCH_1):GND
  CL13  GND            VSS751  @S9S_MB_2U_LIB.S9S_MB_2U(SCH_1):GND
  CL1  GND            VSS750  @S9S_MB_2U_LIB.S9S_MB_2U(SCH_1):GND
  CK81  GND            VSS749  @S9S_MB_2U_LIB.S9S_MB_2U(SCH_1):GND
  CK69  GND            VSS745  @S9S_MB_2U_LIB.S9S_MB_2U(SCH_1):GND
  CK63  GND            VSS744  @S9S_MB_2U_LIB.S9S_MB_2U(SCH_1):GND
  DB75  GND            VSS719  @S9S_MB_2U_LIB.S9S_MB_2U(SCH_1):GND
  DB69  GND            VSS717  @S9S_MB_2U_LIB.S9S_MB_2U(SCH_1):GND
  DB63  GND            VSS715  @S9S_MB_2U_LIB.S9S_MB_2U(SCH_1):GND
  DB59  GND            VSS714  @S9S_MB_2U_LIB.S9S_MB_2U(SCH_1):GND
  DB53  GND            VSS712  @S9S_MB_2U_LIB.S9S_MB_2U(SCH_1):GND
  DB51  GND            VSS711  @S9S_MB_2U_LIB.S9S_MB_2U(SCH_1):GND
  DB44  GND            VSS709  @S9S_MB_2U_LIB.S9S_MB_2U(SCH_1):GND
  DB34  GND            VSS705  @S9S_MB_2U_LIB.S9S_MB_2U(SCH_1):GND
  DB26  GND            VSS702  @S9S_MB_2U_LIB.S9S_MB_2U(SCH_1):GND
  DB20  GND            VSS700  @S9S_MB_2U_LIB.S9S_MB_2U(SCH_1):GND
  DB16  GND            VSS699  @S9S_MB_2U_LIB.S9S_MB_2U(SCH_1):GND
  DA68  GND            VSS690  @S9S_MB_2U_LIB.S9S_MB_2U(SCH_1):GND
  DA43  GND            VSS679  @S9S_MB_2U_LIB.S9S_MB_2U(SCH_1):GND
  CY4  GND            VSS611  @S9S_MB_2U_LIB.S9S_MB_2U(SCH_1):GND
  CW70  GND            VSS595  @S9S_MB_2U_LIB.S9S_MB_2U(SCH_1):GND
  CW33  GND            VSS583  @S9S_MB_2U_LIB.S9S_MB_2U(SCH_1):GND
  CV79  GND            VSS571  @S9S_MB_2U_LIB.S9S_MB_2U(SCH_1):GND
  CV26  GND            VSS562  @S9S_MB_2U_LIB.S9S_MB_2U(SCH_1):GND
  CV16  GND            VSS558  @S9S_MB_2U_LIB.S9S_MB_2U(SCH_1):GND
  CU78  GND            VSS554  @S9S_MB_2U_LIB.S9S_MB_2U(SCH_1):GND
  CU72  GND            VSS553  @S9S_MB_2U_LIB.S9S_MB_2U(SCH_1):GND
  CU25  GND            VSS544  @S9S_MB_2U_LIB.S9S_MB_2U(SCH_1):GND
  CT89  GND            VSS537  @S9S_MB_2U_LIB.S9S_MB_2U(SCH_1):GND
  CT8  GND            VSS534  @S9S_MB_2U_LIB.S9S_MB_2U(SCH_1):GND
  CT4  GND            VSS526  @S9S_MB_2U_LIB.S9S_MB_2U(SCH_1):GND
  CT16  GND            VSS521  @S9S_MB_2U_LIB.S9S_MB_2U(SCH_1):GND
  CR78  GND            VSS514  @S9S_MB_2U_LIB.S9S_MB_2U(SCH_1):GND
  CP79  GND            VSS493  @S9S_MB_2U_LIB.S9S_MB_2U(SCH_1):GND
  CP16  GND            VSS478  @S9S_MB_2U_LIB.S9S_MB_2U(SCH_1):GND
  CN76  GND            VSS471  @S9S_MB_2U_LIB.S9S_MB_2U(SCH_1):GND
  CM22  GND            VSS438  @S9S_MB_2U_LIB.S9S_MB_2U(SCH_1):GND
  CM16  GND            VSS436  @S9S_MB_2U_LIB.S9S_MB_2U(SCH_1):GND

SOCKET4677_AZIFS054P001C01  I10  U2     [SOCKET4677_AZIFS054P001C01-SOCA]
  DL9  GND            VSS1099  @S9S_MB_2U_LIB.S9S_MB_2U(SCH_1):GND
  DL88  GND            VSS1098  @S9S_MB_2U_LIB.S9S_MB_2U(SCH_1):GND
  DL84  GND            VSS1096  @S9S_MB_2U_LIB.S9S_MB_2U(SCH_1):GND
  DL39  GND            VSS1095  @S9S_MB_2U_LIB.S9S_MB_2U(SCH_1):GND
  DK91  GND            VSS1094  @S9S_MB_2U_LIB.S9S_MB_2U(SCH_1):GND
  DK87  GND            VSS1093  @S9S_MB_2U_LIB.S9S_MB_2U(SCH_1):GND
  DK83  GND            VSS1092  @S9S_MB_2U_LIB.S9S_MB_2U(SCH_1):GND
  DK81  GND            VSS1091  @S9S_MB_2U_LIB.S9S_MB_2U(SCH_1):GND
  DK8  GND            VSS1090  @S9S_MB_2U_LIB.S9S_MB_2U(SCH_1):GND
  DK79  GND            VSS1089  @S9S_MB_2U_LIB.S9S_MB_2U(SCH_1):GND
  DK77  GND            VSS1088  @S9S_MB_2U_LIB.S9S_MB_2U(SCH_1):GND
  DK73  GND            VSS1087  @S9S_MB_2U_LIB.S9S_MB_2U(SCH_1):GND
  DK49  GND            VSS1086  @S9S_MB_2U_LIB.S9S_MB_2U(SCH_1):GND
  DK4  GND            VSS1085  @S9S_MB_2U_LIB.S9S_MB_2U(SCH_1):GND
  DK36  GND            VSS1084  @S9S_MB_2U_LIB.S9S_MB_2U(SCH_1):GND
  DK30  GND            VSS1083  @S9S_MB_2U_LIB.S9S_MB_2U(SCH_1):GND
  DK16  GND            VSS1082  @S9S_MB_2U_LIB.S9S_MB_2U(SCH_1):GND
  DJ88  GND            VSS1081  @S9S_MB_2U_LIB.S9S_MB_2U(SCH_1):GND
  DJ84  GND            VSS1080  @S9S_MB_2U_LIB.S9S_MB_2U(SCH_1):GND
  DJ82  GND            VSS1079  @S9S_MB_2U_LIB.S9S_MB_2U(SCH_1):GND
  DJ80  GND            VSS1078  @S9S_MB_2U_LIB.S9S_MB_2U(SCH_1):GND
  DJ74  GND            VSS1076  @S9S_MB_2U_LIB.S9S_MB_2U(SCH_1):GND
  DJ72  GND            VSS1075  @S9S_MB_2U_LIB.S9S_MB_2U(SCH_1):GND
  DJ66  GND            VSS1074  @S9S_MB_2U_LIB.S9S_MB_2U(SCH_1):GND
  DJ60  GND            VSS1073  @S9S_MB_2U_LIB.S9S_MB_2U(SCH_1):GND
  DJ56  GND            VSS1072  @S9S_MB_2U_LIB.S9S_MB_2U(SCH_1):GND
  DJ50  GND            VSS1071  @S9S_MB_2U_LIB.S9S_MB_2U(SCH_1):GND
  DJ48  GND            VSS1070  @S9S_MB_2U_LIB.S9S_MB_2U(SCH_1):GND
  DJ43  GND            VSS1069  @S9S_MB_2U_LIB.S9S_MB_2U(SCH_1):GND
  DJ41  GND            VSS1068  @S9S_MB_2U_LIB.S9S_MB_2U(SCH_1):GND
  DJ37  GND            VSS1067  @S9S_MB_2U_LIB.S9S_MB_2U(SCH_1):GND
  DJ31  GND            VSS1066  @S9S_MB_2U_LIB.S9S_MB_2U(SCH_1):GND
  DJ29  GND            VSS1065  @S9S_MB_2U_LIB.S9S_MB_2U(SCH_1):GND
  DJ23  GND            VSS1062  @S9S_MB_2U_LIB.S9S_MB_2U(SCH_1):GND
  DJ19  GND            VSS1061  @S9S_MB_2U_LIB.S9S_MB_2U(SCH_1):GND
  DH85  GND            VSS1058  @S9S_MB_2U_LIB.S9S_MB_2U(SCH_1):GND
  DH8  GND            VSS1057  @S9S_MB_2U_LIB.S9S_MB_2U(SCH_1):GND
  DH77  GND            VSS1056  @S9S_MB_2U_LIB.S9S_MB_2U(SCH_1):GND
  DH71  GND            VSS1055  @S9S_MB_2U_LIB.S9S_MB_2U(SCH_1):GND
  DH65  GND            VSS1053  @S9S_MB_2U_LIB.S9S_MB_2U(SCH_1):GND
  DH57  GND            VSS1049  @S9S_MB_2U_LIB.S9S_MB_2U(SCH_1):GND
  DH47  GND            VSS1046  @S9S_MB_2U_LIB.S9S_MB_2U(SCH_1):GND
  DH40  GND            VSS1045  @S9S_MB_2U_LIB.S9S_MB_2U(SCH_1):GND
  DH4  GND            VSS1044  @S9S_MB_2U_LIB.S9S_MB_2U(SCH_1):GND
  DH38  GND            VSS1043  @S9S_MB_2U_LIB.S9S_MB_2U(SCH_1):GND
  DH32  GND            VSS1042  @S9S_MB_2U_LIB.S9S_MB_2U(SCH_1):GND
  DH28  GND            VSS1041  @S9S_MB_2U_LIB.S9S_MB_2U(SCH_1):GND
  DH22  GND            VSS1040  @S9S_MB_2U_LIB.S9S_MB_2U(SCH_1):GND
  DH12  GND            VSS1039  @S9S_MB_2U_LIB.S9S_MB_2U(SCH_1):GND
  DG9  GND            VSS1038  @S9S_MB_2U_LIB.S9S_MB_2U(SCH_1):GND
  DG88  GND            VSS1037  @S9S_MB_2U_LIB.S9S_MB_2U(SCH_1):GND
  DG84  GND            VSS1035  @S9S_MB_2U_LIB.S9S_MB_2U(SCH_1):GND
  DG80  GND            VSS1034  @S9S_MB_2U_LIB.S9S_MB_2U(SCH_1):GND
  DG76  GND            VSS1033  @S9S_MB_2U_LIB.S9S_MB_2U(SCH_1):GND
  DG70  GND            VSS1032  @S9S_MB_2U_LIB.S9S_MB_2U(SCH_1):GND
  DG5  GND            VSS1031  @S9S_MB_2U_LIB.S9S_MB_2U(SCH_1):GND
  DG45  GND            VSS1030  @S9S_MB_2U_LIB.S9S_MB_2U(SCH_1):GND
  DG39  GND            VSS1027  @S9S_MB_2U_LIB.S9S_MB_2U(SCH_1):GND
  DG33  GND            VSS1024  @S9S_MB_2U_LIB.S9S_MB_2U(SCH_1):GND
  DG27  GND            VSS1022  @S9S_MB_2U_LIB.S9S_MB_2U(SCH_1):GND
  DF87  GND            VSS1020  @S9S_MB_2U_LIB.S9S_MB_2U(SCH_1):GND
  DF8  GND            VSS1019  @S9S_MB_2U_LIB.S9S_MB_2U(SCH_1):GND
  DF79  GND            VSS1018  @S9S_MB_2U_LIB.S9S_MB_2U(SCH_1):GND
  DF4  GND            VSS1017  @S9S_MB_2U_LIB.S9S_MB_2U(SCH_1):GND
  DE88  GND            VSS1015  @S9S_MB_2U_LIB.S9S_MB_2U(SCH_1):GND
  DE84  GND            VSS1012  @S9S_MB_2U_LIB.S9S_MB_2U(SCH_1):GND
  DE82  GND            VSS1011  @S9S_MB_2U_LIB.S9S_MB_2U(SCH_1):GND
  DE76  GND            VSS1010  @S9S_MB_2U_LIB.S9S_MB_2U(SCH_1):GND
  DE74  GND            VSS1009  @S9S_MB_2U_LIB.S9S_MB_2U(SCH_1):GND
  DE72  GND            VSS1008  @S9S_MB_2U_LIB.S9S_MB_2U(SCH_1):GND
  DE68  GND            VSS1007  @S9S_MB_2U_LIB.S9S_MB_2U(SCH_1):GND
  DE66  GND            VSS1004  @S9S_MB_2U_LIB.S9S_MB_2U(SCH_1):GND
  DE64  GND            VSS1001  @S9S_MB_2U_LIB.S9S_MB_2U(SCH_1):GND
  DE62  GND            VSS999  @S9S_MB_2U_LIB.S9S_MB_2U(SCH_1):GND
  DE60  GND            VSS997  @S9S_MB_2U_LIB.S9S_MB_2U(SCH_1):GND
  DE58  GND            VSS996  @S9S_MB_2U_LIB.S9S_MB_2U(SCH_1):GND
  DE56  GND            VSS995  @S9S_MB_2U_LIB.S9S_MB_2U(SCH_1):GND
  DE54  GND            VSS994  @S9S_MB_2U_LIB.S9S_MB_2U(SCH_1):GND
  DE52  GND            VSS992  @S9S_MB_2U_LIB.S9S_MB_2U(SCH_1):GND
  DE50  GND            VSS991  @S9S_MB_2U_LIB.S9S_MB_2U(SCH_1):GND
  DE48  GND            VSS989  @S9S_MB_2U_LIB.S9S_MB_2U(SCH_1):GND
  DE45  GND            VSS988  @S9S_MB_2U_LIB.S9S_MB_2U(SCH_1):GND
  DE43  GND            VSS987  @S9S_MB_2U_LIB.S9S_MB_2U(SCH_1):GND
  DE41  GND            VSS986  @S9S_MB_2U_LIB.S9S_MB_2U(SCH_1):GND
  DE37  GND            VSS984  @S9S_MB_2U_LIB.S9S_MB_2U(SCH_1):GND
  DE35  GND            VSS983  @S9S_MB_2U_LIB.S9S_MB_2U(SCH_1):GND
  DE33  GND            VSS982  @S9S_MB_2U_LIB.S9S_MB_2U(SCH_1):GND
  DE31  GND            VSS981  @S9S_MB_2U_LIB.S9S_MB_2U(SCH_1):GND
  DE29  GND            VSS978  @S9S_MB_2U_LIB.S9S_MB_2U(SCH_1):GND
  DE27  GND            VSS977  @S9S_MB_2U_LIB.S9S_MB_2U(SCH_1):GND
  DE25  GND            VSS975  @S9S_MB_2U_LIB.S9S_MB_2U(SCH_1):GND
  DE23  GND            VSS974  @S9S_MB_2U_LIB.S9S_MB_2U(SCH_1):GND
  DE21  GND            VSS972  @S9S_MB_2U_LIB.S9S_MB_2U(SCH_1):GND
  DE19  GND            VSS971  @S9S_MB_2U_LIB.S9S_MB_2U(SCH_1):GND
  DE17  GND            VSS970  @S9S_MB_2U_LIB.S9S_MB_2U(SCH_1):GND
  DD8  GND            VSS967  @S9S_MB_2U_LIB.S9S_MB_2U(SCH_1):GND
  DD79  GND            VSS965  @S9S_MB_2U_LIB.S9S_MB_2U(SCH_1):GND
  DD4  GND            VSS964  @S9S_MB_2U_LIB.S9S_MB_2U(SCH_1):GND
  DC9  GND            VSS963  @S9S_MB_2U_LIB.S9S_MB_2U(SCH_1):GND
  DC88  GND            VSS962  @S9S_MB_2U_LIB.S9S_MB_2U(SCH_1):GND
  DC84  GND            VSS961  @S9S_MB_2U_LIB.S9S_MB_2U(SCH_1):GND
  DC80  GND            VSS960  @S9S_MB_2U_LIB.S9S_MB_2U(SCH_1):GND
  DC78  GND            VSS958  @S9S_MB_2U_LIB.S9S_MB_2U(SCH_1):GND
  DC76  GND            VSS956  @S9S_MB_2U_LIB.S9S_MB_2U(SCH_1):GND
  DC70  GND            VSS954  @S9S_MB_2U_LIB.S9S_MB_2U(SCH_1):GND
  DC5  GND            VSS953  @S9S_MB_2U_LIB.S9S_MB_2U(SCH_1):GND
  DC45  GND            VSS952  @S9S_MB_2U_LIB.S9S_MB_2U(SCH_1):GND
  DC39  GND            VSS951  @S9S_MB_2U_LIB.S9S_MB_2U(SCH_1):GND
  DC33  GND            VSS950  @S9S_MB_2U_LIB.S9S_MB_2U(SCH_1):GND
  DC27  GND            VSS949  @S9S_MB_2U_LIB.S9S_MB_2U(SCH_1):GND
  DL52  GND            VSS909  @S9S_MB_2U_LIB.S9S_MB_2U(SCH_1):GND
  DL5  GND            VSS908  @S9S_MB_2U_LIB.S9S_MB_2U(SCH_1):GND
  DL17  GND            VSS905  @S9S_MB_2U_LIB.S9S_MB_2U(SCH_1):GND
  DL13  GND            VSS904  @S9S_MB_2U_LIB.S9S_MB_2U(SCH_1):GND
  DL1  GND            VSS903  @S9S_MB_2U_LIB.S9S_MB_2U(SCH_1):GND
  DK67  GND            VSS894  @S9S_MB_2U_LIB.S9S_MB_2U(SCH_1):GND
  DK61  GND            VSS893  @S9S_MB_2U_LIB.S9S_MB_2U(SCH_1):GND
  DK55  GND            VSS890  @S9S_MB_2U_LIB.S9S_MB_2U(SCH_1):GND
  DK42  GND            VSS887  @S9S_MB_2U_LIB.S9S_MB_2U(SCH_1):GND
  DK24  GND            VSS883  @S9S_MB_2U_LIB.S9S_MB_2U(SCH_1):GND
  DK18  GND            VSS882  @S9S_MB_2U_LIB.S9S_MB_2U(SCH_1):GND
  DK12  GND            VSS880  @S9S_MB_2U_LIB.S9S_MB_2U(SCH_1):GND
  DJ68  GND            VSS872  @S9S_MB_2U_LIB.S9S_MB_2U(SCH_1):GND
  DJ62  GND            VSS870  @S9S_MB_2U_LIB.S9S_MB_2U(SCH_1):GND
  DJ54  GND            VSS867  @S9S_MB_2U_LIB.S9S_MB_2U(SCH_1):GND
  DJ35  GND            VSS861  @S9S_MB_2U_LIB.S9S_MB_2U(SCH_1):GND
  DJ25  GND            VSS857  @S9S_MB_2U_LIB.S9S_MB_2U(SCH_1):GND
  DH75  GND            VSS849  @S9S_MB_2U_LIB.S9S_MB_2U(SCH_1):GND
  DH69  GND            VSS847  @S9S_MB_2U_LIB.S9S_MB_2U(SCH_1):GND
  DH63  GND            VSS845  @S9S_MB_2U_LIB.S9S_MB_2U(SCH_1):GND
  DH59  GND            VSS844  @S9S_MB_2U_LIB.S9S_MB_2U(SCH_1):GND
  DH53  GND            VSS842  @S9S_MB_2U_LIB.S9S_MB_2U(SCH_1):GND
  DH51  GND            VSS841  @S9S_MB_2U_LIB.S9S_MB_2U(SCH_1):GND
  DH44  GND            VSS839  @S9S_MB_2U_LIB.S9S_MB_2U(SCH_1):GND
  DH34  GND            VSS835  @S9S_MB_2U_LIB.S9S_MB_2U(SCH_1):GND
  DH26  GND            VSS832  @S9S_MB_2U_LIB.S9S_MB_2U(SCH_1):GND
  DH20  GND            VSS830  @S9S_MB_2U_LIB.S9S_MB_2U(SCH_1):GND
  DH16  GND            VSS829  @S9S_MB_2U_LIB.S9S_MB_2U(SCH_1):GND
  DG64  GND            VSS821  @S9S_MB_2U_LIB.S9S_MB_2U(SCH_1):GND
  DG58  GND            VSS820  @S9S_MB_2U_LIB.S9S_MB_2U(SCH_1):GND
  DG52  GND            VSS817  @S9S_MB_2U_LIB.S9S_MB_2U(SCH_1):GND
  DG21  GND            VSS809  @S9S_MB_2U_LIB.S9S_MB_2U(SCH_1):GND
  DG13  GND            VSS808  @S9S_MB_2U_LIB.S9S_MB_2U(SCH_1):GND
  DG1  GND            VSS807  @S9S_MB_2U_LIB.S9S_MB_2U(SCH_1):GND
  DF91  GND            VSS806  @S9S_MB_2U_LIB.S9S_MB_2U(SCH_1):GND
  DF49  GND            VSS802  @S9S_MB_2U_LIB.S9S_MB_2U(SCH_1):GND
  DF16  GND            VSS799  @S9S_MB_2U_LIB.S9S_MB_2U(SCH_1):GND
  DF12  GND            VSS798  @S9S_MB_2U_LIB.S9S_MB_2U(SCH_1):GND
  DE70  GND            VSS791  @S9S_MB_2U_LIB.S9S_MB_2U(SCH_1):GND
  DE39  GND            VSS776  @S9S_MB_2U_LIB.S9S_MB_2U(SCH_1):GND
  DD49  GND            VSS753  @S9S_MB_2U_LIB.S9S_MB_2U(SCH_1):GND
  DD16  GND            VSS748  @S9S_MB_2U_LIB.S9S_MB_2U(SCH_1):GND
  DD12  GND            VSS747  @S9S_MB_2U_LIB.S9S_MB_2U(SCH_1):GND
  DC64  GND            VSS739  @S9S_MB_2U_LIB.S9S_MB_2U(SCH_1):GND
  DC58  GND            VSS738  @S9S_MB_2U_LIB.S9S_MB_2U(SCH_1):GND
  DC52  GND            VSS735  @S9S_MB_2U_LIB.S9S_MB_2U(SCH_1):GND
  DC21  GND            VSS726  @S9S_MB_2U_LIB.S9S_MB_2U(SCH_1):GND
  DC13  GND            VSS725  @S9S_MB_2U_LIB.S9S_MB_2U(SCH_1):GND
  DC1  GND            VSS724  @S9S_MB_2U_LIB.S9S_MB_2U(SCH_1):GND
  DB91  GND            VSS723  @S9S_MB_2U_LIB.S9S_MB_2U(SCH_1):GND

SOCKET4677_AZIFS054P001C01  I10  U2     [SOCKET4677_AZIFS054P001C01-SOCA]
  DW9  GND            VSS1268  @S9S_MB_2U_LIB.S9S_MB_2U(SCH_1):GND
  DW64  GND            VSS1256  @S9S_MB_2U_LIB.S9S_MB_2U(SCH_1):GND
  DW62  GND            VSS1255  @S9S_MB_2U_LIB.S9S_MB_2U(SCH_1):GND
  DW58  GND            VSS1254  @S9S_MB_2U_LIB.S9S_MB_2U(SCH_1):GND
  DW56  GND            VSS1253  @S9S_MB_2U_LIB.S9S_MB_2U(SCH_1):GND
  DW54  GND            VSS1252  @S9S_MB_2U_LIB.S9S_MB_2U(SCH_1):GND
  DW52  GND            VSS1251  @S9S_MB_2U_LIB.S9S_MB_2U(SCH_1):GND
  DW50  GND            VSS1250  @S9S_MB_2U_LIB.S9S_MB_2U(SCH_1):GND
  DW5  GND            VSS1249  @S9S_MB_2U_LIB.S9S_MB_2U(SCH_1):GND
  DW48  GND            VSS1248  @S9S_MB_2U_LIB.S9S_MB_2U(SCH_1):GND
  DW45  GND            VSS1247  @S9S_MB_2U_LIB.S9S_MB_2U(SCH_1):GND
  DW43  GND            VSS1246  @S9S_MB_2U_LIB.S9S_MB_2U(SCH_1):GND
  DW41  GND            VSS1245  @S9S_MB_2U_LIB.S9S_MB_2U(SCH_1):GND
  DW39  GND            VSS1244  @S9S_MB_2U_LIB.S9S_MB_2U(SCH_1):GND
  DW37  GND            VSS1243  @S9S_MB_2U_LIB.S9S_MB_2U(SCH_1):GND
  DW35  GND            VSS1242  @S9S_MB_2U_LIB.S9S_MB_2U(SCH_1):GND
  DW33  GND            VSS1241  @S9S_MB_2U_LIB.S9S_MB_2U(SCH_1):GND
  DW31  GND            VSS1240  @S9S_MB_2U_LIB.S9S_MB_2U(SCH_1):GND
  DW29  GND            VSS1239  @S9S_MB_2U_LIB.S9S_MB_2U(SCH_1):GND
  DW27  GND            VSS1238  @S9S_MB_2U_LIB.S9S_MB_2U(SCH_1):GND
  DW25  GND            VSS1236  @S9S_MB_2U_LIB.S9S_MB_2U(SCH_1):GND
  DW23  GND            VSS1234  @S9S_MB_2U_LIB.S9S_MB_2U(SCH_1):GND
  DW19  GND            VSS1233  @S9S_MB_2U_LIB.S9S_MB_2U(SCH_1):GND
  DW17  GND            VSS1231  @S9S_MB_2U_LIB.S9S_MB_2U(SCH_1):GND
  DW13  GND            VSS1230  @S9S_MB_2U_LIB.S9S_MB_2U(SCH_1):GND
  DW1  GND            VSS1229  @S9S_MB_2U_LIB.S9S_MB_2U(SCH_1):GND
  DV91  GND            VSS1228  @S9S_MB_2U_LIB.S9S_MB_2U(SCH_1):GND
  DV87  GND            VSS1227  @S9S_MB_2U_LIB.S9S_MB_2U(SCH_1):GND
  DV83  GND            VSS1226  @S9S_MB_2U_LIB.S9S_MB_2U(SCH_1):GND
  DV81  GND            VSS1222  @S9S_MB_2U_LIB.S9S_MB_2U(SCH_1):GND
  DV8  GND            VSS1221  @S9S_MB_2U_LIB.S9S_MB_2U(SCH_1):GND
  DV79  GND            VSS1219  @S9S_MB_2U_LIB.S9S_MB_2U(SCH_1):GND
  DV77  GND            VSS1218  @S9S_MB_2U_LIB.S9S_MB_2U(SCH_1):GND
  DU88  GND            VSS1216  @S9S_MB_2U_LIB.S9S_MB_2U(SCH_1):GND
  DU84  GND            VSS1215  @S9S_MB_2U_LIB.S9S_MB_2U(SCH_1):GND
  DU78  GND            VSS1214  @S9S_MB_2U_LIB.S9S_MB_2U(SCH_1):GND
  DU76  GND            VSS1213  @S9S_MB_2U_LIB.S9S_MB_2U(SCH_1):GND
  DU33  GND            VSS1212  @S9S_MB_2U_LIB.S9S_MB_2U(SCH_1):GND
  DU27  GND            VSS1211  @S9S_MB_2U_LIB.S9S_MB_2U(SCH_1):GND
  DU21  GND            VSS1209  @S9S_MB_2U_LIB.S9S_MB_2U(SCH_1):GND
  DT8  GND            VSS1207  @S9S_MB_2U_LIB.S9S_MB_2U(SCH_1):GND
  DT75  GND            VSS1206  @S9S_MB_2U_LIB.S9S_MB_2U(SCH_1):GND
  DT71  GND            VSS1205  @S9S_MB_2U_LIB.S9S_MB_2U(SCH_1):GND
  DT69  GND            VSS1204  @S9S_MB_2U_LIB.S9S_MB_2U(SCH_1):GND
  DT65  GND            VSS1203  @S9S_MB_2U_LIB.S9S_MB_2U(SCH_1):GND
  DT57  GND            VSS1202  @S9S_MB_2U_LIB.S9S_MB_2U(SCH_1):GND
  DT47  GND            VSS1201  @S9S_MB_2U_LIB.S9S_MB_2U(SCH_1):GND
  DT40  GND            VSS1199  @S9S_MB_2U_LIB.S9S_MB_2U(SCH_1):GND
  DT38  GND            VSS1196  @S9S_MB_2U_LIB.S9S_MB_2U(SCH_1):GND
  DT34  GND            VSS1194  @S9S_MB_2U_LIB.S9S_MB_2U(SCH_1):GND
  DT32  GND            VSS1192  @S9S_MB_2U_LIB.S9S_MB_2U(SCH_1):GND
  DT28  GND            VSS1191  @S9S_MB_2U_LIB.S9S_MB_2U(SCH_1):GND
  DT22  GND            VSS1190  @S9S_MB_2U_LIB.S9S_MB_2U(SCH_1):GND
  DT12  GND            VSS1189  @S9S_MB_2U_LIB.S9S_MB_2U(SCH_1):GND
  DR9  GND            VSS1187  @S9S_MB_2U_LIB.S9S_MB_2U(SCH_1):GND
  DR88  GND            VSS1186  @S9S_MB_2U_LIB.S9S_MB_2U(SCH_1):GND
  DR84  GND            VSS1184  @S9S_MB_2U_LIB.S9S_MB_2U(SCH_1):GND
  DR78  GND            VSS1183  @S9S_MB_2U_LIB.S9S_MB_2U(SCH_1):GND
  DR74  GND            VSS1182  @S9S_MB_2U_LIB.S9S_MB_2U(SCH_1):GND
  DR66  GND            VSS1181  @S9S_MB_2U_LIB.S9S_MB_2U(SCH_1):GND
  DR56  GND            VSS1179  @S9S_MB_2U_LIB.S9S_MB_2U(SCH_1):GND
  DR50  GND            VSS1178  @S9S_MB_2U_LIB.S9S_MB_2U(SCH_1):GND
  DR48  GND            VSS1177  @S9S_MB_2U_LIB.S9S_MB_2U(SCH_1):GND
  DR43  GND            VSS1176  @S9S_MB_2U_LIB.S9S_MB_2U(SCH_1):GND
  DR41  GND            VSS1175  @S9S_MB_2U_LIB.S9S_MB_2U(SCH_1):GND
  DR37  GND            VSS1174  @S9S_MB_2U_LIB.S9S_MB_2U(SCH_1):GND
  DR31  GND            VSS1173  @S9S_MB_2U_LIB.S9S_MB_2U(SCH_1):GND
  DR29  GND            VSS1172  @S9S_MB_2U_LIB.S9S_MB_2U(SCH_1):GND
  DR23  GND            VSS1169  @S9S_MB_2U_LIB.S9S_MB_2U(SCH_1):GND
  DR19  GND            VSS1166  @S9S_MB_2U_LIB.S9S_MB_2U(SCH_1):GND
  DR13  GND            VSS1164  @S9S_MB_2U_LIB.S9S_MB_2U(SCH_1):GND
  DR1  GND            VSS1162  @S9S_MB_2U_LIB.S9S_MB_2U(SCH_1):GND
  DP87  GND            VSS1160  @S9S_MB_2U_LIB.S9S_MB_2U(SCH_1):GND
  DP81  GND            VSS1159  @S9S_MB_2U_LIB.S9S_MB_2U(SCH_1):GND
  DP8  GND            VSS1157  @S9S_MB_2U_LIB.S9S_MB_2U(SCH_1):GND
  DP73  GND            VSS1154  @S9S_MB_2U_LIB.S9S_MB_2U(SCH_1):GND
  DP49  GND            VSS1153  @S9S_MB_2U_LIB.S9S_MB_2U(SCH_1):GND
  DP4  GND            VSS1152  @S9S_MB_2U_LIB.S9S_MB_2U(SCH_1):GND
  DP36  GND            VSS1151  @S9S_MB_2U_LIB.S9S_MB_2U(SCH_1):GND
  DP30  GND            VSS1150  @S9S_MB_2U_LIB.S9S_MB_2U(SCH_1):GND
  DP16  GND            VSS1149  @S9S_MB_2U_LIB.S9S_MB_2U(SCH_1):GND
  DN88  GND            VSS1148  @S9S_MB_2U_LIB.S9S_MB_2U(SCH_1):GND
  DN84  GND            VSS1147  @S9S_MB_2U_LIB.S9S_MB_2U(SCH_1):GND
  DN78  GND            VSS1143  @S9S_MB_2U_LIB.S9S_MB_2U(SCH_1):GND
  DM8  GND            VSS1140  @S9S_MB_2U_LIB.S9S_MB_2U(SCH_1):GND
  DM79  GND            VSS1139  @S9S_MB_2U_LIB.S9S_MB_2U(SCH_1):GND
  DM77  GND            VSS1138  @S9S_MB_2U_LIB.S9S_MB_2U(SCH_1):GND
  DM75  GND            VSS1137  @S9S_MB_2U_LIB.S9S_MB_2U(SCH_1):GND
  DM71  GND            VSS1136  @S9S_MB_2U_LIB.S9S_MB_2U(SCH_1):GND
  DM69  GND            VSS1135  @S9S_MB_2U_LIB.S9S_MB_2U(SCH_1):GND
  DM67  GND            VSS1134  @S9S_MB_2U_LIB.S9S_MB_2U(SCH_1):GND
  DM65  GND            VSS1133  @S9S_MB_2U_LIB.S9S_MB_2U(SCH_1):GND
  DM63  GND            VSS1132  @S9S_MB_2U_LIB.S9S_MB_2U(SCH_1):GND
  DM61  GND            VSS1130  @S9S_MB_2U_LIB.S9S_MB_2U(SCH_1):GND
  DM59  GND            VSS1128  @S9S_MB_2U_LIB.S9S_MB_2U(SCH_1):GND
  DM57  GND            VSS1127  @S9S_MB_2U_LIB.S9S_MB_2U(SCH_1):GND
  DM55  GND            VSS1124  @S9S_MB_2U_LIB.S9S_MB_2U(SCH_1):GND
  DM53  GND            VSS1123  @S9S_MB_2U_LIB.S9S_MB_2U(SCH_1):GND
  DM49  GND            VSS1122  @S9S_MB_2U_LIB.S9S_MB_2U(SCH_1):GND
  DM47  GND            VSS1121  @S9S_MB_2U_LIB.S9S_MB_2U(SCH_1):GND
  DM44  GND            VSS1120  @S9S_MB_2U_LIB.S9S_MB_2U(SCH_1):GND
  DM42  GND            VSS1119  @S9S_MB_2U_LIB.S9S_MB_2U(SCH_1):GND
  DM40  GND            VSS1118  @S9S_MB_2U_LIB.S9S_MB_2U(SCH_1):GND
  DM4  GND            VSS1117  @S9S_MB_2U_LIB.S9S_MB_2U(SCH_1):GND
  DM38  GND            VSS1114  @S9S_MB_2U_LIB.S9S_MB_2U(SCH_1):GND
  DM36  GND            VSS1113  @S9S_MB_2U_LIB.S9S_MB_2U(SCH_1):GND
  DM34  GND            VSS1110  @S9S_MB_2U_LIB.S9S_MB_2U(SCH_1):GND
  DM32  GND            VSS1109  @S9S_MB_2U_LIB.S9S_MB_2U(SCH_1):GND
  DM30  GND            VSS1108  @S9S_MB_2U_LIB.S9S_MB_2U(SCH_1):GND
  DM28  GND            VSS1107  @S9S_MB_2U_LIB.S9S_MB_2U(SCH_1):GND
  DM26  GND            VSS1106  @S9S_MB_2U_LIB.S9S_MB_2U(SCH_1):GND
  DM24  GND            VSS1105  @S9S_MB_2U_LIB.S9S_MB_2U(SCH_1):GND
  DM22  GND            VSS1104  @S9S_MB_2U_LIB.S9S_MB_2U(SCH_1):GND
  DM20  GND            VSS1103  @S9S_MB_2U_LIB.S9S_MB_2U(SCH_1):GND
  DM18  GND            VSS1102  @S9S_MB_2U_LIB.S9S_MB_2U(SCH_1):GND
  DM16  GND            VSS1101  @S9S_MB_2U_LIB.S9S_MB_2U(SCH_1):GND
  DM12  GND            VSS1100  @S9S_MB_2U_LIB.S9S_MB_2U(SCH_1):GND
  DW60  GND            VSS1097  @S9S_MB_2U_LIB.S9S_MB_2U(SCH_1):GND
  DW21  GND            VSS1077  @S9S_MB_2U_LIB.S9S_MB_2U(SCH_1):GND
  DV42  GND            VSS1064  @S9S_MB_2U_LIB.S9S_MB_2U(SCH_1):GND
  DV4  GND            VSS1063  @S9S_MB_2U_LIB.S9S_MB_2U(SCH_1):GND
  DV16  GND            VSS1060  @S9S_MB_2U_LIB.S9S_MB_2U(SCH_1):GND
  DV12  GND            VSS1059  @S9S_MB_2U_LIB.S9S_MB_2U(SCH_1):GND
  DU70  GND            VSS1054  @S9S_MB_2U_LIB.S9S_MB_2U(SCH_1):GND
  DU64  GND            VSS1052  @S9S_MB_2U_LIB.S9S_MB_2U(SCH_1):GND
  DU58  GND            VSS1051  @S9S_MB_2U_LIB.S9S_MB_2U(SCH_1):GND
  DU52  GND            VSS1050  @S9S_MB_2U_LIB.S9S_MB_2U(SCH_1):GND
  DU45  GND            VSS1048  @S9S_MB_2U_LIB.S9S_MB_2U(SCH_1):GND
  DU39  GND            VSS1047  @S9S_MB_2U_LIB.S9S_MB_2U(SCH_1):GND
  DT83  GND            VSS1036  @S9S_MB_2U_LIB.S9S_MB_2U(SCH_1):GND
  DT63  GND            VSS1029  @S9S_MB_2U_LIB.S9S_MB_2U(SCH_1):GND
  DT59  GND            VSS1028  @S9S_MB_2U_LIB.S9S_MB_2U(SCH_1):GND
  DT53  GND            VSS1026  @S9S_MB_2U_LIB.S9S_MB_2U(SCH_1):GND
  DT51  GND            VSS1025  @S9S_MB_2U_LIB.S9S_MB_2U(SCH_1):GND
  DT44  GND            VSS1023  @S9S_MB_2U_LIB.S9S_MB_2U(SCH_1):GND
  DT4  GND            VSS1021  @S9S_MB_2U_LIB.S9S_MB_2U(SCH_1):GND
  DT26  GND            VSS1016  @S9S_MB_2U_LIB.S9S_MB_2U(SCH_1):GND
  DT20  GND            VSS1014  @S9S_MB_2U_LIB.S9S_MB_2U(SCH_1):GND
  DT16  GND            VSS1013  @S9S_MB_2U_LIB.S9S_MB_2U(SCH_1):GND
  DR72  GND            VSS1006  @S9S_MB_2U_LIB.S9S_MB_2U(SCH_1):GND
  DR68  GND            VSS1005  @S9S_MB_2U_LIB.S9S_MB_2U(SCH_1):GND
  DR62  GND            VSS1003  @S9S_MB_2U_LIB.S9S_MB_2U(SCH_1):GND
  DR60  GND            VSS1002  @S9S_MB_2U_LIB.S9S_MB_2U(SCH_1):GND
  DR54  GND            VSS1000  @S9S_MB_2U_LIB.S9S_MB_2U(SCH_1):GND
  DR5  GND            VSS998  @S9S_MB_2U_LIB.S9S_MB_2U(SCH_1):GND
  DR35  GND            VSS993  @S9S_MB_2U_LIB.S9S_MB_2U(SCH_1):GND
  DR25  GND            VSS990  @S9S_MB_2U_LIB.S9S_MB_2U(SCH_1):GND
  DP91  GND            VSS985  @S9S_MB_2U_LIB.S9S_MB_2U(SCH_1):GND
  DP67  GND            VSS980  @S9S_MB_2U_LIB.S9S_MB_2U(SCH_1):GND
  DP61  GND            VSS979  @S9S_MB_2U_LIB.S9S_MB_2U(SCH_1):GND
  DP55  GND            VSS976  @S9S_MB_2U_LIB.S9S_MB_2U(SCH_1):GND
  DP42  GND            VSS973  @S9S_MB_2U_LIB.S9S_MB_2U(SCH_1):GND
  DP24  GND            VSS969  @S9S_MB_2U_LIB.S9S_MB_2U(SCH_1):GND
  DP18  GND            VSS968  @S9S_MB_2U_LIB.S9S_MB_2U(SCH_1):GND
  DP12  GND            VSS966  @S9S_MB_2U_LIB.S9S_MB_2U(SCH_1):GND
  DN52  GND            VSS959  @S9S_MB_2U_LIB.S9S_MB_2U(SCH_1):GND
  DN39  GND            VSS957  @S9S_MB_2U_LIB.S9S_MB_2U(SCH_1):GND
  DN17  GND            VSS955  @S9S_MB_2U_LIB.S9S_MB_2U(SCH_1):GND
  DM73  GND            VSS945  @S9S_MB_2U_LIB.S9S_MB_2U(SCH_1):GND
  DM51  GND            VSS934  @S9S_MB_2U_LIB.S9S_MB_2U(SCH_1):GND

SOCKET4677_AZIFS054P001C01  I9   U2     [SOCKET4677_AZIFS054P001C01-SOCA]
  EH4  GND            VSS1420  @S9S_MB_2U_LIB.S9S_MB_2U(SCH_1):GND
  EH30  GND            VSS1418  @S9S_MB_2U_LIB.S9S_MB_2U(SCH_1):GND
  EH24  GND            VSS1417  @S9S_MB_2U_LIB.S9S_MB_2U(SCH_1):GND
  EH16  GND            VSS1416  @S9S_MB_2U_LIB.S9S_MB_2U(SCH_1):GND
  EG90  GND            VSS1415  @S9S_MB_2U_LIB.S9S_MB_2U(SCH_1):GND
  EG9  GND            VSS1414  @S9S_MB_2U_LIB.S9S_MB_2U(SCH_1):GND
  EG88  GND            VSS1413  @S9S_MB_2U_LIB.S9S_MB_2U(SCH_1):GND
  EG86  GND            VSS1412  @S9S_MB_2U_LIB.S9S_MB_2U(SCH_1):GND
  EG84  GND            VSS1411  @S9S_MB_2U_LIB.S9S_MB_2U(SCH_1):GND
  EG82  GND            VSS1410  @S9S_MB_2U_LIB.S9S_MB_2U(SCH_1):GND
  EG39  GND            VSS1408  @S9S_MB_2U_LIB.S9S_MB_2U(SCH_1):GND
  EF87  GND            VSS1407  @S9S_MB_2U_LIB.S9S_MB_2U(SCH_1):GND
  EF85  GND            VSS1406  @S9S_MB_2U_LIB.S9S_MB_2U(SCH_1):GND
  EF8  GND            VSS1404  @S9S_MB_2U_LIB.S9S_MB_2U(SCH_1):GND
  EF77  GND            VSS1403  @S9S_MB_2U_LIB.S9S_MB_2U(SCH_1):GND
  EF71  GND            VSS1402  @S9S_MB_2U_LIB.S9S_MB_2U(SCH_1):GND
  EF69  GND            VSS1399  @S9S_MB_2U_LIB.S9S_MB_2U(SCH_1):GND
  EF67  GND            VSS1395  @S9S_MB_2U_LIB.S9S_MB_2U(SCH_1):GND
  EF65  GND            VSS1393  @S9S_MB_2U_LIB.S9S_MB_2U(SCH_1):GND
  EF63  GND            VSS1392  @S9S_MB_2U_LIB.S9S_MB_2U(SCH_1):GND
  EF61  GND            VSS1390  @S9S_MB_2U_LIB.S9S_MB_2U(SCH_1):GND
  EF59  GND            VSS1389  @S9S_MB_2U_LIB.S9S_MB_2U(SCH_1):GND
  EF57  GND            VSS1388  @S9S_MB_2U_LIB.S9S_MB_2U(SCH_1):GND
  EF55  GND            VSS1387  @S9S_MB_2U_LIB.S9S_MB_2U(SCH_1):GND
  EF53  GND            VSS1386  @S9S_MB_2U_LIB.S9S_MB_2U(SCH_1):GND
  EF49  GND            VSS1385  @S9S_MB_2U_LIB.S9S_MB_2U(SCH_1):GND
  EF47  GND            VSS1384  @S9S_MB_2U_LIB.S9S_MB_2U(SCH_1):GND
  EF44  GND            VSS1383  @S9S_MB_2U_LIB.S9S_MB_2U(SCH_1):GND
  EF42  GND            VSS1382  @S9S_MB_2U_LIB.S9S_MB_2U(SCH_1):GND
  EF40  GND            VSS1376  @S9S_MB_2U_LIB.S9S_MB_2U(SCH_1):GND
  EF4  GND            VSS1374  @S9S_MB_2U_LIB.S9S_MB_2U(SCH_1):GND
  EF38  GND            VSS1373  @S9S_MB_2U_LIB.S9S_MB_2U(SCH_1):GND
  EF36  GND            VSS1370  @S9S_MB_2U_LIB.S9S_MB_2U(SCH_1):GND
  EF34  GND            VSS1367  @S9S_MB_2U_LIB.S9S_MB_2U(SCH_1):GND
  EF32  GND            VSS1365  @S9S_MB_2U_LIB.S9S_MB_2U(SCH_1):GND
  EF30  GND            VSS1364  @S9S_MB_2U_LIB.S9S_MB_2U(SCH_1):GND
  EF28  GND            VSS1363  @S9S_MB_2U_LIB.S9S_MB_2U(SCH_1):GND
  EF26  GND            VSS1362  @S9S_MB_2U_LIB.S9S_MB_2U(SCH_1):GND
  EF24  GND            VSS1361  @S9S_MB_2U_LIB.S9S_MB_2U(SCH_1):GND
  EF22  GND            VSS1360  @S9S_MB_2U_LIB.S9S_MB_2U(SCH_1):GND
  EF20  GND            VSS1358  @S9S_MB_2U_LIB.S9S_MB_2U(SCH_1):GND
  EF2  GND            VSS1356  @S9S_MB_2U_LIB.S9S_MB_2U(SCH_1):GND
  EF18  GND            VSS1354  @S9S_MB_2U_LIB.S9S_MB_2U(SCH_1):GND
  EF16  GND            VSS1353  @S9S_MB_2U_LIB.S9S_MB_2U(SCH_1):GND
  EF12  GND            VSS1352  @S9S_MB_2U_LIB.S9S_MB_2U(SCH_1):GND
  EE88  GND            VSS1351  @S9S_MB_2U_LIB.S9S_MB_2U(SCH_1):GND
  EE80  GND            VSS1350  @S9S_MB_2U_LIB.S9S_MB_2U(SCH_1):GND
  EE78  GND            VSS1349  @S9S_MB_2U_LIB.S9S_MB_2U(SCH_1):GND
  ED8  GND            VSS1348  @S9S_MB_2U_LIB.S9S_MB_2U(SCH_1):GND
  ED49  GND            VSS1346  @S9S_MB_2U_LIB.S9S_MB_2U(SCH_1):GND
  ED4  GND            VSS1344  @S9S_MB_2U_LIB.S9S_MB_2U(SCH_1):GND
  ED36  GND            VSS1342  @S9S_MB_2U_LIB.S9S_MB_2U(SCH_1):GND
  ED30  GND            VSS1341  @S9S_MB_2U_LIB.S9S_MB_2U(SCH_1):GND
  ED24  GND            VSS1339  @S9S_MB_2U_LIB.S9S_MB_2U(SCH_1):GND
  ED16  GND            VSS1338  @S9S_MB_2U_LIB.S9S_MB_2U(SCH_1):GND
  EC9  GND            VSS1337  @S9S_MB_2U_LIB.S9S_MB_2U(SCH_1):GND
  EC88  GND            VSS1336  @S9S_MB_2U_LIB.S9S_MB_2U(SCH_1):GND
  EC84  GND            VSS1335  @S9S_MB_2U_LIB.S9S_MB_2U(SCH_1):GND
  EC82  GND            VSS1333  @S9S_MB_2U_LIB.S9S_MB_2U(SCH_1):GND
  EC74  GND            VSS1332  @S9S_MB_2U_LIB.S9S_MB_2U(SCH_1):GND
  EC72  GND            VSS1330  @S9S_MB_2U_LIB.S9S_MB_2U(SCH_1):GND
  EC66  GND            VSS1329  @S9S_MB_2U_LIB.S9S_MB_2U(SCH_1):GND
  EC56  GND            VSS1327  @S9S_MB_2U_LIB.S9S_MB_2U(SCH_1):GND
  EC50  GND            VSS1326  @S9S_MB_2U_LIB.S9S_MB_2U(SCH_1):GND
  EC48  GND            VSS1324  @S9S_MB_2U_LIB.S9S_MB_2U(SCH_1):GND
  EC43  GND            VSS1323  @S9S_MB_2U_LIB.S9S_MB_2U(SCH_1):GND
  EC41  GND            VSS1321  @S9S_MB_2U_LIB.S9S_MB_2U(SCH_1):GND
  EH6  GND            VSS1318  @S9S_MB_2U_LIB.S9S_MB_2U(SCH_1):GND
  EC37  GND            VSS1317  @S9S_MB_2U_LIB.S9S_MB_2U(SCH_1):GND
  EC31  GND            VSS1316  @S9S_MB_2U_LIB.S9S_MB_2U(SCH_1):GND
  EC29  GND            VSS1314  @S9S_MB_2U_LIB.S9S_MB_2U(SCH_1):GND
  EC23  GND            VSS1313  @S9S_MB_2U_LIB.S9S_MB_2U(SCH_1):GND
  EC19  GND            VSS1311  @S9S_MB_2U_LIB.S9S_MB_2U(SCH_1):GND
  EC13  GND            VSS1310  @S9S_MB_2U_LIB.S9S_MB_2U(SCH_1):GND
  EC1  GND            VSS1309  @S9S_MB_2U_LIB.S9S_MB_2U(SCH_1):GND
  EB87  GND            VSS1308  @S9S_MB_2U_LIB.S9S_MB_2U(SCH_1):GND
  EB83  GND            VSS1307  @S9S_MB_2U_LIB.S9S_MB_2U(SCH_1):GND
  EB8  GND            VSS1306  @S9S_MB_2U_LIB.S9S_MB_2U(SCH_1):GND
  EH18  GND            VSS1305  @S9S_MB_2U_LIB.S9S_MB_2U(SCH_1):GND
  EB79  GND            VSS1304  @S9S_MB_2U_LIB.S9S_MB_2U(SCH_1):GND
  EH14  GND            VSS1303  @S9S_MB_2U_LIB.S9S_MB_2U(SCH_1):GND
  EH12  GND            VSS1302  @S9S_MB_2U_LIB.S9S_MB_2U(SCH_1):GND
  EB75  GND            VSS1301  @S9S_MB_2U_LIB.S9S_MB_2U(SCH_1):GND
  EB71  GND            VSS1300  @S9S_MB_2U_LIB.S9S_MB_2U(SCH_1):GND
  EB69  GND            VSS1299  @S9S_MB_2U_LIB.S9S_MB_2U(SCH_1):GND
  EB65  GND            VSS1298  @S9S_MB_2U_LIB.S9S_MB_2U(SCH_1):GND
  EB57  GND            VSS1297  @S9S_MB_2U_LIB.S9S_MB_2U(SCH_1):GND
  EB47  GND            VSS1296  @S9S_MB_2U_LIB.S9S_MB_2U(SCH_1):GND
  EB40  GND            VSS1295  @S9S_MB_2U_LIB.S9S_MB_2U(SCH_1):GND
  EG7  GND            VSS1294  @S9S_MB_2U_LIB.S9S_MB_2U(SCH_1):GND
  EB38  GND            VSS1293  @S9S_MB_2U_LIB.S9S_MB_2U(SCH_1):GND
  EB32  GND            VSS1292  @S9S_MB_2U_LIB.S9S_MB_2U(SCH_1):GND
  EG52  GND            VSS1291  @S9S_MB_2U_LIB.S9S_MB_2U(SCH_1):GND
  EG5  GND            VSS1290  @S9S_MB_2U_LIB.S9S_MB_2U(SCH_1):GND
  EB28  GND            VSS1289  @S9S_MB_2U_LIB.S9S_MB_2U(SCH_1):GND
  EB22  GND            VSS1288  @S9S_MB_2U_LIB.S9S_MB_2U(SCH_1):GND
  EB12  GND            VSS1287  @S9S_MB_2U_LIB.S9S_MB_2U(SCH_1):GND
  EA88  GND            VSS1286  @S9S_MB_2U_LIB.S9S_MB_2U(SCH_1):GND
  EA84  GND            VSS1285  @S9S_MB_2U_LIB.S9S_MB_2U(SCH_1):GND
  EG13  GND            VSS1284  @S9S_MB_2U_LIB.S9S_MB_2U(SCH_1):GND
  EF89  GND            VSS1283  @S9S_MB_2U_LIB.S9S_MB_2U(SCH_1):GND
  EA80  GND            VSS1282  @S9S_MB_2U_LIB.S9S_MB_2U(SCH_1):GND
  EA78  GND            VSS1281  @S9S_MB_2U_LIB.S9S_MB_2U(SCH_1):GND
  EA76  GND            VSS1280  @S9S_MB_2U_LIB.S9S_MB_2U(SCH_1):GND
  EA70  GND            VSS1279  @S9S_MB_2U_LIB.S9S_MB_2U(SCH_1):GND
  EA33  GND            VSS1278  @S9S_MB_2U_LIB.S9S_MB_2U(SCH_1):GND
  EF75  GND            VSS1277  @S9S_MB_2U_LIB.S9S_MB_2U(SCH_1):GND
  EF73  GND            VSS1276  @S9S_MB_2U_LIB.S9S_MB_2U(SCH_1):GND
  EA27  GND            VSS1275  @S9S_MB_2U_LIB.S9S_MB_2U(SCH_1):GND
  EA21  GND            VSS1274  @S9S_MB_2U_LIB.S9S_MB_2U(SCH_1):GND
  DY8  GND            VSS1270  @S9S_MB_2U_LIB.S9S_MB_2U(SCH_1):GND
  DY77  GND            VSS1269  @S9S_MB_2U_LIB.S9S_MB_2U(SCH_1):GND
  DW88  GND            VSS1267  @S9S_MB_2U_LIB.S9S_MB_2U(SCH_1):GND
  DW84  GND            VSS1266  @S9S_MB_2U_LIB.S9S_MB_2U(SCH_1):GND
  EF51  GND            VSS1265  @S9S_MB_2U_LIB.S9S_MB_2U(SCH_1):GND
  DW82  GND            VSS1264  @S9S_MB_2U_LIB.S9S_MB_2U(SCH_1):GND
  DW80  GND            VSS1263  @S9S_MB_2U_LIB.S9S_MB_2U(SCH_1):GND
  DW76  GND            VSS1262  @S9S_MB_2U_LIB.S9S_MB_2U(SCH_1):GND
  DW74  GND            VSS1261  @S9S_MB_2U_LIB.S9S_MB_2U(SCH_1):GND
  DW72  GND            VSS1260  @S9S_MB_2U_LIB.S9S_MB_2U(SCH_1):GND
  DW70  GND            VSS1259  @S9S_MB_2U_LIB.S9S_MB_2U(SCH_1):GND
  DW68  GND            VSS1258  @S9S_MB_2U_LIB.S9S_MB_2U(SCH_1):GND
  DW66  GND            VSS1257  @S9S_MB_2U_LIB.S9S_MB_2U(SCH_1):GND
  EE52  GND            VSS1237  @S9S_MB_2U_LIB.S9S_MB_2U(SCH_1):GND
  EE39  GND            VSS1235  @S9S_MB_2U_LIB.S9S_MB_2U(SCH_1):GND
  EE17  GND            VSS1232  @S9S_MB_2U_LIB.S9S_MB_2U(SCH_1):GND
  ED73  GND            VSS1225  @S9S_MB_2U_LIB.S9S_MB_2U(SCH_1):GND
  ED67  GND            VSS1224  @S9S_MB_2U_LIB.S9S_MB_2U(SCH_1):GND
  ED61  GND            VSS1223  @S9S_MB_2U_LIB.S9S_MB_2U(SCH_1):GND
  ED55  GND            VSS1220  @S9S_MB_2U_LIB.S9S_MB_2U(SCH_1):GND
  ED42  GND            VSS1217  @S9S_MB_2U_LIB.S9S_MB_2U(SCH_1):GND
  ED18  GND            VSS1210  @S9S_MB_2U_LIB.S9S_MB_2U(SCH_1):GND
  ED12  GND            VSS1208  @S9S_MB_2U_LIB.S9S_MB_2U(SCH_1):GND
  EC68  GND            VSS1200  @S9S_MB_2U_LIB.S9S_MB_2U(SCH_1):GND
  EC62  GND            VSS1198  @S9S_MB_2U_LIB.S9S_MB_2U(SCH_1):GND
  EC60  GND            VSS1197  @S9S_MB_2U_LIB.S9S_MB_2U(SCH_1):GND
  EC54  GND            VSS1195  @S9S_MB_2U_LIB.S9S_MB_2U(SCH_1):GND
  EC5  GND            VSS1193  @S9S_MB_2U_LIB.S9S_MB_2U(SCH_1):GND
  EC35  GND            VSS1188  @S9S_MB_2U_LIB.S9S_MB_2U(SCH_1):GND
  EC25  GND            VSS1185  @S9S_MB_2U_LIB.S9S_MB_2U(SCH_1):GND
  EB91  GND            VSS1180  @S9S_MB_2U_LIB.S9S_MB_2U(SCH_1):GND
  EB63  GND            VSS1171  @S9S_MB_2U_LIB.S9S_MB_2U(SCH_1):GND
  EB59  GND            VSS1170  @S9S_MB_2U_LIB.S9S_MB_2U(SCH_1):GND
  EB53  GND            VSS1168  @S9S_MB_2U_LIB.S9S_MB_2U(SCH_1):GND
  EB51  GND            VSS1167  @S9S_MB_2U_LIB.S9S_MB_2U(SCH_1):GND
  EB44  GND            VSS1165  @S9S_MB_2U_LIB.S9S_MB_2U(SCH_1):GND
  EB4  GND            VSS1163  @S9S_MB_2U_LIB.S9S_MB_2U(SCH_1):GND
  EB34  GND            VSS1161  @S9S_MB_2U_LIB.S9S_MB_2U(SCH_1):GND
  EB26  GND            VSS1158  @S9S_MB_2U_LIB.S9S_MB_2U(SCH_1):GND
  EB20  GND            VSS1156  @S9S_MB_2U_LIB.S9S_MB_2U(SCH_1):GND
  EB16  GND            VSS1155  @S9S_MB_2U_LIB.S9S_MB_2U(SCH_1):GND
  EA64  GND            VSS1146  @S9S_MB_2U_LIB.S9S_MB_2U(SCH_1):GND
  EA58  GND            VSS1145  @S9S_MB_2U_LIB.S9S_MB_2U(SCH_1):GND
  EA52  GND            VSS1144  @S9S_MB_2U_LIB.S9S_MB_2U(SCH_1):GND
  EA45  GND            VSS1142  @S9S_MB_2U_LIB.S9S_MB_2U(SCH_1):GND
  EA39  GND            VSS1141  @S9S_MB_2U_LIB.S9S_MB_2U(SCH_1):GND
  DY42  GND            VSS1116  @S9S_MB_2U_LIB.S9S_MB_2U(SCH_1):GND
  DY4  GND            VSS1115  @S9S_MB_2U_LIB.S9S_MB_2U(SCH_1):GND
  DY16  GND            VSS1112  @S9S_MB_2U_LIB.S9S_MB_2U(SCH_1):GND
  DY12  GND            VSS1111  @S9S_MB_2U_LIB.S9S_MB_2U(SCH_1):GND

SOCKET4677_AZIFS054P001C01  I1   U2     [SOCKET4677_AZIFS054P001C01-SOCA]
  ET57  GND            VSS1569  @S9S_MB_2U_LIB.S9S_MB_2U(SCH_1):GND
  ET38  GND            VSS1565  @S9S_MB_2U_LIB.S9S_MB_2U(SCH_1):GND
  ET34  GND            VSS1563  @S9S_MB_2U_LIB.S9S_MB_2U(SCH_1):GND
  ET28  GND            VSS1562  @S9S_MB_2U_LIB.S9S_MB_2U(SCH_1):GND
  ET22  GND            VSS1561  @S9S_MB_2U_LIB.S9S_MB_2U(SCH_1):GND
  ET16  GND            VSS1559  @S9S_MB_2U_LIB.S9S_MB_2U(SCH_1):GND
  ET10  GND            VSS1557  @S9S_MB_2U_LIB.S9S_MB_2U(SCH_1):GND
  ER86  GND            VSS1556  @S9S_MB_2U_LIB.S9S_MB_2U(SCH_1):GND
  ER84  GND            VSS1555  @S9S_MB_2U_LIB.S9S_MB_2U(SCH_1):GND
  ER80  GND            VSS1554  @S9S_MB_2U_LIB.S9S_MB_2U(SCH_1):GND
  ER78  GND            VSS1553  @S9S_MB_2U_LIB.S9S_MB_2U(SCH_1):GND
  ER74  GND            VSS1552  @S9S_MB_2U_LIB.S9S_MB_2U(SCH_1):GND
  ER70  GND            VSS1551  @S9S_MB_2U_LIB.S9S_MB_2U(SCH_1):GND
  ER7  GND            VSS1550  @S9S_MB_2U_LIB.S9S_MB_2U(SCH_1):GND
  ER5  GND            VSS1549  @S9S_MB_2U_LIB.S9S_MB_2U(SCH_1):GND
  ER33  GND            VSS1548  @S9S_MB_2U_LIB.S9S_MB_2U(SCH_1):GND
  ER27  GND            VSS1547  @S9S_MB_2U_LIB.S9S_MB_2U(SCH_1):GND
  EP83  GND            VSS1545  @S9S_MB_2U_LIB.S9S_MB_2U(SCH_1):GND
  EP67  GND            VSS1543  @S9S_MB_2U_LIB.S9S_MB_2U(SCH_1):GND
  EN80  GND            VSS1542  @S9S_MB_2U_LIB.S9S_MB_2U(SCH_1):GND
  EN78  GND            VSS1541  @S9S_MB_2U_LIB.S9S_MB_2U(SCH_1):GND
  EN64  GND            VSS1540  @S9S_MB_2U_LIB.S9S_MB_2U(SCH_1):GND
  EN56  GND            VSS1539  @S9S_MB_2U_LIB.S9S_MB_2U(SCH_1):GND
  EN54  GND            VSS1537  @S9S_MB_2U_LIB.S9S_MB_2U(SCH_1):GND
  EN52  GND            VSS1533  @S9S_MB_2U_LIB.S9S_MB_2U(SCH_1):GND
  EN50  GND            VSS1531  @S9S_MB_2U_LIB.S9S_MB_2U(SCH_1):GND
  EN48  GND            VSS1530  @S9S_MB_2U_LIB.S9S_MB_2U(SCH_1):GND
  EN45  GND            VSS1529  @S9S_MB_2U_LIB.S9S_MB_2U(SCH_1):GND
  EN43  GND            VSS1528  @S9S_MB_2U_LIB.S9S_MB_2U(SCH_1):GND
  EN41  GND            VSS1526  @S9S_MB_2U_LIB.S9S_MB_2U(SCH_1):GND
  EN37  GND            VSS1525  @S9S_MB_2U_LIB.S9S_MB_2U(SCH_1):GND
  EN35  GND            VSS1524  @S9S_MB_2U_LIB.S9S_MB_2U(SCH_1):GND
  EN33  GND            VSS1522  @S9S_MB_2U_LIB.S9S_MB_2U(SCH_1):GND
  EN31  GND            VSS1520  @S9S_MB_2U_LIB.S9S_MB_2U(SCH_1):GND
  EN29  GND            VSS1518  @S9S_MB_2U_LIB.S9S_MB_2U(SCH_1):GND
  EN27  GND            VSS1517  @S9S_MB_2U_LIB.S9S_MB_2U(SCH_1):GND
  EN25  GND            VSS1515  @S9S_MB_2U_LIB.S9S_MB_2U(SCH_1):GND
  EN23  GND            VSS1513  @S9S_MB_2U_LIB.S9S_MB_2U(SCH_1):GND
  EN21  GND            VSS1512  @S9S_MB_2U_LIB.S9S_MB_2U(SCH_1):GND
  EN19  GND            VSS1506  @S9S_MB_2U_LIB.S9S_MB_2U(SCH_1):GND
  EN17  GND            VSS1505  @S9S_MB_2U_LIB.S9S_MB_2U(SCH_1):GND
  EN15  GND            VSS1503  @S9S_MB_2U_LIB.S9S_MB_2U(SCH_1):GND
  EN13  GND            VSS1501  @S9S_MB_2U_LIB.S9S_MB_2U(SCH_1):GND
  EN11  GND            VSS1500  @S9S_MB_2U_LIB.S9S_MB_2U(SCH_1):GND
  EM83  GND            VSS1499  @S9S_MB_2U_LIB.S9S_MB_2U(SCH_1):GND
  EM81  GND            VSS1498  @S9S_MB_2U_LIB.S9S_MB_2U(SCH_1):GND
  EM8  GND            VSS1497  @S9S_MB_2U_LIB.S9S_MB_2U(SCH_1):GND
  EM73  GND            VSS1496  @S9S_MB_2U_LIB.S9S_MB_2U(SCH_1):GND
  ET59  GND            VSS1493  @S9S_MB_2U_LIB.S9S_MB_2U(SCH_1):GND
  EM42  GND            VSS1492  @S9S_MB_2U_LIB.S9S_MB_2U(SCH_1):GND
  ET53  GND            VSS1491  @S9S_MB_2U_LIB.S9S_MB_2U(SCH_1):GND
  EL76  GND            VSS1489  @S9S_MB_2U_LIB.S9S_MB_2U(SCH_1):GND
  EL64  GND            VSS1488  @S9S_MB_2U_LIB.S9S_MB_2U(SCH_1):GND
  EL5  GND            VSS1486  @S9S_MB_2U_LIB.S9S_MB_2U(SCH_1):GND
  EL45  GND            VSS1485  @S9S_MB_2U_LIB.S9S_MB_2U(SCH_1):GND
  ET32  GND            VSS1484  @S9S_MB_2U_LIB.S9S_MB_2U(SCH_1):GND
  EL39  GND            VSS1483  @S9S_MB_2U_LIB.S9S_MB_2U(SCH_1):GND
  ET26  GND            VSS1482  @S9S_MB_2U_LIB.S9S_MB_2U(SCH_1):GND
  EL33  GND            VSS1481  @S9S_MB_2U_LIB.S9S_MB_2U(SCH_1):GND
  ET20  GND            VSS1480  @S9S_MB_2U_LIB.S9S_MB_2U(SCH_1):GND
  EL3  GND            VSS1479  @S9S_MB_2U_LIB.S9S_MB_2U(SCH_1):GND
  ET14  GND            VSS1478  @S9S_MB_2U_LIB.S9S_MB_2U(SCH_1):GND
  EL27  GND            VSS1477  @S9S_MB_2U_LIB.S9S_MB_2U(SCH_1):GND
  ER9  GND            VSS1476  @S9S_MB_2U_LIB.S9S_MB_2U(SCH_1):GND
  EL21  GND            VSS1475  @S9S_MB_2U_LIB.S9S_MB_2U(SCH_1):GND
  EK75  GND            VSS1474  @S9S_MB_2U_LIB.S9S_MB_2U(SCH_1):GND
  EK69  GND            VSS1473  @S9S_MB_2U_LIB.S9S_MB_2U(SCH_1):GND
  EK65  GND            VSS1472  @S9S_MB_2U_LIB.S9S_MB_2U(SCH_1):GND
  EK57  GND            VSS1471  @S9S_MB_2U_LIB.S9S_MB_2U(SCH_1):GND
  EK47  GND            VSS1470  @S9S_MB_2U_LIB.S9S_MB_2U(SCH_1):GND
  EK40  GND            VSS1469  @S9S_MB_2U_LIB.S9S_MB_2U(SCH_1):GND
  ER64  GND            VSS1468  @S9S_MB_2U_LIB.S9S_MB_2U(SCH_1):GND
  ER58  GND            VSS1467  @S9S_MB_2U_LIB.S9S_MB_2U(SCH_1):GND
  EK4  GND            VSS1466  @S9S_MB_2U_LIB.S9S_MB_2U(SCH_1):GND
  EK38  GND            VSS1465  @S9S_MB_2U_LIB.S9S_MB_2U(SCH_1):GND
  ER52  GND            VSS1464  @S9S_MB_2U_LIB.S9S_MB_2U(SCH_1):GND
  EK34  GND            VSS1463  @S9S_MB_2U_LIB.S9S_MB_2U(SCH_1):GND
  ER39  GND            VSS1462  @S9S_MB_2U_LIB.S9S_MB_2U(SCH_1):GND
  EK32  GND            VSS1461  @S9S_MB_2U_LIB.S9S_MB_2U(SCH_1):GND
  EK28  GND            VSS1460  @S9S_MB_2U_LIB.S9S_MB_2U(SCH_1):GND
  EK22  GND            VSS1459  @S9S_MB_2U_LIB.S9S_MB_2U(SCH_1):GND
  EK2  GND            VSS1458  @S9S_MB_2U_LIB.S9S_MB_2U(SCH_1):GND
  ER21  GND            VSS1457  @S9S_MB_2U_LIB.S9S_MB_2U(SCH_1):GND
  ER15  GND            VSS1456  @S9S_MB_2U_LIB.S9S_MB_2U(SCH_1):GND
  EK14  GND            VSS1455  @S9S_MB_2U_LIB.S9S_MB_2U(SCH_1):GND
  EP77  GND            VSS1454  @S9S_MB_2U_LIB.S9S_MB_2U(SCH_1):GND
  EP71  GND            VSS1453  @S9S_MB_2U_LIB.S9S_MB_2U(SCH_1):GND
  EP69  GND            VSS1452  @S9S_MB_2U_LIB.S9S_MB_2U(SCH_1):GND
  EK10  GND            VSS1451  @S9S_MB_2U_LIB.S9S_MB_2U(SCH_1):GND
  EJ9  GND            VSS1450  @S9S_MB_2U_LIB.S9S_MB_2U(SCH_1):GND
  EJ88  GND            VSS1449  @S9S_MB_2U_LIB.S9S_MB_2U(SCH_1):GND
  EJ78  GND            VSS1448  @S9S_MB_2U_LIB.S9S_MB_2U(SCH_1):GND
  EJ74  GND            VSS1447  @S9S_MB_2U_LIB.S9S_MB_2U(SCH_1):GND
  EN9  GND            VSS1446  @S9S_MB_2U_LIB.S9S_MB_2U(SCH_1):GND
  EN88  GND            VSS1445  @S9S_MB_2U_LIB.S9S_MB_2U(SCH_1):GND
  EJ7  GND            VSS1444  @S9S_MB_2U_LIB.S9S_MB_2U(SCH_1):GND
  EJ66  GND            VSS1443  @S9S_MB_2U_LIB.S9S_MB_2U(SCH_1):GND
  EJ60  GND            VSS1442  @S9S_MB_2U_LIB.S9S_MB_2U(SCH_1):GND
  EN72  GND            VSS1441  @S9S_MB_2U_LIB.S9S_MB_2U(SCH_1):GND
  EN66  GND            VSS1440  @S9S_MB_2U_LIB.S9S_MB_2U(SCH_1):GND
  EJ56  GND            VSS1439  @S9S_MB_2U_LIB.S9S_MB_2U(SCH_1):GND
  EN62  GND            VSS1438  @S9S_MB_2U_LIB.S9S_MB_2U(SCH_1):GND
  EN60  GND            VSS1437  @S9S_MB_2U_LIB.S9S_MB_2U(SCH_1):GND
  EN58  GND            VSS1436  @S9S_MB_2U_LIB.S9S_MB_2U(SCH_1):GND
  EJ50  GND            VSS1435  @S9S_MB_2U_LIB.S9S_MB_2U(SCH_1):GND
  EJ48  GND            VSS1434  @S9S_MB_2U_LIB.S9S_MB_2U(SCH_1):GND
  EJ43  GND            VSS1433  @S9S_MB_2U_LIB.S9S_MB_2U(SCH_1):GND
  EJ41  GND            VSS1432  @S9S_MB_2U_LIB.S9S_MB_2U(SCH_1):GND
  EJ37  GND            VSS1431  @S9S_MB_2U_LIB.S9S_MB_2U(SCH_1):GND
  EJ31  GND            VSS1430  @S9S_MB_2U_LIB.S9S_MB_2U(SCH_1):GND
  EJ29  GND            VSS1429  @S9S_MB_2U_LIB.S9S_MB_2U(SCH_1):GND
  EJ23  GND            VSS1428  @S9S_MB_2U_LIB.S9S_MB_2U(SCH_1):GND
  EN39  GND            VSS1427  @S9S_MB_2U_LIB.S9S_MB_2U(SCH_1):GND
  EJ19  GND            VSS1426  @S9S_MB_2U_LIB.S9S_MB_2U(SCH_1):GND
  EJ13  GND            VSS1425  @S9S_MB_2U_LIB.S9S_MB_2U(SCH_1):GND
  EH83  GND            VSS1424  @S9S_MB_2U_LIB.S9S_MB_2U(SCH_1):GND
  EH81  GND            VSS1423  @S9S_MB_2U_LIB.S9S_MB_2U(SCH_1):GND
  EH73  GND            VSS1422  @S9S_MB_2U_LIB.S9S_MB_2U(SCH_1):GND
  EH49  GND            VSS1421  @S9S_MB_2U_LIB.S9S_MB_2U(SCH_1):GND
  EH36  GND            VSS1419  @S9S_MB_2U_LIB.S9S_MB_2U(SCH_1):GND
  EM79  GND            VSS1409  @S9S_MB_2U_LIB.S9S_MB_2U(SCH_1):GND
  EM49  GND            VSS1405  @S9S_MB_2U_LIB.S9S_MB_2U(SCH_1):GND
  EL9  GND            VSS1401  @S9S_MB_2U_LIB.S9S_MB_2U(SCH_1):GND
  EL86  GND            VSS1400  @S9S_MB_2U_LIB.S9S_MB_2U(SCH_1):GND
  EL72  GND            VSS1398  @S9S_MB_2U_LIB.S9S_MB_2U(SCH_1):GND
  EL70  GND            VSS1397  @S9S_MB_2U_LIB.S9S_MB_2U(SCH_1):GND
  EL7  GND            VSS1396  @S9S_MB_2U_LIB.S9S_MB_2U(SCH_1):GND
  EL58  GND            VSS1394  @S9S_MB_2U_LIB.S9S_MB_2U(SCH_1):GND
  EL52  GND            VSS1391  @S9S_MB_2U_LIB.S9S_MB_2U(SCH_1):GND
  EL15  GND            VSS1381  @S9S_MB_2U_LIB.S9S_MB_2U(SCH_1):GND
  EK89  GND            VSS1380  @S9S_MB_2U_LIB.S9S_MB_2U(SCH_1):GND
  EK83  GND            VSS1379  @S9S_MB_2U_LIB.S9S_MB_2U(SCH_1):GND
  EK79  GND            VSS1378  @S9S_MB_2U_LIB.S9S_MB_2U(SCH_1):GND
  EK77  GND            VSS1377  @S9S_MB_2U_LIB.S9S_MB_2U(SCH_1):GND
  EK71  GND            VSS1375  @S9S_MB_2U_LIB.S9S_MB_2U(SCH_1):GND
  EK63  GND            VSS1372  @S9S_MB_2U_LIB.S9S_MB_2U(SCH_1):GND
  EK59  GND            VSS1371  @S9S_MB_2U_LIB.S9S_MB_2U(SCH_1):GND
  EK53  GND            VSS1369  @S9S_MB_2U_LIB.S9S_MB_2U(SCH_1):GND
  EK51  GND            VSS1368  @S9S_MB_2U_LIB.S9S_MB_2U(SCH_1):GND
  EK44  GND            VSS1366  @S9S_MB_2U_LIB.S9S_MB_2U(SCH_1):GND
  EK26  GND            VSS1359  @S9S_MB_2U_LIB.S9S_MB_2U(SCH_1):GND
  EK20  GND            VSS1357  @S9S_MB_2U_LIB.S9S_MB_2U(SCH_1):GND
  EK16  GND            VSS1355  @S9S_MB_2U_LIB.S9S_MB_2U(SCH_1):GND
  EJ72  GND            VSS1347  @S9S_MB_2U_LIB.S9S_MB_2U(SCH_1):GND
  EJ68  GND            VSS1345  @S9S_MB_2U_LIB.S9S_MB_2U(SCH_1):GND
  EJ62  GND            VSS1343  @S9S_MB_2U_LIB.S9S_MB_2U(SCH_1):GND
  EJ54  GND            VSS1340  @S9S_MB_2U_LIB.S9S_MB_2U(SCH_1):GND
  EJ35  GND            VSS1334  @S9S_MB_2U_LIB.S9S_MB_2U(SCH_1):GND
  EJ25  GND            VSS1331  @S9S_MB_2U_LIB.S9S_MB_2U(SCH_1):GND
  EJ17  GND            VSS1328  @S9S_MB_2U_LIB.S9S_MB_2U(SCH_1):GND
  EJ11  GND            VSS1325  @S9S_MB_2U_LIB.S9S_MB_2U(SCH_1):GND
  EH79  GND            VSS1322  @S9S_MB_2U_LIB.S9S_MB_2U(SCH_1):GND
  EH67  GND            VSS1320  @S9S_MB_2U_LIB.S9S_MB_2U(SCH_1):GND
  EH61  GND            VSS1319  @S9S_MB_2U_LIB.S9S_MB_2U(SCH_1):GND
  EH55  GND            VSS1315  @S9S_MB_2U_LIB.S9S_MB_2U(SCH_1):GND
  EH42  GND            VSS1312  @S9S_MB_2U_LIB.S9S_MB_2U(SCH_1):GND
  ER50  GND            GND_ER50  @S9S_MB_2U_LIB.S9S_MB_2U(SCH_1):GND
  ER48  GND            GND_ER48  @S9S_MB_2U_LIB.S9S_MB_2U(SCH_1):GND
  ER43  GND            GND_ER43  @S9S_MB_2U_LIB.S9S_MB_2U(SCH_1):GND
  ER41  GND            GND_ER41  @S9S_MB_2U_LIB.S9S_MB_2U(SCH_1):GND

SOCKET4677_AZIFS054P001C01  I4   U2     [SOCKET4677_AZIFS054P001C01-SOCA]
  Y89  PVCCFA_EHV_FIVRA_CPU0  VCCFA_EHV_FIVRA104  @S9S_MB_2U_LIB.S9S_MB_2U(SCH_1):PVCCFA_EHV_FIVRA_CPU0
  Y85  PVCCFA_EHV_FIVRA_CPU0  VCCFA_EHV_FIVRA103  @S9S_MB_2U_LIB.S9S_MB_2U(SCH_1):PVCCFA_EHV_FIVRA_CPU0
  Y79  PVCCFA_EHV_FIVRA_CPU0  VCCFA_EHV_FIVRA102  @S9S_MB_2U_LIB.S9S_MB_2U(SCH_1):PVCCFA_EHV_FIVRA_CPU0
  W80  PVCCFA_EHV_FIVRA_CPU0  VCCFA_EHV_FIVRA101  @S9S_MB_2U_LIB.S9S_MB_2U(SCH_1):PVCCFA_EHV_FIVRA_CPU0
   U7  PVCCFA_EHV_FIVRA_CPU0  VCCFA_EHV_FIVRA100  @S9S_MB_2U_LIB.S9S_MB_2U(SCH_1):PVCCFA_EHV_FIVRA_CPU0
  U15  PVCCFA_EHV_FIVRA_CPU0  VCCFA_EHV_FIVRA99  @S9S_MB_2U_LIB.S9S_MB_2U(SCH_1):PVCCFA_EHV_FIVRA_CPU0
  U11  PVCCFA_EHV_FIVRA_CPU0  VCCFA_EHV_FIVRA98  @S9S_MB_2U_LIB.S9S_MB_2U(SCH_1):PVCCFA_EHV_FIVRA_CPU0
  T89  PVCCFA_EHV_FIVRA_CPU0  VCCFA_EHV_FIVRA97  @S9S_MB_2U_LIB.S9S_MB_2U(SCH_1):PVCCFA_EHV_FIVRA_CPU0
  T85  PVCCFA_EHV_FIVRA_CPU0  VCCFA_EHV_FIVRA96  @S9S_MB_2U_LIB.S9S_MB_2U(SCH_1):PVCCFA_EHV_FIVRA_CPU0
  R80  PVCCFA_EHV_FIVRA_CPU0  VCCFA_EHV_FIVRA95  @S9S_MB_2U_LIB.S9S_MB_2U(SCH_1):PVCCFA_EHV_FIVRA_CPU0
  P79  PVCCFA_EHV_FIVRA_CPU0  VCCFA_EHV_FIVRA94  @S9S_MB_2U_LIB.S9S_MB_2U(SCH_1):PVCCFA_EHV_FIVRA_CPU0
   N7  PVCCFA_EHV_FIVRA_CPU0  VCCFA_EHV_FIVRA93  @S9S_MB_2U_LIB.S9S_MB_2U(SCH_1):PVCCFA_EHV_FIVRA_CPU0
  N11  PVCCFA_EHV_FIVRA_CPU0  VCCFA_EHV_FIVRA92  @S9S_MB_2U_LIB.S9S_MB_2U(SCH_1):PVCCFA_EHV_FIVRA_CPU0
  M89  PVCCFA_EHV_FIVRA_CPU0  VCCFA_EHV_FIVRA91  @S9S_MB_2U_LIB.S9S_MB_2U(SCH_1):PVCCFA_EHV_FIVRA_CPU0
  M85  PVCCFA_EHV_FIVRA_CPU0  VCCFA_EHV_FIVRA90  @S9S_MB_2U_LIB.S9S_MB_2U(SCH_1):PVCCFA_EHV_FIVRA_CPU0
  L84  PVCCFA_EHV_FIVRA_CPU0  VCCFA_EHV_FIVRA89  @S9S_MB_2U_LIB.S9S_MB_2U(SCH_1):PVCCFA_EHV_FIVRA_CPU0
  K87  PVCCFA_EHV_FIVRA_CPU0  VCCFA_EHV_FIVRA88  @S9S_MB_2U_LIB.S9S_MB_2U(SCH_1):PVCCFA_EHV_FIVRA_CPU0
  J80  PVCCFA_EHV_FIVRA_CPU0  VCCFA_EHV_FIVRA87  @S9S_MB_2U_LIB.S9S_MB_2U(SCH_1):PVCCFA_EHV_FIVRA_CPU0
   J7  PVCCFA_EHV_FIVRA_CPU0  VCCFA_EHV_FIVRA86  @S9S_MB_2U_LIB.S9S_MB_2U(SCH_1):PVCCFA_EHV_FIVRA_CPU0
  J11  PVCCFA_EHV_FIVRA_CPU0  VCCFA_EHV_FIVRA85  @S9S_MB_2U_LIB.S9S_MB_2U(SCH_1):PVCCFA_EHV_FIVRA_CPU0
  H89  PVCCFA_EHV_FIVRA_CPU0  VCCFA_EHV_FIVRA84  @S9S_MB_2U_LIB.S9S_MB_2U(SCH_1):PVCCFA_EHV_FIVRA_CPU0
  EN84  PVCCFA_EHV_FIVRA_CPU0  VCCFA_EHV_FIVRA83  @S9S_MB_2U_LIB.S9S_MB_2U(SCH_1):PVCCFA_EHV_FIVRA_CPU0
  EJ84  PVCCFA_EHV_FIVRA_CPU0  VCCFA_EHV_FIVRA82  @S9S_MB_2U_LIB.S9S_MB_2U(SCH_1):PVCCFA_EHV_FIVRA_CPU0
  EJ15  PVCCFA_EHV_FIVRA_CPU0  VCCFA_EHV_FIVRA81  @S9S_MB_2U_LIB.S9S_MB_2U(SCH_1):PVCCFA_EHV_FIVRA_CPU0
  EG80  PVCCFA_EHV_FIVRA_CPU0  VCCFA_EHV_FIVRA80  @S9S_MB_2U_LIB.S9S_MB_2U(SCH_1):PVCCFA_EHV_FIVRA_CPU0
  EF79  PVCCFA_EHV_FIVRA_CPU0  VCCFA_EHV_FIVRA79  @S9S_MB_2U_LIB.S9S_MB_2U(SCH_1):PVCCFA_EHV_FIVRA_CPU0
  EE84  PVCCFA_EHV_FIVRA_CPU0  VCCFA_EHV_FIVRA78  @S9S_MB_2U_LIB.S9S_MB_2U(SCH_1):PVCCFA_EHV_FIVRA_CPU0
  EE7  PVCCFA_EHV_FIVRA_CPU0  VCCFA_EHV_FIVRA77  @S9S_MB_2U_LIB.S9S_MB_2U(SCH_1):PVCCFA_EHV_FIVRA_CPU0
  EE15  PVCCFA_EHV_FIVRA_CPU0  VCCFA_EHV_FIVRA76  @S9S_MB_2U_LIB.S9S_MB_2U(SCH_1):PVCCFA_EHV_FIVRA_CPU0
  EE11  PVCCFA_EHV_FIVRA_CPU0  VCCFA_EHV_FIVRA75  @S9S_MB_2U_LIB.S9S_MB_2U(SCH_1):PVCCFA_EHV_FIVRA_CPU0
  ED89  PVCCFA_EHV_FIVRA_CPU0  VCCFA_EHV_FIVRA74  @S9S_MB_2U_LIB.S9S_MB_2U(SCH_1):PVCCFA_EHV_FIVRA_CPU0
  ED85  PVCCFA_EHV_FIVRA_CPU0  VCCFA_EHV_FIVRA73  @S9S_MB_2U_LIB.S9S_MB_2U(SCH_1):PVCCFA_EHV_FIVRA_CPU0
  ED79  PVCCFA_EHV_FIVRA_CPU0  VCCFA_EHV_FIVRA72  @S9S_MB_2U_LIB.S9S_MB_2U(SCH_1):PVCCFA_EHV_FIVRA_CPU0
  EC78  PVCCFA_EHV_FIVRA_CPU0  VCCFA_EHV_FIVRA71  @S9S_MB_2U_LIB.S9S_MB_2U(SCH_1):PVCCFA_EHV_FIVRA_CPU0
  EA7  PVCCFA_EHV_FIVRA_CPU0  VCCFA_EHV_FIVRA70  @S9S_MB_2U_LIB.S9S_MB_2U(SCH_1):PVCCFA_EHV_FIVRA_CPU0
  EA3  PVCCFA_EHV_FIVRA_CPU0  VCCFA_EHV_FIVRA69  @S9S_MB_2U_LIB.S9S_MB_2U(SCH_1):PVCCFA_EHV_FIVRA_CPU0
  EA15  PVCCFA_EHV_FIVRA_CPU0  VCCFA_EHV_FIVRA68  @S9S_MB_2U_LIB.S9S_MB_2U(SCH_1):PVCCFA_EHV_FIVRA_CPU0
  EA11  PVCCFA_EHV_FIVRA_CPU0  VCCFA_EHV_FIVRA67  @S9S_MB_2U_LIB.S9S_MB_2U(SCH_1):PVCCFA_EHV_FIVRA_CPU0
  DY89  PVCCFA_EHV_FIVRA_CPU0  VCCFA_EHV_FIVRA66  @S9S_MB_2U_LIB.S9S_MB_2U(SCH_1):PVCCFA_EHV_FIVRA_CPU0
  DY85  PVCCFA_EHV_FIVRA_CPU0  VCCFA_EHV_FIVRA65  @S9S_MB_2U_LIB.S9S_MB_2U(SCH_1):PVCCFA_EHV_FIVRA_CPU0
  DU7  PVCCFA_EHV_FIVRA_CPU0  VCCFA_EHV_FIVRA64  @S9S_MB_2U_LIB.S9S_MB_2U(SCH_1):PVCCFA_EHV_FIVRA_CPU0
  DU3  PVCCFA_EHV_FIVRA_CPU0  VCCFA_EHV_FIVRA63  @S9S_MB_2U_LIB.S9S_MB_2U(SCH_1):PVCCFA_EHV_FIVRA_CPU0
  DU15  PVCCFA_EHV_FIVRA_CPU0  VCCFA_EHV_FIVRA62  @S9S_MB_2U_LIB.S9S_MB_2U(SCH_1):PVCCFA_EHV_FIVRA_CPU0
  DU11  PVCCFA_EHV_FIVRA_CPU0  VCCFA_EHV_FIVRA61  @S9S_MB_2U_LIB.S9S_MB_2U(SCH_1):PVCCFA_EHV_FIVRA_CPU0
  DT89  PVCCFA_EHV_FIVRA_CPU0  VCCFA_EHV_FIVRA60  @S9S_MB_2U_LIB.S9S_MB_2U(SCH_1):PVCCFA_EHV_FIVRA_CPU0
  DT85  PVCCFA_EHV_FIVRA_CPU0  VCCFA_EHV_FIVRA59  @S9S_MB_2U_LIB.S9S_MB_2U(SCH_1):PVCCFA_EHV_FIVRA_CPU0
  DT79  PVCCFA_EHV_FIVRA_CPU0  VCCFA_EHV_FIVRA58  @S9S_MB_2U_LIB.S9S_MB_2U(SCH_1):PVCCFA_EHV_FIVRA_CPU0
  DN7  PVCCFA_EHV_FIVRA_CPU0  VCCFA_EHV_FIVRA57  @S9S_MB_2U_LIB.S9S_MB_2U(SCH_1):PVCCFA_EHV_FIVRA_CPU0
  DN3  PVCCFA_EHV_FIVRA_CPU0  VCCFA_EHV_FIVRA56  @S9S_MB_2U_LIB.S9S_MB_2U(SCH_1):PVCCFA_EHV_FIVRA_CPU0
  DN15  PVCCFA_EHV_FIVRA_CPU0  VCCFA_EHV_FIVRA55  @S9S_MB_2U_LIB.S9S_MB_2U(SCH_1):PVCCFA_EHV_FIVRA_CPU0
  DN11  PVCCFA_EHV_FIVRA_CPU0  VCCFA_EHV_FIVRA54  @S9S_MB_2U_LIB.S9S_MB_2U(SCH_1):PVCCFA_EHV_FIVRA_CPU0
  DM89  PVCCFA_EHV_FIVRA_CPU0  VCCFA_EHV_FIVRA53  @S9S_MB_2U_LIB.S9S_MB_2U(SCH_1):PVCCFA_EHV_FIVRA_CPU0
  DM85  PVCCFA_EHV_FIVRA_CPU0  VCCFA_EHV_FIVRA52  @S9S_MB_2U_LIB.S9S_MB_2U(SCH_1):PVCCFA_EHV_FIVRA_CPU0
  DM83  PVCCFA_EHV_FIVRA_CPU0  VCCFA_EHV_FIVRA51  @S9S_MB_2U_LIB.S9S_MB_2U(SCH_1):PVCCFA_EHV_FIVRA_CPU0
  DH89  PVCCFA_EHV_FIVRA_CPU0  VCCFA_EHV_FIVRA50  @S9S_MB_2U_LIB.S9S_MB_2U(SCH_1):PVCCFA_EHV_FIVRA_CPU0
  DD89  PVCCFA_EHV_FIVRA_CPU0  VCCFA_EHV_FIVRA49  @S9S_MB_2U_LIB.S9S_MB_2U(SCH_1):PVCCFA_EHV_FIVRA_CPU0
  DD85  PVCCFA_EHV_FIVRA_CPU0  VCCFA_EHV_FIVRA48  @S9S_MB_2U_LIB.S9S_MB_2U(SCH_1):PVCCFA_EHV_FIVRA_CPU0
  DD83  PVCCFA_EHV_FIVRA_CPU0  VCCFA_EHV_FIVRA47  @S9S_MB_2U_LIB.S9S_MB_2U(SCH_1):PVCCFA_EHV_FIVRA_CPU0
  DD77  PVCCFA_EHV_FIVRA_CPU0  VCCFA_EHV_FIVRA46  @S9S_MB_2U_LIB.S9S_MB_2U(SCH_1):PVCCFA_EHV_FIVRA_CPU0
  CY89  PVCCFA_EHV_FIVRA_CPU0  VCCFA_EHV_FIVRA45  @S9S_MB_2U_LIB.S9S_MB_2U(SCH_1):PVCCFA_EHV_FIVRA_CPU0
  CY85  PVCCFA_EHV_FIVRA_CPU0  VCCFA_EHV_FIVRA44  @S9S_MB_2U_LIB.S9S_MB_2U(SCH_1):PVCCFA_EHV_FIVRA_CPU0
  CY79  PVCCFA_EHV_FIVRA_CPU0  VCCFA_EHV_FIVRA43  @S9S_MB_2U_LIB.S9S_MB_2U(SCH_1):PVCCFA_EHV_FIVRA_CPU0
  CY75  PVCCFA_EHV_FIVRA_CPU0  VCCFA_EHV_FIVRA42  @S9S_MB_2U_LIB.S9S_MB_2U(SCH_1):PVCCFA_EHV_FIVRA_CPU0
  CT85  PVCCFA_EHV_FIVRA_CPU0  VCCFA_EHV_FIVRA41  @S9S_MB_2U_LIB.S9S_MB_2U(SCH_1):PVCCFA_EHV_FIVRA_CPU0
  CT77  PVCCFA_EHV_FIVRA_CPU0  VCCFA_EHV_FIVRA40  @S9S_MB_2U_LIB.S9S_MB_2U(SCH_1):PVCCFA_EHV_FIVRA_CPU0
  CP73  PVCCFA_EHV_FIVRA_CPU0  VCCFA_EHV_FIVRA39  @S9S_MB_2U_LIB.S9S_MB_2U(SCH_1):PVCCFA_EHV_FIVRA_CPU0
  CN78  PVCCFA_EHV_FIVRA_CPU0  VCCFA_EHV_FIVRA38  @S9S_MB_2U_LIB.S9S_MB_2U(SCH_1):PVCCFA_EHV_FIVRA_CPU0
  CM73  PVCCFA_EHV_FIVRA_CPU0  VCCFA_EHV_FIVRA37  @S9S_MB_2U_LIB.S9S_MB_2U(SCH_1):PVCCFA_EHV_FIVRA_CPU0
  CK79  PVCCFA_EHV_FIVRA_CPU0  VCCFA_EHV_FIVRA36  @S9S_MB_2U_LIB.S9S_MB_2U(SCH_1):PVCCFA_EHV_FIVRA_CPU0
  CK73  PVCCFA_EHV_FIVRA_CPU0  VCCFA_EHV_FIVRA35  @S9S_MB_2U_LIB.S9S_MB_2U(SCH_1):PVCCFA_EHV_FIVRA_CPU0
  CE74  PVCCFA_EHV_FIVRA_CPU0  VCCFA_EHV_FIVRA34  @S9S_MB_2U_LIB.S9S_MB_2U(SCH_1):PVCCFA_EHV_FIVRA_CPU0
  C88  PVCCFA_EHV_FIVRA_CPU0  VCCFA_EHV_FIVRA33  @S9S_MB_2U_LIB.S9S_MB_2U(SCH_1):PVCCFA_EHV_FIVRA_CPU0
  C84  PVCCFA_EHV_FIVRA_CPU0  VCCFA_EHV_FIVRA32  @S9S_MB_2U_LIB.S9S_MB_2U(SCH_1):PVCCFA_EHV_FIVRA_CPU0
  BJ78  PVCCFA_EHV_FIVRA_CPU0  VCCFA_EHV_FIVRA31  @S9S_MB_2U_LIB.S9S_MB_2U(SCH_1):PVCCFA_EHV_FIVRA_CPU0
  BJ72  PVCCFA_EHV_FIVRA_CPU0  VCCFA_EHV_FIVRA30  @S9S_MB_2U_LIB.S9S_MB_2U(SCH_1):PVCCFA_EHV_FIVRA_CPU0
  BH79  PVCCFA_EHV_FIVRA_CPU0  VCCFA_EHV_FIVRA29  @S9S_MB_2U_LIB.S9S_MB_2U(SCH_1):PVCCFA_EHV_FIVRA_CPU0
  BF77  PVCCFA_EHV_FIVRA_CPU0  VCCFA_EHV_FIVRA28  @S9S_MB_2U_LIB.S9S_MB_2U(SCH_1):PVCCFA_EHV_FIVRA_CPU0
  BE72  PVCCFA_EHV_FIVRA_CPU0  VCCFA_EHV_FIVRA27  @S9S_MB_2U_LIB.S9S_MB_2U(SCH_1):PVCCFA_EHV_FIVRA_CPU0
  AY89  PVCCFA_EHV_FIVRA_CPU0  VCCFA_EHV_FIVRA26  @S9S_MB_2U_LIB.S9S_MB_2U(SCH_1):PVCCFA_EHV_FIVRA_CPU0
  AW76  PVCCFA_EHV_FIVRA_CPU0  VCCFA_EHV_FIVRA25  @S9S_MB_2U_LIB.S9S_MB_2U(SCH_1):PVCCFA_EHV_FIVRA_CPU0
  AU15  PVCCFA_EHV_FIVRA_CPU0  VCCFA_EHV_FIVRA24  @S9S_MB_2U_LIB.S9S_MB_2U(SCH_1):PVCCFA_EHV_FIVRA_CPU0
  AT89  PVCCFA_EHV_FIVRA_CPU0  VCCFA_EHV_FIVRA23  @S9S_MB_2U_LIB.S9S_MB_2U(SCH_1):PVCCFA_EHV_FIVRA_CPU0
  AT73  PVCCFA_EHV_FIVRA_CPU0  VCCFA_EHV_FIVRA22  @S9S_MB_2U_LIB.S9S_MB_2U(SCH_1):PVCCFA_EHV_FIVRA_CPU0
  AN80  PVCCFA_EHV_FIVRA_CPU0  VCCFA_EHV_FIVRA21  @S9S_MB_2U_LIB.S9S_MB_2U(SCH_1):PVCCFA_EHV_FIVRA_CPU0
  AN7  PVCCFA_EHV_FIVRA_CPU0  VCCFA_EHV_FIVRA20  @S9S_MB_2U_LIB.S9S_MB_2U(SCH_1):PVCCFA_EHV_FIVRA_CPU0
  AN15  PVCCFA_EHV_FIVRA_CPU0  VCCFA_EHV_FIVRA19  @S9S_MB_2U_LIB.S9S_MB_2U(SCH_1):PVCCFA_EHV_FIVRA_CPU0
  AN11  PVCCFA_EHV_FIVRA_CPU0  VCCFA_EHV_FIVRA18  @S9S_MB_2U_LIB.S9S_MB_2U(SCH_1):PVCCFA_EHV_FIVRA_CPU0
  AM89  PVCCFA_EHV_FIVRA_CPU0  VCCFA_EHV_FIVRA17  @S9S_MB_2U_LIB.S9S_MB_2U(SCH_1):PVCCFA_EHV_FIVRA_CPU0
  AM85  PVCCFA_EHV_FIVRA_CPU0  VCCFA_EHV_FIVRA16  @S9S_MB_2U_LIB.S9S_MB_2U(SCH_1):PVCCFA_EHV_FIVRA_CPU0
  AM79  PVCCFA_EHV_FIVRA_CPU0  VCCFA_EHV_FIVRA15  @S9S_MB_2U_LIB.S9S_MB_2U(SCH_1):PVCCFA_EHV_FIVRA_CPU0
  AJ7  PVCCFA_EHV_FIVRA_CPU0  VCCFA_EHV_FIVRA14  @S9S_MB_2U_LIB.S9S_MB_2U(SCH_1):PVCCFA_EHV_FIVRA_CPU0
  AJ15  PVCCFA_EHV_FIVRA_CPU0  VCCFA_EHV_FIVRA13  @S9S_MB_2U_LIB.S9S_MB_2U(SCH_1):PVCCFA_EHV_FIVRA_CPU0
  AJ11  PVCCFA_EHV_FIVRA_CPU0  VCCFA_EHV_FIVRA12  @S9S_MB_2U_LIB.S9S_MB_2U(SCH_1):PVCCFA_EHV_FIVRA_CPU0
  AH89  PVCCFA_EHV_FIVRA_CPU0  VCCFA_EHV_FIVRA11  @S9S_MB_2U_LIB.S9S_MB_2U(SCH_1):PVCCFA_EHV_FIVRA_CPU0
  AH85  PVCCFA_EHV_FIVRA_CPU0  VCCFA_EHV_FIVRA10  @S9S_MB_2U_LIB.S9S_MB_2U(SCH_1):PVCCFA_EHV_FIVRA_CPU0
  AG78  PVCCFA_EHV_FIVRA_CPU0  VCCFA_EHV_FIVRA9  @S9S_MB_2U_LIB.S9S_MB_2U(SCH_1):PVCCFA_EHV_FIVRA_CPU0
  AF77  PVCCFA_EHV_FIVRA_CPU0  VCCFA_EHV_FIVRA8  @S9S_MB_2U_LIB.S9S_MB_2U(SCH_1):PVCCFA_EHV_FIVRA_CPU0
  AE7  PVCCFA_EHV_FIVRA_CPU0  VCCFA_EHV_FIVRA7  @S9S_MB_2U_LIB.S9S_MB_2U(SCH_1):PVCCFA_EHV_FIVRA_CPU0
  AE15  PVCCFA_EHV_FIVRA_CPU0  VCCFA_EHV_FIVRA6  @S9S_MB_2U_LIB.S9S_MB_2U(SCH_1):PVCCFA_EHV_FIVRA_CPU0
  AE11  PVCCFA_EHV_FIVRA_CPU0  VCCFA_EHV_FIVRA5  @S9S_MB_2U_LIB.S9S_MB_2U(SCH_1):PVCCFA_EHV_FIVRA_CPU0
  AD89  PVCCFA_EHV_FIVRA_CPU0  VCCFA_EHV_FIVRA4  @S9S_MB_2U_LIB.S9S_MB_2U(SCH_1):PVCCFA_EHV_FIVRA_CPU0
  AD85  PVCCFA_EHV_FIVRA_CPU0  VCCFA_EHV_FIVRA3  @S9S_MB_2U_LIB.S9S_MB_2U(SCH_1):PVCCFA_EHV_FIVRA_CPU0
  AA7  PVCCFA_EHV_FIVRA_CPU0  VCCFA_EHV_FIVRA2  @S9S_MB_2U_LIB.S9S_MB_2U(SCH_1):PVCCFA_EHV_FIVRA_CPU0
  AA15  PVCCFA_EHV_FIVRA_CPU0  VCCFA_EHV_FIVRA1  @S9S_MB_2U_LIB.S9S_MB_2U(SCH_1):PVCCFA_EHV_FIVRA_CPU0
  AA11  PVCCFA_EHV_FIVRA_CPU0  VCCFA_EHV_FIVRA0  @S9S_MB_2U_LIB.S9S_MB_2U(SCH_1):PVCCFA_EHV_FIVRA_CPU0

SOCKET4677_AZIFS054P001C01  I8   U2     [SOCKET4677_AZIFS054P001C01-SOCA]
  CG68  PVPP_HBM_CPU0  VPP_HBM4  @S9S_MB_2U_LIB.S9S_MB_2U(SCH_1):PVPP_HBM_CPU0
  CF67  PVPP_HBM_CPU0  VPP_HBM3  @S9S_MB_2U_LIB.S9S_MB_2U(SCH_1):PVPP_HBM_CPU0
  CE68  PVPP_HBM_CPU0  VPP_HBM2  @S9S_MB_2U_LIB.S9S_MB_2U(SCH_1):PVPP_HBM_CPU0
  CD67  PVPP_HBM_CPU0  VPP_HBM1  @S9S_MB_2U_LIB.S9S_MB_2U(SCH_1):PVPP_HBM_CPU0
  CC68  PVPP_HBM_CPU0  VPP_HBM0  @S9S_MB_2U_LIB.S9S_MB_2U(SCH_1):PVPP_HBM_CPU0
  BN19  PVNN_MAIN_CPU0  VCCVNN3  @S9S_MB_2U_LIB.S9S_MB_2U(SCH_1):PVNN_MAIN_CPU0
  BJ19  PVNN_MAIN_CPU0  VCCVNN2  @S9S_MB_2U_LIB.S9S_MB_2U(SCH_1):PVNN_MAIN_CPU0
  BE19  PVNN_MAIN_CPU0  VCCVNN1  @S9S_MB_2U_LIB.S9S_MB_2U(SCH_1):PVNN_MAIN_CPU0
  BA19  PVNN_MAIN_CPU0  VCCVNN0  @S9S_MB_2U_LIB.S9S_MB_2U(SCH_1):PVNN_MAIN_CPU0
  DJ11  PVCCINFAON_CPU0  VCCINFAON59  @S9S_MB_2U_LIB.S9S_MB_2U(SCH_1):PVCCINFAON_CPU0
  DE7  PVCCINFAON_CPU0  VCCINFAON58  @S9S_MB_2U_LIB.S9S_MB_2U(SCH_1):PVCCINFAON_CPU0
  DA7  PVCCINFAON_CPU0  VCCINFAON57  @S9S_MB_2U_LIB.S9S_MB_2U(SCH_1):PVCCINFAON_CPU0
  DA3  PVCCINFAON_CPU0  VCCINFAON56  @S9S_MB_2U_LIB.S9S_MB_2U(SCH_1):PVCCINFAON_CPU0
  CW64  PVCCINFAON_CPU0  VCCINFAON55  @S9S_MB_2U_LIB.S9S_MB_2U(SCH_1):PVCCINFAON_CPU0
  CR66  PVCCINFAON_CPU0  VCCINFAON54  @S9S_MB_2U_LIB.S9S_MB_2U(SCH_1):PVCCINFAON_CPU0
  DJ7  PVCCINFAON_CPU0  VCCINFAON32  @S9S_MB_2U_LIB.S9S_MB_2U(SCH_1):PVCCINFAON_CPU0
  DJ3  PVCCINFAON_CPU0  VCCINFAON31  @S9S_MB_2U_LIB.S9S_MB_2U(SCH_1):PVCCINFAON_CPU0
  DJ15  PVCCINFAON_CPU0  VCCINFAON30  @S9S_MB_2U_LIB.S9S_MB_2U(SCH_1):PVCCINFAON_CPU0
  DE3  PVCCINFAON_CPU0  VCCINFAON29  @S9S_MB_2U_LIB.S9S_MB_2U(SCH_1):PVCCINFAON_CPU0
  DE15  PVCCINFAON_CPU0  VCCINFAON28  @S9S_MB_2U_LIB.S9S_MB_2U(SCH_1):PVCCINFAON_CPU0
  DE11  PVCCINFAON_CPU0  VCCINFAON27  @S9S_MB_2U_LIB.S9S_MB_2U(SCH_1):PVCCINFAON_CPU0
  DA64  PVCCINFAON_CPU0  VCCINFAON26  @S9S_MB_2U_LIB.S9S_MB_2U(SCH_1):PVCCINFAON_CPU0
  DA15  PVCCINFAON_CPU0  VCCINFAON25  @S9S_MB_2U_LIB.S9S_MB_2U(SCH_1):PVCCINFAON_CPU0
  DA11  PVCCINFAON_CPU0  VCCINFAON24  @S9S_MB_2U_LIB.S9S_MB_2U(SCH_1):PVCCINFAON_CPU0
  CY67  PVCCINFAON_CPU0  VCCINFAON23  @S9S_MB_2U_LIB.S9S_MB_2U(SCH_1):PVCCINFAON_CPU0
  CY65  PVCCINFAON_CPU0  VCCINFAON22  @S9S_MB_2U_LIB.S9S_MB_2U(SCH_1):PVCCINFAON_CPU0
  CW66  PVCCINFAON_CPU0  VCCINFAON21  @S9S_MB_2U_LIB.S9S_MB_2U(SCH_1):PVCCINFAON_CPU0
  CV67  PVCCINFAON_CPU0  VCCINFAON20  @S9S_MB_2U_LIB.S9S_MB_2U(SCH_1):PVCCINFAON_CPU0
  CV65  PVCCINFAON_CPU0  VCCINFAON19  @S9S_MB_2U_LIB.S9S_MB_2U(SCH_1):PVCCINFAON_CPU0
  CU7  PVCCINFAON_CPU0  VCCINFAON18  @S9S_MB_2U_LIB.S9S_MB_2U(SCH_1):PVCCINFAON_CPU0
  CU64  PVCCINFAON_CPU0  VCCINFAON17  @S9S_MB_2U_LIB.S9S_MB_2U(SCH_1):PVCCINFAON_CPU0
  CU3  PVCCINFAON_CPU0  VCCINFAON16  @S9S_MB_2U_LIB.S9S_MB_2U(SCH_1):PVCCINFAON_CPU0
  CU15  PVCCINFAON_CPU0  VCCINFAON15  @S9S_MB_2U_LIB.S9S_MB_2U(SCH_1):PVCCINFAON_CPU0
  CU11  PVCCINFAON_CPU0  VCCINFAON14  @S9S_MB_2U_LIB.S9S_MB_2U(SCH_1):PVCCINFAON_CPU0
  CT67  PVCCINFAON_CPU0  VCCINFAON13  @S9S_MB_2U_LIB.S9S_MB_2U(SCH_1):PVCCINFAON_CPU0
  CT65  PVCCINFAON_CPU0  VCCINFAON12  @S9S_MB_2U_LIB.S9S_MB_2U(SCH_1):PVCCINFAON_CPU0
  CP67  PVCCINFAON_CPU0  VCCINFAON11  @S9S_MB_2U_LIB.S9S_MB_2U(SCH_1):PVCCINFAON_CPU0
  CP65  PVCCINFAON_CPU0  VCCINFAON10  @S9S_MB_2U_LIB.S9S_MB_2U(SCH_1):PVCCINFAON_CPU0
  CN7  PVCCINFAON_CPU0  VCCINFAON9  @S9S_MB_2U_LIB.S9S_MB_2U(SCH_1):PVCCINFAON_CPU0
  CN66  PVCCINFAON_CPU0  VCCINFAON8  @S9S_MB_2U_LIB.S9S_MB_2U(SCH_1):PVCCINFAON_CPU0
  CN64  PVCCINFAON_CPU0  VCCINFAON7  @S9S_MB_2U_LIB.S9S_MB_2U(SCH_1):PVCCINFAON_CPU0
  CN3  PVCCINFAON_CPU0  VCCINFAON6  @S9S_MB_2U_LIB.S9S_MB_2U(SCH_1):PVCCINFAON_CPU0
  CN15  PVCCINFAON_CPU0  VCCINFAON5  @S9S_MB_2U_LIB.S9S_MB_2U(SCH_1):PVCCINFAON_CPU0
  CN11  PVCCINFAON_CPU0  VCCINFAON4  @S9S_MB_2U_LIB.S9S_MB_2U(SCH_1):PVCCINFAON_CPU0
  CJ7  PVCCINFAON_CPU0  VCCINFAON3  @S9S_MB_2U_LIB.S9S_MB_2U(SCH_1):PVCCINFAON_CPU0
  CJ3  PVCCINFAON_CPU0  VCCINFAON2  @S9S_MB_2U_LIB.S9S_MB_2U(SCH_1):PVCCINFAON_CPU0
  CJ15  PVCCINFAON_CPU0  VCCINFAON1  @S9S_MB_2U_LIB.S9S_MB_2U(SCH_1):PVCCINFAON_CPU0
  CE15  PVCCINFAON_CPU0  VCCINFAON0  @S9S_MB_2U_LIB.S9S_MB_2U(SCH_1):PVCCINFAON_CPU0
   N3  PVCCFA_EHV_CPU0  VCCFA_EHV9  @S9S_MB_2U_LIB.S9S_MB_2U(SCH_1):PVCCFA_EHV_CPU0
   U3  PVCCFA_EHV_CPU0  VCCFA_EHV8  @S9S_MB_2U_LIB.S9S_MB_2U(SCH_1):PVCCFA_EHV_CPU0
  AW60  PVCCFA_EHV_CPU0  VCCFA_EHV7  @S9S_MB_2U_LIB.S9S_MB_2U(SCH_1):PVCCFA_EHV_CPU0
  AV61  PVCCFA_EHV_CPU0  VCCFA_EHV6  @S9S_MB_2U_LIB.S9S_MB_2U(SCH_1):PVCCFA_EHV_CPU0
  AU60  PVCCFA_EHV_CPU0  VCCFA_EHV5  @S9S_MB_2U_LIB.S9S_MB_2U(SCH_1):PVCCFA_EHV_CPU0
  AT61  PVCCFA_EHV_CPU0  VCCFA_EHV4  @S9S_MB_2U_LIB.S9S_MB_2U(SCH_1):PVCCFA_EHV_CPU0
  AN3  PVCCFA_EHV_CPU0  VCCFA_EHV3  @S9S_MB_2U_LIB.S9S_MB_2U(SCH_1):PVCCFA_EHV_CPU0
  AJ3  PVCCFA_EHV_CPU0  VCCFA_EHV2  @S9S_MB_2U_LIB.S9S_MB_2U(SCH_1):PVCCFA_EHV_CPU0
  AE3  PVCCFA_EHV_CPU0  VCCFA_EHV1  @S9S_MB_2U_LIB.S9S_MB_2U(SCH_1):PVCCFA_EHV_CPU0
  AA3  PVCCFA_EHV_CPU0  VCCFA_EHV0  @S9S_MB_2U_LIB.S9S_MB_2U(SCH_1):PVCCFA_EHV_CPU0
  CY53  PVCCD_HV_CPU0  VCCD_HV28  @S9S_MB_2U_LIB.S9S_MB_2U(SCH_1):PVCCD_HV_CPU0
  CY36  PVCCD_HV_CPU0  VCCD_HV27  @S9S_MB_2U_LIB.S9S_MB_2U(SCH_1):PVCCD_HV_CPU0
  CW54  PVCCD_HV_CPU0  VCCD_HV26  @S9S_MB_2U_LIB.S9S_MB_2U(SCH_1):PVCCD_HV_CPU0
  CY34  PVCCD_HV_CPU0  VCCD_HV25  @S9S_MB_2U_LIB.S9S_MB_2U(SCH_1):PVCCD_HV_CPU0
  CW56  PVCCD_HV_CPU0  VCCD_HV24  @S9S_MB_2U_LIB.S9S_MB_2U(SCH_1):PVCCD_HV_CPU0
  CW52  PVCCD_HV_CPU0  VCCD_HV23  @S9S_MB_2U_LIB.S9S_MB_2U(SCH_1):PVCCD_HV_CPU0
  CW37  PVCCD_HV_CPU0  VCCD_HV22  @S9S_MB_2U_LIB.S9S_MB_2U(SCH_1):PVCCD_HV_CPU0
  CW35  PVCCD_HV_CPU0  VCCD_HV21  @S9S_MB_2U_LIB.S9S_MB_2U(SCH_1):PVCCD_HV_CPU0
  CE7  PVCCD_HV_CPU0  VCCD_HV20  @S9S_MB_2U_LIB.S9S_MB_2U(SCH_1):PVCCD_HV_CPU0
  CA7  PVCCD_HV_CPU0  VCCD_HV19  @S9S_MB_2U_LIB.S9S_MB_2U(SCH_1):PVCCD_HV_CPU0
  BN7  PVCCD_HV_CPU0  VCCD_HV18  @S9S_MB_2U_LIB.S9S_MB_2U(SCH_1):PVCCD_HV_CPU0
  BJ7  PVCCD_HV_CPU0  VCCD_HV17  @S9S_MB_2U_LIB.S9S_MB_2U(SCH_1):PVCCD_HV_CPU0
  BJ3  PVCCD_HV_CPU0  VCCD_HV16  @S9S_MB_2U_LIB.S9S_MB_2U(SCH_1):PVCCD_HV_CPU0
  BJ11  PVCCD_HV_CPU0  VCCD_HV15  @S9S_MB_2U_LIB.S9S_MB_2U(SCH_1):PVCCD_HV_CPU0
  BE7  PVCCD_HV_CPU0  VCCD_HV14  @S9S_MB_2U_LIB.S9S_MB_2U(SCH_1):PVCCD_HV_CPU0
  BE3  PVCCD_HV_CPU0  VCCD_HV13  @S9S_MB_2U_LIB.S9S_MB_2U(SCH_1):PVCCD_HV_CPU0
  BE11  PVCCD_HV_CPU0  VCCD_HV12  @S9S_MB_2U_LIB.S9S_MB_2U(SCH_1):PVCCD_HV_CPU0
  BA7  PVCCD_HV_CPU0  VCCD_HV11  @S9S_MB_2U_LIB.S9S_MB_2U(SCH_1):PVCCD_HV_CPU0
  BA3  PVCCD_HV_CPU0  VCCD_HV10  @S9S_MB_2U_LIB.S9S_MB_2U(SCH_1):PVCCD_HV_CPU0
  AV55  PVCCD_HV_CPU0  VCCD_HV9  @S9S_MB_2U_LIB.S9S_MB_2U(SCH_1):PVCCD_HV_CPU0
  AV53  PVCCD_HV_CPU0  VCCD_HV8  @S9S_MB_2U_LIB.S9S_MB_2U(SCH_1):PVCCD_HV_CPU0
  AV36  PVCCD_HV_CPU0  VCCD_HV7  @S9S_MB_2U_LIB.S9S_MB_2U(SCH_1):PVCCD_HV_CPU0
  AV34  PVCCD_HV_CPU0  VCCD_HV6  @S9S_MB_2U_LIB.S9S_MB_2U(SCH_1):PVCCD_HV_CPU0
  AU7  PVCCD_HV_CPU0  VCCD_HV5  @S9S_MB_2U_LIB.S9S_MB_2U(SCH_1):PVCCD_HV_CPU0
  AU54  PVCCD_HV_CPU0  VCCD_HV4  @S9S_MB_2U_LIB.S9S_MB_2U(SCH_1):PVCCD_HV_CPU0
  AU35  PVCCD_HV_CPU0  VCCD_HV3  @S9S_MB_2U_LIB.S9S_MB_2U(SCH_1):PVCCD_HV_CPU0
  AU3  PVCCD_HV_CPU0  VCCD_HV2  @S9S_MB_2U_LIB.S9S_MB_2U(SCH_1):PVCCD_HV_CPU0
  AT55  PVCCD_HV_CPU0  VCCD_HV1  @S9S_MB_2U_LIB.S9S_MB_2U(SCH_1):PVCCD_HV_CPU0
  AT36  PVCCD_HV_CPU0  VCCD_HV0  @S9S_MB_2U_LIB.S9S_MB_2U(SCH_1):PVCCD_HV_CPU0
  BC21  P3V3_AUX       VCCCPLD_3P3V1  @S9S_MB_2U_LIB.S9S_MB_2U(SCH_1):P3V3_AUX
  BA21  P3V3_AUX       VCCCPLD_3P3V0  @S9S_MB_2U_LIB.S9S_MB_2U(SCH_1):P3V3_AUX

SOCKET4677_AZIFS054P001C01  I7   U2     [SOCKET4677_AZIFS054P001C01-SOCA]
  BN41  PVCCIN_CPU0    VCCIN39  @S9S_MB_2U_LIB.S9S_MB_2U(SCH_1):PVCCIN_CPU0
  BN39  PVCCIN_CPU0    VCCIN38  @S9S_MB_2U_LIB.S9S_MB_2U(SCH_1):PVCCIN_CPU0
  BN37  PVCCIN_CPU0    VCCIN37  @S9S_MB_2U_LIB.S9S_MB_2U(SCH_1):PVCCIN_CPU0
  BN35  PVCCIN_CPU0    VCCIN36  @S9S_MB_2U_LIB.S9S_MB_2U(SCH_1):PVCCIN_CPU0
  BN33  PVCCIN_CPU0    VCCIN35  @S9S_MB_2U_LIB.S9S_MB_2U(SCH_1):PVCCIN_CPU0
  BM91  PVCCIN_CPU0    VCCIN34  @S9S_MB_2U_LIB.S9S_MB_2U(SCH_1):PVCCIN_CPU0
  BM89  PVCCIN_CPU0    VCCIN33  @S9S_MB_2U_LIB.S9S_MB_2U(SCH_1):PVCCIN_CPU0
  BM87  PVCCIN_CPU0    VCCIN32  @S9S_MB_2U_LIB.S9S_MB_2U(SCH_1):PVCCIN_CPU0
  BM85  PVCCIN_CPU0    VCCIN31  @S9S_MB_2U_LIB.S9S_MB_2U(SCH_1):PVCCIN_CPU0
  BM83  PVCCIN_CPU0    VCCIN30  @S9S_MB_2U_LIB.S9S_MB_2U(SCH_1):PVCCIN_CPU0
  BM81  PVCCIN_CPU0    VCCIN29  @S9S_MB_2U_LIB.S9S_MB_2U(SCH_1):PVCCIN_CPU0
  BM79  PVCCIN_CPU0    VCCIN28  @S9S_MB_2U_LIB.S9S_MB_2U(SCH_1):PVCCIN_CPU0
  BL90  PVCCIN_CPU0    VCCIN27  @S9S_MB_2U_LIB.S9S_MB_2U(SCH_1):PVCCIN_CPU0
  BL88  PVCCIN_CPU0    VCCIN26  @S9S_MB_2U_LIB.S9S_MB_2U(SCH_1):PVCCIN_CPU0
  BL86  PVCCIN_CPU0    VCCIN25  @S9S_MB_2U_LIB.S9S_MB_2U(SCH_1):PVCCIN_CPU0
  BL84  PVCCIN_CPU0    VCCIN24  @S9S_MB_2U_LIB.S9S_MB_2U(SCH_1):PVCCIN_CPU0
  BL82  PVCCIN_CPU0    VCCIN23  @S9S_MB_2U_LIB.S9S_MB_2U(SCH_1):PVCCIN_CPU0
  BL80  PVCCIN_CPU0    VCCIN22  @S9S_MB_2U_LIB.S9S_MB_2U(SCH_1):PVCCIN_CPU0
  BK91  PVCCIN_CPU0    VCCIN21  @S9S_MB_2U_LIB.S9S_MB_2U(SCH_1):PVCCIN_CPU0
  BK89  PVCCIN_CPU0    VCCIN20  @S9S_MB_2U_LIB.S9S_MB_2U(SCH_1):PVCCIN_CPU0
  BK87  PVCCIN_CPU0    VCCIN19  @S9S_MB_2U_LIB.S9S_MB_2U(SCH_1):PVCCIN_CPU0
  BK85  PVCCIN_CPU0    VCCIN18  @S9S_MB_2U_LIB.S9S_MB_2U(SCH_1):PVCCIN_CPU0
  BK83  PVCCIN_CPU0    VCCIN17  @S9S_MB_2U_LIB.S9S_MB_2U(SCH_1):PVCCIN_CPU0
  BK81  PVCCIN_CPU0    VCCIN16  @S9S_MB_2U_LIB.S9S_MB_2U(SCH_1):PVCCIN_CPU0
  BH91  PVCCIN_CPU0    VCCIN15  @S9S_MB_2U_LIB.S9S_MB_2U(SCH_1):PVCCIN_CPU0
  BH89  PVCCIN_CPU0    VCCIN14  @S9S_MB_2U_LIB.S9S_MB_2U(SCH_1):PVCCIN_CPU0
  BH87  PVCCIN_CPU0    VCCIN13  @S9S_MB_2U_LIB.S9S_MB_2U(SCH_1):PVCCIN_CPU0
  BH85  PVCCIN_CPU0    VCCIN12  @S9S_MB_2U_LIB.S9S_MB_2U(SCH_1):PVCCIN_CPU0
  BG90  PVCCIN_CPU0    VCCIN11  @S9S_MB_2U_LIB.S9S_MB_2U(SCH_1):PVCCIN_CPU0
  BG88  PVCCIN_CPU0    VCCIN10  @S9S_MB_2U_LIB.S9S_MB_2U(SCH_1):PVCCIN_CPU0
  BG86  PVCCIN_CPU0    VCCIN9  @S9S_MB_2U_LIB.S9S_MB_2U(SCH_1):PVCCIN_CPU0
  BG84  PVCCIN_CPU0    VCCIN8  @S9S_MB_2U_LIB.S9S_MB_2U(SCH_1):PVCCIN_CPU0
  BF91  PVCCIN_CPU0    VCCIN7  @S9S_MB_2U_LIB.S9S_MB_2U(SCH_1):PVCCIN_CPU0
  BF89  PVCCIN_CPU0    VCCIN6  @S9S_MB_2U_LIB.S9S_MB_2U(SCH_1):PVCCIN_CPU0
  BF87  PVCCIN_CPU0    VCCIN5  @S9S_MB_2U_LIB.S9S_MB_2U(SCH_1):PVCCIN_CPU0
  BF85  PVCCIN_CPU0    VCCIN4  @S9S_MB_2U_LIB.S9S_MB_2U(SCH_1):PVCCIN_CPU0
  BE90  PVCCIN_CPU0    VCCIN3  @S9S_MB_2U_LIB.S9S_MB_2U(SCH_1):PVCCIN_CPU0
  BE88  PVCCIN_CPU0    VCCIN2  @S9S_MB_2U_LIB.S9S_MB_2U(SCH_1):PVCCIN_CPU0
  BE86  PVCCIN_CPU0    VCCIN1  @S9S_MB_2U_LIB.S9S_MB_2U(SCH_1):PVCCIN_CPU0
  BD91  PVCCIN_CPU0    VCCIN0  @S9S_MB_2U_LIB.S9S_MB_2U(SCH_1):PVCCIN_CPU0
  DA21  PVCCINFAON_CPU0  VCCINFAON53  @S9S_MB_2U_LIB.S9S_MB_2U(SCH_1):PVCCINFAON_CPU0
  CW62  PVCCINFAON_CPU0  VCCINFAON52  @S9S_MB_2U_LIB.S9S_MB_2U(SCH_1):PVCCINFAON_CPU0
  CV63  PVCCINFAON_CPU0  VCCINFAON51  @S9S_MB_2U_LIB.S9S_MB_2U(SCH_1):PVCCINFAON_CPU0
  CV61  PVCCINFAON_CPU0  VCCINFAON50  @S9S_MB_2U_LIB.S9S_MB_2U(SCH_1):PVCCINFAON_CPU0
  CT63  PVCCINFAON_CPU0  VCCINFAON49  @S9S_MB_2U_LIB.S9S_MB_2U(SCH_1):PVCCINFAON_CPU0
  CP63  PVCCINFAON_CPU0  VCCINFAON48  @S9S_MB_2U_LIB.S9S_MB_2U(SCH_1):PVCCINFAON_CPU0
  CN19  PVCCINFAON_CPU0  VCCINFAON47  @S9S_MB_2U_LIB.S9S_MB_2U(SCH_1):PVCCINFAON_CPU0
  CJ19  PVCCINFAON_CPU0  VCCINFAON46  @S9S_MB_2U_LIB.S9S_MB_2U(SCH_1):PVCCINFAON_CPU0
  CJ11  PVCCINFAON_CPU0  VCCINFAON45  @S9S_MB_2U_LIB.S9S_MB_2U(SCH_1):PVCCINFAON_CPU0
  CE19  PVCCINFAON_CPU0  VCCINFAON44  @S9S_MB_2U_LIB.S9S_MB_2U(SCH_1):PVCCINFAON_CPU0
  CA15  PVCCINFAON_CPU0  VCCINFAON43  @S9S_MB_2U_LIB.S9S_MB_2U(SCH_1):PVCCINFAON_CPU0
  BN15  PVCCINFAON_CPU0  VCCINFAON42  @S9S_MB_2U_LIB.S9S_MB_2U(SCH_1):PVCCINFAON_CPU0
  BK61  PVCCINFAON_CPU0  VCCINFAON41  @S9S_MB_2U_LIB.S9S_MB_2U(SCH_1):PVCCINFAON_CPU0
  BJ60  PVCCINFAON_CPU0  VCCINFAON40  @S9S_MB_2U_LIB.S9S_MB_2U(SCH_1):PVCCINFAON_CPU0
  BJ15  PVCCINFAON_CPU0  VCCINFAON39  @S9S_MB_2U_LIB.S9S_MB_2U(SCH_1):PVCCINFAON_CPU0
  BG60  PVCCINFAON_CPU0  VCCINFAON38  @S9S_MB_2U_LIB.S9S_MB_2U(SCH_1):PVCCINFAON_CPU0
  BE60  PVCCINFAON_CPU0  VCCINFAON37  @S9S_MB_2U_LIB.S9S_MB_2U(SCH_1):PVCCINFAON_CPU0
  BE15  PVCCINFAON_CPU0  VCCINFAON36  @S9S_MB_2U_LIB.S9S_MB_2U(SCH_1):PVCCINFAON_CPU0
  BC60  PVCCINFAON_CPU0  VCCINFAON35  @S9S_MB_2U_LIB.S9S_MB_2U(SCH_1):PVCCINFAON_CPU0
  BA15  PVCCINFAON_CPU0  VCCINFAON34  @S9S_MB_2U_LIB.S9S_MB_2U(SCH_1):PVCCINFAON_CPU0
  AY18  PVCCINFAON_CPU0  VCCINFAON33  @S9S_MB_2U_LIB.S9S_MB_2U(SCH_1):PVCCINFAON_CPU0

SOCKET4677_AZIFS054P001C01  I7   U2     [SOCKET4677_AZIFS054P001C01-SOCA]
  BW78  PVCCIN_CPU0    VCCIN189  @S9S_MB_2U_LIB.S9S_MB_2U(SCH_1):PVCCIN_CPU0
  BW76  PVCCIN_CPU0    VCCIN188  @S9S_MB_2U_LIB.S9S_MB_2U(SCH_1):PVCCIN_CPU0
  BW74  PVCCIN_CPU0    VCCIN187  @S9S_MB_2U_LIB.S9S_MB_2U(SCH_1):PVCCIN_CPU0
  BW72  PVCCIN_CPU0    VCCIN186  @S9S_MB_2U_LIB.S9S_MB_2U(SCH_1):PVCCIN_CPU0
  BW70  PVCCIN_CPU0    VCCIN185  @S9S_MB_2U_LIB.S9S_MB_2U(SCH_1):PVCCIN_CPU0
  BW68  PVCCIN_CPU0    VCCIN184  @S9S_MB_2U_LIB.S9S_MB_2U(SCH_1):PVCCIN_CPU0
  BW66  PVCCIN_CPU0    VCCIN183  @S9S_MB_2U_LIB.S9S_MB_2U(SCH_1):PVCCIN_CPU0
  BW64  PVCCIN_CPU0    VCCIN182  @S9S_MB_2U_LIB.S9S_MB_2U(SCH_1):PVCCIN_CPU0
  BW62  PVCCIN_CPU0    VCCIN181  @S9S_MB_2U_LIB.S9S_MB_2U(SCH_1):PVCCIN_CPU0
  BW60  PVCCIN_CPU0    VCCIN180  @S9S_MB_2U_LIB.S9S_MB_2U(SCH_1):PVCCIN_CPU0
  BW58  PVCCIN_CPU0    VCCIN179  @S9S_MB_2U_LIB.S9S_MB_2U(SCH_1):PVCCIN_CPU0
  BW56  PVCCIN_CPU0    VCCIN178  @S9S_MB_2U_LIB.S9S_MB_2U(SCH_1):PVCCIN_CPU0
  BW54  PVCCIN_CPU0    VCCIN177  @S9S_MB_2U_LIB.S9S_MB_2U(SCH_1):PVCCIN_CPU0
  BW52  PVCCIN_CPU0    VCCIN176  @S9S_MB_2U_LIB.S9S_MB_2U(SCH_1):PVCCIN_CPU0
  BW50  PVCCIN_CPU0    VCCIN175  @S9S_MB_2U_LIB.S9S_MB_2U(SCH_1):PVCCIN_CPU0
  BW48  PVCCIN_CPU0    VCCIN174  @S9S_MB_2U_LIB.S9S_MB_2U(SCH_1):PVCCIN_CPU0
  BW45  PVCCIN_CPU0    VCCIN173  @S9S_MB_2U_LIB.S9S_MB_2U(SCH_1):PVCCIN_CPU0
  BW43  PVCCIN_CPU0    VCCIN172  @S9S_MB_2U_LIB.S9S_MB_2U(SCH_1):PVCCIN_CPU0
  BW41  PVCCIN_CPU0    VCCIN171  @S9S_MB_2U_LIB.S9S_MB_2U(SCH_1):PVCCIN_CPU0
  BW39  PVCCIN_CPU0    VCCIN170  @S9S_MB_2U_LIB.S9S_MB_2U(SCH_1):PVCCIN_CPU0
  BW37  PVCCIN_CPU0    VCCIN169  @S9S_MB_2U_LIB.S9S_MB_2U(SCH_1):PVCCIN_CPU0
  BW35  PVCCIN_CPU0    VCCIN168  @S9S_MB_2U_LIB.S9S_MB_2U(SCH_1):PVCCIN_CPU0
  BW33  PVCCIN_CPU0    VCCIN167  @S9S_MB_2U_LIB.S9S_MB_2U(SCH_1):PVCCIN_CPU0
  BV89  PVCCIN_CPU0    VCCIN166  @S9S_MB_2U_LIB.S9S_MB_2U(SCH_1):PVCCIN_CPU0
  BV87  PVCCIN_CPU0    VCCIN165  @S9S_MB_2U_LIB.S9S_MB_2U(SCH_1):PVCCIN_CPU0
  BV85  PVCCIN_CPU0    VCCIN164  @S9S_MB_2U_LIB.S9S_MB_2U(SCH_1):PVCCIN_CPU0
  BV83  PVCCIN_CPU0    VCCIN163  @S9S_MB_2U_LIB.S9S_MB_2U(SCH_1):PVCCIN_CPU0
  BV81  PVCCIN_CPU0    VCCIN162  @S9S_MB_2U_LIB.S9S_MB_2U(SCH_1):PVCCIN_CPU0
  BV79  PVCCIN_CPU0    VCCIN161  @S9S_MB_2U_LIB.S9S_MB_2U(SCH_1):PVCCIN_CPU0
  BV77  PVCCIN_CPU0    VCCIN160  @S9S_MB_2U_LIB.S9S_MB_2U(SCH_1):PVCCIN_CPU0
  BV75  PVCCIN_CPU0    VCCIN159  @S9S_MB_2U_LIB.S9S_MB_2U(SCH_1):PVCCIN_CPU0
  BV73  PVCCIN_CPU0    VCCIN158  @S9S_MB_2U_LIB.S9S_MB_2U(SCH_1):PVCCIN_CPU0
  BV71  PVCCIN_CPU0    VCCIN157  @S9S_MB_2U_LIB.S9S_MB_2U(SCH_1):PVCCIN_CPU0
  BV69  PVCCIN_CPU0    VCCIN156  @S9S_MB_2U_LIB.S9S_MB_2U(SCH_1):PVCCIN_CPU0
  BV67  PVCCIN_CPU0    VCCIN155  @S9S_MB_2U_LIB.S9S_MB_2U(SCH_1):PVCCIN_CPU0
  BV65  PVCCIN_CPU0    VCCIN154  @S9S_MB_2U_LIB.S9S_MB_2U(SCH_1):PVCCIN_CPU0
  BV63  PVCCIN_CPU0    VCCIN153  @S9S_MB_2U_LIB.S9S_MB_2U(SCH_1):PVCCIN_CPU0
  BV61  PVCCIN_CPU0    VCCIN152  @S9S_MB_2U_LIB.S9S_MB_2U(SCH_1):PVCCIN_CPU0
  BV59  PVCCIN_CPU0    VCCIN151  @S9S_MB_2U_LIB.S9S_MB_2U(SCH_1):PVCCIN_CPU0
  BV57  PVCCIN_CPU0    VCCIN150  @S9S_MB_2U_LIB.S9S_MB_2U(SCH_1):PVCCIN_CPU0
  BV55  PVCCIN_CPU0    VCCIN149  @S9S_MB_2U_LIB.S9S_MB_2U(SCH_1):PVCCIN_CPU0
  BV53  PVCCIN_CPU0    VCCIN148  @S9S_MB_2U_LIB.S9S_MB_2U(SCH_1):PVCCIN_CPU0
  BV51  PVCCIN_CPU0    VCCIN147  @S9S_MB_2U_LIB.S9S_MB_2U(SCH_1):PVCCIN_CPU0
  BV49  PVCCIN_CPU0    VCCIN146  @S9S_MB_2U_LIB.S9S_MB_2U(SCH_1):PVCCIN_CPU0
  BV47  PVCCIN_CPU0    VCCIN145  @S9S_MB_2U_LIB.S9S_MB_2U(SCH_1):PVCCIN_CPU0
  BV44  PVCCIN_CPU0    VCCIN144  @S9S_MB_2U_LIB.S9S_MB_2U(SCH_1):PVCCIN_CPU0
  BV42  PVCCIN_CPU0    VCCIN143  @S9S_MB_2U_LIB.S9S_MB_2U(SCH_1):PVCCIN_CPU0
  BV40  PVCCIN_CPU0    VCCIN142  @S9S_MB_2U_LIB.S9S_MB_2U(SCH_1):PVCCIN_CPU0
  BV38  PVCCIN_CPU0    VCCIN141  @S9S_MB_2U_LIB.S9S_MB_2U(SCH_1):PVCCIN_CPU0
  BV36  PVCCIN_CPU0    VCCIN140  @S9S_MB_2U_LIB.S9S_MB_2U(SCH_1):PVCCIN_CPU0
  BV34  PVCCIN_CPU0    VCCIN139  @S9S_MB_2U_LIB.S9S_MB_2U(SCH_1):PVCCIN_CPU0
  BV32  PVCCIN_CPU0    VCCIN138  @S9S_MB_2U_LIB.S9S_MB_2U(SCH_1):PVCCIN_CPU0
  BU90  PVCCIN_CPU0    VCCIN137  @S9S_MB_2U_LIB.S9S_MB_2U(SCH_1):PVCCIN_CPU0
  BU88  PVCCIN_CPU0    VCCIN136  @S9S_MB_2U_LIB.S9S_MB_2U(SCH_1):PVCCIN_CPU0
  BU86  PVCCIN_CPU0    VCCIN135  @S9S_MB_2U_LIB.S9S_MB_2U(SCH_1):PVCCIN_CPU0
  BU84  PVCCIN_CPU0    VCCIN134  @S9S_MB_2U_LIB.S9S_MB_2U(SCH_1):PVCCIN_CPU0
  BU82  PVCCIN_CPU0    VCCIN133  @S9S_MB_2U_LIB.S9S_MB_2U(SCH_1):PVCCIN_CPU0
  BU80  PVCCIN_CPU0    VCCIN132  @S9S_MB_2U_LIB.S9S_MB_2U(SCH_1):PVCCIN_CPU0
  BU78  PVCCIN_CPU0    VCCIN131  @S9S_MB_2U_LIB.S9S_MB_2U(SCH_1):PVCCIN_CPU0
  BU76  PVCCIN_CPU0    VCCIN130  @S9S_MB_2U_LIB.S9S_MB_2U(SCH_1):PVCCIN_CPU0
  BU74  PVCCIN_CPU0    VCCIN129  @S9S_MB_2U_LIB.S9S_MB_2U(SCH_1):PVCCIN_CPU0
  BU72  PVCCIN_CPU0    VCCIN128  @S9S_MB_2U_LIB.S9S_MB_2U(SCH_1):PVCCIN_CPU0
  BU70  PVCCIN_CPU0    VCCIN127  @S9S_MB_2U_LIB.S9S_MB_2U(SCH_1):PVCCIN_CPU0
  BU68  PVCCIN_CPU0    VCCIN126  @S9S_MB_2U_LIB.S9S_MB_2U(SCH_1):PVCCIN_CPU0
  BU66  PVCCIN_CPU0    VCCIN125  @S9S_MB_2U_LIB.S9S_MB_2U(SCH_1):PVCCIN_CPU0
  BU64  PVCCIN_CPU0    VCCIN124  @S9S_MB_2U_LIB.S9S_MB_2U(SCH_1):PVCCIN_CPU0
  BU62  PVCCIN_CPU0    VCCIN123  @S9S_MB_2U_LIB.S9S_MB_2U(SCH_1):PVCCIN_CPU0
  BU60  PVCCIN_CPU0    VCCIN122  @S9S_MB_2U_LIB.S9S_MB_2U(SCH_1):PVCCIN_CPU0
  BU58  PVCCIN_CPU0    VCCIN121  @S9S_MB_2U_LIB.S9S_MB_2U(SCH_1):PVCCIN_CPU0
  BU56  PVCCIN_CPU0    VCCIN120  @S9S_MB_2U_LIB.S9S_MB_2U(SCH_1):PVCCIN_CPU0
  BU54  PVCCIN_CPU0    VCCIN119  @S9S_MB_2U_LIB.S9S_MB_2U(SCH_1):PVCCIN_CPU0
  BU52  PVCCIN_CPU0    VCCIN118  @S9S_MB_2U_LIB.S9S_MB_2U(SCH_1):PVCCIN_CPU0
  BU50  PVCCIN_CPU0    VCCIN117  @S9S_MB_2U_LIB.S9S_MB_2U(SCH_1):PVCCIN_CPU0
  BU48  PVCCIN_CPU0    VCCIN116  @S9S_MB_2U_LIB.S9S_MB_2U(SCH_1):PVCCIN_CPU0
  BU45  PVCCIN_CPU0    VCCIN115  @S9S_MB_2U_LIB.S9S_MB_2U(SCH_1):PVCCIN_CPU0
  BU43  PVCCIN_CPU0    VCCIN114  @S9S_MB_2U_LIB.S9S_MB_2U(SCH_1):PVCCIN_CPU0
  BU41  PVCCIN_CPU0    VCCIN113  @S9S_MB_2U_LIB.S9S_MB_2U(SCH_1):PVCCIN_CPU0
  BU39  PVCCIN_CPU0    VCCIN112  @S9S_MB_2U_LIB.S9S_MB_2U(SCH_1):PVCCIN_CPU0
  BU37  PVCCIN_CPU0    VCCIN111  @S9S_MB_2U_LIB.S9S_MB_2U(SCH_1):PVCCIN_CPU0
  BU35  PVCCIN_CPU0    VCCIN110  @S9S_MB_2U_LIB.S9S_MB_2U(SCH_1):PVCCIN_CPU0
  BU33  PVCCIN_CPU0    VCCIN109  @S9S_MB_2U_LIB.S9S_MB_2U(SCH_1):PVCCIN_CPU0
  BT89  PVCCIN_CPU0    VCCIN108  @S9S_MB_2U_LIB.S9S_MB_2U(SCH_1):PVCCIN_CPU0
  BT87  PVCCIN_CPU0    VCCIN107  @S9S_MB_2U_LIB.S9S_MB_2U(SCH_1):PVCCIN_CPU0
  BT85  PVCCIN_CPU0    VCCIN106  @S9S_MB_2U_LIB.S9S_MB_2U(SCH_1):PVCCIN_CPU0
  BT83  PVCCIN_CPU0    VCCIN105  @S9S_MB_2U_LIB.S9S_MB_2U(SCH_1):PVCCIN_CPU0
  BT81  PVCCIN_CPU0    VCCIN104  @S9S_MB_2U_LIB.S9S_MB_2U(SCH_1):PVCCIN_CPU0
  BT79  PVCCIN_CPU0    VCCIN103  @S9S_MB_2U_LIB.S9S_MB_2U(SCH_1):PVCCIN_CPU0
  BT77  PVCCIN_CPU0    VCCIN102  @S9S_MB_2U_LIB.S9S_MB_2U(SCH_1):PVCCIN_CPU0
  BT75  PVCCIN_CPU0    VCCIN101  @S9S_MB_2U_LIB.S9S_MB_2U(SCH_1):PVCCIN_CPU0
  BT73  PVCCIN_CPU0    VCCIN100  @S9S_MB_2U_LIB.S9S_MB_2U(SCH_1):PVCCIN_CPU0
  BT71  PVCCIN_CPU0    VCCIN99  @S9S_MB_2U_LIB.S9S_MB_2U(SCH_1):PVCCIN_CPU0
  BT69  PVCCIN_CPU0    VCCIN98  @S9S_MB_2U_LIB.S9S_MB_2U(SCH_1):PVCCIN_CPU0
  BT67  PVCCIN_CPU0    VCCIN97  @S9S_MB_2U_LIB.S9S_MB_2U(SCH_1):PVCCIN_CPU0
  BT65  PVCCIN_CPU0    VCCIN96  @S9S_MB_2U_LIB.S9S_MB_2U(SCH_1):PVCCIN_CPU0
  BT63  PVCCIN_CPU0    VCCIN95  @S9S_MB_2U_LIB.S9S_MB_2U(SCH_1):PVCCIN_CPU0
  BT61  PVCCIN_CPU0    VCCIN94  @S9S_MB_2U_LIB.S9S_MB_2U(SCH_1):PVCCIN_CPU0
  BT59  PVCCIN_CPU0    VCCIN93  @S9S_MB_2U_LIB.S9S_MB_2U(SCH_1):PVCCIN_CPU0
  BT57  PVCCIN_CPU0    VCCIN92  @S9S_MB_2U_LIB.S9S_MB_2U(SCH_1):PVCCIN_CPU0
  BT55  PVCCIN_CPU0    VCCIN91  @S9S_MB_2U_LIB.S9S_MB_2U(SCH_1):PVCCIN_CPU0
  BT53  PVCCIN_CPU0    VCCIN90  @S9S_MB_2U_LIB.S9S_MB_2U(SCH_1):PVCCIN_CPU0
  BT51  PVCCIN_CPU0    VCCIN89  @S9S_MB_2U_LIB.S9S_MB_2U(SCH_1):PVCCIN_CPU0
  BT49  PVCCIN_CPU0    VCCIN88  @S9S_MB_2U_LIB.S9S_MB_2U(SCH_1):PVCCIN_CPU0
  BT47  PVCCIN_CPU0    VCCIN87  @S9S_MB_2U_LIB.S9S_MB_2U(SCH_1):PVCCIN_CPU0
  BT44  PVCCIN_CPU0    VCCIN86  @S9S_MB_2U_LIB.S9S_MB_2U(SCH_1):PVCCIN_CPU0
  BT42  PVCCIN_CPU0    VCCIN85  @S9S_MB_2U_LIB.S9S_MB_2U(SCH_1):PVCCIN_CPU0
  BT40  PVCCIN_CPU0    VCCIN84  @S9S_MB_2U_LIB.S9S_MB_2U(SCH_1):PVCCIN_CPU0
  BT38  PVCCIN_CPU0    VCCIN83  @S9S_MB_2U_LIB.S9S_MB_2U(SCH_1):PVCCIN_CPU0
  BT36  PVCCIN_CPU0    VCCIN82  @S9S_MB_2U_LIB.S9S_MB_2U(SCH_1):PVCCIN_CPU0
  BT34  PVCCIN_CPU0    VCCIN81  @S9S_MB_2U_LIB.S9S_MB_2U(SCH_1):PVCCIN_CPU0
  BT32  PVCCIN_CPU0    VCCIN80  @S9S_MB_2U_LIB.S9S_MB_2U(SCH_1):PVCCIN_CPU0
  BR78  PVCCIN_CPU0    VCCIN79  @S9S_MB_2U_LIB.S9S_MB_2U(SCH_1):PVCCIN_CPU0
  BR62  PVCCIN_CPU0    VCCIN78  @S9S_MB_2U_LIB.S9S_MB_2U(SCH_1):PVCCIN_CPU0
  BR60  PVCCIN_CPU0    VCCIN77  @S9S_MB_2U_LIB.S9S_MB_2U(SCH_1):PVCCIN_CPU0
  BP89  PVCCIN_CPU0    VCCIN76  @S9S_MB_2U_LIB.S9S_MB_2U(SCH_1):PVCCIN_CPU0
  BP87  PVCCIN_CPU0    VCCIN75  @S9S_MB_2U_LIB.S9S_MB_2U(SCH_1):PVCCIN_CPU0
  BP85  PVCCIN_CPU0    VCCIN74  @S9S_MB_2U_LIB.S9S_MB_2U(SCH_1):PVCCIN_CPU0
  BP83  PVCCIN_CPU0    VCCIN73  @S9S_MB_2U_LIB.S9S_MB_2U(SCH_1):PVCCIN_CPU0
  BP81  PVCCIN_CPU0    VCCIN72  @S9S_MB_2U_LIB.S9S_MB_2U(SCH_1):PVCCIN_CPU0
  BP79  PVCCIN_CPU0    VCCIN71  @S9S_MB_2U_LIB.S9S_MB_2U(SCH_1):PVCCIN_CPU0
  BP61  PVCCIN_CPU0    VCCIN70  @S9S_MB_2U_LIB.S9S_MB_2U(SCH_1):PVCCIN_CPU0
  BP59  PVCCIN_CPU0    VCCIN69  @S9S_MB_2U_LIB.S9S_MB_2U(SCH_1):PVCCIN_CPU0
  BP57  PVCCIN_CPU0    VCCIN68  @S9S_MB_2U_LIB.S9S_MB_2U(SCH_1):PVCCIN_CPU0
  BP55  PVCCIN_CPU0    VCCIN67  @S9S_MB_2U_LIB.S9S_MB_2U(SCH_1):PVCCIN_CPU0
  BP53  PVCCIN_CPU0    VCCIN66  @S9S_MB_2U_LIB.S9S_MB_2U(SCH_1):PVCCIN_CPU0
  BP51  PVCCIN_CPU0    VCCIN65  @S9S_MB_2U_LIB.S9S_MB_2U(SCH_1):PVCCIN_CPU0
  BP49  PVCCIN_CPU0    VCCIN64  @S9S_MB_2U_LIB.S9S_MB_2U(SCH_1):PVCCIN_CPU0
  BP47  PVCCIN_CPU0    VCCIN63  @S9S_MB_2U_LIB.S9S_MB_2U(SCH_1):PVCCIN_CPU0
  BP44  PVCCIN_CPU0    VCCIN62  @S9S_MB_2U_LIB.S9S_MB_2U(SCH_1):PVCCIN_CPU0
  BP42  PVCCIN_CPU0    VCCIN61  @S9S_MB_2U_LIB.S9S_MB_2U(SCH_1):PVCCIN_CPU0
  BP40  PVCCIN_CPU0    VCCIN60  @S9S_MB_2U_LIB.S9S_MB_2U(SCH_1):PVCCIN_CPU0
  BP38  PVCCIN_CPU0    VCCIN59  @S9S_MB_2U_LIB.S9S_MB_2U(SCH_1):PVCCIN_CPU0
  BP36  PVCCIN_CPU0    VCCIN58  @S9S_MB_2U_LIB.S9S_MB_2U(SCH_1):PVCCIN_CPU0
  BP34  PVCCIN_CPU0    VCCIN57  @S9S_MB_2U_LIB.S9S_MB_2U(SCH_1):PVCCIN_CPU0
  BP32  PVCCIN_CPU0    VCCIN56  @S9S_MB_2U_LIB.S9S_MB_2U(SCH_1):PVCCIN_CPU0
  BN90  PVCCIN_CPU0    VCCIN55  @S9S_MB_2U_LIB.S9S_MB_2U(SCH_1):PVCCIN_CPU0
  BN88  PVCCIN_CPU0    VCCIN54  @S9S_MB_2U_LIB.S9S_MB_2U(SCH_1):PVCCIN_CPU0
  BN86  PVCCIN_CPU0    VCCIN53  @S9S_MB_2U_LIB.S9S_MB_2U(SCH_1):PVCCIN_CPU0
  BN84  PVCCIN_CPU0    VCCIN52  @S9S_MB_2U_LIB.S9S_MB_2U(SCH_1):PVCCIN_CPU0
  BN82  PVCCIN_CPU0    VCCIN51  @S9S_MB_2U_LIB.S9S_MB_2U(SCH_1):PVCCIN_CPU0
  BN80  PVCCIN_CPU0    VCCIN50  @S9S_MB_2U_LIB.S9S_MB_2U(SCH_1):PVCCIN_CPU0
  BN78  PVCCIN_CPU0    VCCIN49  @S9S_MB_2U_LIB.S9S_MB_2U(SCH_1):PVCCIN_CPU0
  BN60  PVCCIN_CPU0    VCCIN48  @S9S_MB_2U_LIB.S9S_MB_2U(SCH_1):PVCCIN_CPU0
  BN58  PVCCIN_CPU0    VCCIN47  @S9S_MB_2U_LIB.S9S_MB_2U(SCH_1):PVCCIN_CPU0
  BN56  PVCCIN_CPU0    VCCIN46  @S9S_MB_2U_LIB.S9S_MB_2U(SCH_1):PVCCIN_CPU0
  BN54  PVCCIN_CPU0    VCCIN45  @S9S_MB_2U_LIB.S9S_MB_2U(SCH_1):PVCCIN_CPU0
  BN52  PVCCIN_CPU0    VCCIN44  @S9S_MB_2U_LIB.S9S_MB_2U(SCH_1):PVCCIN_CPU0
  BN50  PVCCIN_CPU0    VCCIN43  @S9S_MB_2U_LIB.S9S_MB_2U(SCH_1):PVCCIN_CPU0
  BN48  PVCCIN_CPU0    VCCIN42  @S9S_MB_2U_LIB.S9S_MB_2U(SCH_1):PVCCIN_CPU0
  BN45  PVCCIN_CPU0    VCCIN41  @S9S_MB_2U_LIB.S9S_MB_2U(SCH_1):PVCCIN_CPU0
  BN43  PVCCIN_CPU0    VCCIN40  @S9S_MB_2U_LIB.S9S_MB_2U(SCH_1):PVCCIN_CPU0

SOCKET4677_AZIFS054P001C01  I1   U2     [SOCKET4677_AZIFS054P001C01-SOCA]
  CM89  PVCCIN_CPU0    VCCIN339  @S9S_MB_2U_LIB.S9S_MB_2U(SCH_1):PVCCIN_CPU0
  CP89  PVCCIN_CPU0    VCCIN338  @S9S_MB_2U_LIB.S9S_MB_2U(SCH_1):PVCCIN_CPU0
  CN90  PVCCIN_CPU0    VCCIN337  @S9S_MB_2U_LIB.S9S_MB_2U(SCH_1):PVCCIN_CPU0
  CN88  PVCCIN_CPU0    VCCIN336  @S9S_MB_2U_LIB.S9S_MB_2U(SCH_1):PVCCIN_CPU0
  CM91  PVCCIN_CPU0    VCCIN335  @S9S_MB_2U_LIB.S9S_MB_2U(SCH_1):PVCCIN_CPU0
  CM87  PVCCIN_CPU0    VCCIN334  @S9S_MB_2U_LIB.S9S_MB_2U(SCH_1):PVCCIN_CPU0
  CL90  PVCCIN_CPU0    VCCIN333  @S9S_MB_2U_LIB.S9S_MB_2U(SCH_1):PVCCIN_CPU0
  CL88  PVCCIN_CPU0    VCCIN332  @S9S_MB_2U_LIB.S9S_MB_2U(SCH_1):PVCCIN_CPU0
  CL86  PVCCIN_CPU0    VCCIN331  @S9S_MB_2U_LIB.S9S_MB_2U(SCH_1):PVCCIN_CPU0
  CL84  PVCCIN_CPU0    VCCIN330  @S9S_MB_2U_LIB.S9S_MB_2U(SCH_1):PVCCIN_CPU0
  CK91  PVCCIN_CPU0    VCCIN329  @S9S_MB_2U_LIB.S9S_MB_2U(SCH_1):PVCCIN_CPU0
  CK89  PVCCIN_CPU0    VCCIN328  @S9S_MB_2U_LIB.S9S_MB_2U(SCH_1):PVCCIN_CPU0
  CK87  PVCCIN_CPU0    VCCIN327  @S9S_MB_2U_LIB.S9S_MB_2U(SCH_1):PVCCIN_CPU0
  CK85  PVCCIN_CPU0    VCCIN326  @S9S_MB_2U_LIB.S9S_MB_2U(SCH_1):PVCCIN_CPU0
  CK83  PVCCIN_CPU0    VCCIN325  @S9S_MB_2U_LIB.S9S_MB_2U(SCH_1):PVCCIN_CPU0
  CJ90  PVCCIN_CPU0    VCCIN324  @S9S_MB_2U_LIB.S9S_MB_2U(SCH_1):PVCCIN_CPU0
  CJ88  PVCCIN_CPU0    VCCIN323  @S9S_MB_2U_LIB.S9S_MB_2U(SCH_1):PVCCIN_CPU0
  CJ86  PVCCIN_CPU0    VCCIN322  @S9S_MB_2U_LIB.S9S_MB_2U(SCH_1):PVCCIN_CPU0
  CJ84  PVCCIN_CPU0    VCCIN321  @S9S_MB_2U_LIB.S9S_MB_2U(SCH_1):PVCCIN_CPU0
  CJ82  PVCCIN_CPU0    VCCIN320  @S9S_MB_2U_LIB.S9S_MB_2U(SCH_1):PVCCIN_CPU0
  CH91  PVCCIN_CPU0    VCCIN319  @S9S_MB_2U_LIB.S9S_MB_2U(SCH_1):PVCCIN_CPU0
  CH81  PVCCIN_CPU0    VCCIN318  @S9S_MB_2U_LIB.S9S_MB_2U(SCH_1):PVCCIN_CPU0
  CG90  PVCCIN_CPU0    VCCIN317  @S9S_MB_2U_LIB.S9S_MB_2U(SCH_1):PVCCIN_CPU0
  CG88  PVCCIN_CPU0    VCCIN316  @S9S_MB_2U_LIB.S9S_MB_2U(SCH_1):PVCCIN_CPU0
  CG86  PVCCIN_CPU0    VCCIN315  @S9S_MB_2U_LIB.S9S_MB_2U(SCH_1):PVCCIN_CPU0
  CG84  PVCCIN_CPU0    VCCIN314  @S9S_MB_2U_LIB.S9S_MB_2U(SCH_1):PVCCIN_CPU0
  CG82  PVCCIN_CPU0    VCCIN313  @S9S_MB_2U_LIB.S9S_MB_2U(SCH_1):PVCCIN_CPU0
  CG80  PVCCIN_CPU0    VCCIN312  @S9S_MB_2U_LIB.S9S_MB_2U(SCH_1):PVCCIN_CPU0
  CF91  PVCCIN_CPU0    VCCIN311  @S9S_MB_2U_LIB.S9S_MB_2U(SCH_1):PVCCIN_CPU0
  CF89  PVCCIN_CPU0    VCCIN310  @S9S_MB_2U_LIB.S9S_MB_2U(SCH_1):PVCCIN_CPU0
  CF87  PVCCIN_CPU0    VCCIN309  @S9S_MB_2U_LIB.S9S_MB_2U(SCH_1):PVCCIN_CPU0
  CF85  PVCCIN_CPU0    VCCIN308  @S9S_MB_2U_LIB.S9S_MB_2U(SCH_1):PVCCIN_CPU0
  CF83  PVCCIN_CPU0    VCCIN307  @S9S_MB_2U_LIB.S9S_MB_2U(SCH_1):PVCCIN_CPU0
  CF81  PVCCIN_CPU0    VCCIN306  @S9S_MB_2U_LIB.S9S_MB_2U(SCH_1):PVCCIN_CPU0
  CF79  PVCCIN_CPU0    VCCIN305  @S9S_MB_2U_LIB.S9S_MB_2U(SCH_1):PVCCIN_CPU0
  CE90  PVCCIN_CPU0    VCCIN304  @S9S_MB_2U_LIB.S9S_MB_2U(SCH_1):PVCCIN_CPU0
  CE88  PVCCIN_CPU0    VCCIN303  @S9S_MB_2U_LIB.S9S_MB_2U(SCH_1):PVCCIN_CPU0
  CE86  PVCCIN_CPU0    VCCIN302  @S9S_MB_2U_LIB.S9S_MB_2U(SCH_1):PVCCIN_CPU0
  CE84  PVCCIN_CPU0    VCCIN301  @S9S_MB_2U_LIB.S9S_MB_2U(SCH_1):PVCCIN_CPU0
  CE82  PVCCIN_CPU0    VCCIN300  @S9S_MB_2U_LIB.S9S_MB_2U(SCH_1):PVCCIN_CPU0
  CE80  PVCCIN_CPU0    VCCIN299  @S9S_MB_2U_LIB.S9S_MB_2U(SCH_1):PVCCIN_CPU0
  CD89  PVCCIN_CPU0    VCCIN298  @S9S_MB_2U_LIB.S9S_MB_2U(SCH_1):PVCCIN_CPU0
  CD87  PVCCIN_CPU0    VCCIN297  @S9S_MB_2U_LIB.S9S_MB_2U(SCH_1):PVCCIN_CPU0
  CD85  PVCCIN_CPU0    VCCIN296  @S9S_MB_2U_LIB.S9S_MB_2U(SCH_1):PVCCIN_CPU0
  CD83  PVCCIN_CPU0    VCCIN295  @S9S_MB_2U_LIB.S9S_MB_2U(SCH_1):PVCCIN_CPU0
  CD81  PVCCIN_CPU0    VCCIN294  @S9S_MB_2U_LIB.S9S_MB_2U(SCH_1):PVCCIN_CPU0
  CD79  PVCCIN_CPU0    VCCIN293  @S9S_MB_2U_LIB.S9S_MB_2U(SCH_1):PVCCIN_CPU0
  CD59  PVCCIN_CPU0    VCCIN292  @S9S_MB_2U_LIB.S9S_MB_2U(SCH_1):PVCCIN_CPU0
  CD57  PVCCIN_CPU0    VCCIN291  @S9S_MB_2U_LIB.S9S_MB_2U(SCH_1):PVCCIN_CPU0
  CD55  PVCCIN_CPU0    VCCIN290  @S9S_MB_2U_LIB.S9S_MB_2U(SCH_1):PVCCIN_CPU0
  CD53  PVCCIN_CPU0    VCCIN289  @S9S_MB_2U_LIB.S9S_MB_2U(SCH_1):PVCCIN_CPU0
  CD51  PVCCIN_CPU0    VCCIN288  @S9S_MB_2U_LIB.S9S_MB_2U(SCH_1):PVCCIN_CPU0
  CD49  PVCCIN_CPU0    VCCIN287  @S9S_MB_2U_LIB.S9S_MB_2U(SCH_1):PVCCIN_CPU0
  CD47  PVCCIN_CPU0    VCCIN286  @S9S_MB_2U_LIB.S9S_MB_2U(SCH_1):PVCCIN_CPU0
  CD44  PVCCIN_CPU0    VCCIN285  @S9S_MB_2U_LIB.S9S_MB_2U(SCH_1):PVCCIN_CPU0
  CD42  PVCCIN_CPU0    VCCIN284  @S9S_MB_2U_LIB.S9S_MB_2U(SCH_1):PVCCIN_CPU0
  CD40  PVCCIN_CPU0    VCCIN283  @S9S_MB_2U_LIB.S9S_MB_2U(SCH_1):PVCCIN_CPU0
  CD38  PVCCIN_CPU0    VCCIN282  @S9S_MB_2U_LIB.S9S_MB_2U(SCH_1):PVCCIN_CPU0
  CD36  PVCCIN_CPU0    VCCIN281  @S9S_MB_2U_LIB.S9S_MB_2U(SCH_1):PVCCIN_CPU0
  CD34  PVCCIN_CPU0    VCCIN280  @S9S_MB_2U_LIB.S9S_MB_2U(SCH_1):PVCCIN_CPU0
  CD32  PVCCIN_CPU0    VCCIN279  @S9S_MB_2U_LIB.S9S_MB_2U(SCH_1):PVCCIN_CPU0
  CC90  PVCCIN_CPU0    VCCIN278  @S9S_MB_2U_LIB.S9S_MB_2U(SCH_1):PVCCIN_CPU0
  CC88  PVCCIN_CPU0    VCCIN277  @S9S_MB_2U_LIB.S9S_MB_2U(SCH_1):PVCCIN_CPU0
  CC86  PVCCIN_CPU0    VCCIN276  @S9S_MB_2U_LIB.S9S_MB_2U(SCH_1):PVCCIN_CPU0
  CC84  PVCCIN_CPU0    VCCIN275  @S9S_MB_2U_LIB.S9S_MB_2U(SCH_1):PVCCIN_CPU0
  CC82  PVCCIN_CPU0    VCCIN274  @S9S_MB_2U_LIB.S9S_MB_2U(SCH_1):PVCCIN_CPU0
  CC80  PVCCIN_CPU0    VCCIN273  @S9S_MB_2U_LIB.S9S_MB_2U(SCH_1):PVCCIN_CPU0
  CC78  PVCCIN_CPU0    VCCIN272  @S9S_MB_2U_LIB.S9S_MB_2U(SCH_1):PVCCIN_CPU0
  CC76  PVCCIN_CPU0    VCCIN271  @S9S_MB_2U_LIB.S9S_MB_2U(SCH_1):PVCCIN_CPU0
  CC60  PVCCIN_CPU0    VCCIN270  @S9S_MB_2U_LIB.S9S_MB_2U(SCH_1):PVCCIN_CPU0
  CC58  PVCCIN_CPU0    VCCIN269  @S9S_MB_2U_LIB.S9S_MB_2U(SCH_1):PVCCIN_CPU0
  CC56  PVCCIN_CPU0    VCCIN268  @S9S_MB_2U_LIB.S9S_MB_2U(SCH_1):PVCCIN_CPU0
  CC54  PVCCIN_CPU0    VCCIN267  @S9S_MB_2U_LIB.S9S_MB_2U(SCH_1):PVCCIN_CPU0
  CC52  PVCCIN_CPU0    VCCIN266  @S9S_MB_2U_LIB.S9S_MB_2U(SCH_1):PVCCIN_CPU0
  CC50  PVCCIN_CPU0    VCCIN265  @S9S_MB_2U_LIB.S9S_MB_2U(SCH_1):PVCCIN_CPU0
  CC48  PVCCIN_CPU0    VCCIN264  @S9S_MB_2U_LIB.S9S_MB_2U(SCH_1):PVCCIN_CPU0
  CC45  PVCCIN_CPU0    VCCIN263  @S9S_MB_2U_LIB.S9S_MB_2U(SCH_1):PVCCIN_CPU0
  CC43  PVCCIN_CPU0    VCCIN262  @S9S_MB_2U_LIB.S9S_MB_2U(SCH_1):PVCCIN_CPU0
  CC41  PVCCIN_CPU0    VCCIN261  @S9S_MB_2U_LIB.S9S_MB_2U(SCH_1):PVCCIN_CPU0
  CC39  PVCCIN_CPU0    VCCIN260  @S9S_MB_2U_LIB.S9S_MB_2U(SCH_1):PVCCIN_CPU0
  CC37  PVCCIN_CPU0    VCCIN259  @S9S_MB_2U_LIB.S9S_MB_2U(SCH_1):PVCCIN_CPU0
  CC35  PVCCIN_CPU0    VCCIN258  @S9S_MB_2U_LIB.S9S_MB_2U(SCH_1):PVCCIN_CPU0
  CC33  PVCCIN_CPU0    VCCIN257  @S9S_MB_2U_LIB.S9S_MB_2U(SCH_1):PVCCIN_CPU0
  CB77  PVCCIN_CPU0    VCCIN256  @S9S_MB_2U_LIB.S9S_MB_2U(SCH_1):PVCCIN_CPU0
  CB75  PVCCIN_CPU0    VCCIN255  @S9S_MB_2U_LIB.S9S_MB_2U(SCH_1):PVCCIN_CPU0
  CB61  PVCCIN_CPU0    VCCIN254  @S9S_MB_2U_LIB.S9S_MB_2U(SCH_1):PVCCIN_CPU0
  CA90  PVCCIN_CPU0    VCCIN253  @S9S_MB_2U_LIB.S9S_MB_2U(SCH_1):PVCCIN_CPU0
  CA88  PVCCIN_CPU0    VCCIN252  @S9S_MB_2U_LIB.S9S_MB_2U(SCH_1):PVCCIN_CPU0
  CA86  PVCCIN_CPU0    VCCIN251  @S9S_MB_2U_LIB.S9S_MB_2U(SCH_1):PVCCIN_CPU0
  CA84  PVCCIN_CPU0    VCCIN250  @S9S_MB_2U_LIB.S9S_MB_2U(SCH_1):PVCCIN_CPU0
  CA82  PVCCIN_CPU0    VCCIN249  @S9S_MB_2U_LIB.S9S_MB_2U(SCH_1):PVCCIN_CPU0
  CA80  PVCCIN_CPU0    VCCIN248  @S9S_MB_2U_LIB.S9S_MB_2U(SCH_1):PVCCIN_CPU0
  CA78  PVCCIN_CPU0    VCCIN247  @S9S_MB_2U_LIB.S9S_MB_2U(SCH_1):PVCCIN_CPU0
  CA76  PVCCIN_CPU0    VCCIN246  @S9S_MB_2U_LIB.S9S_MB_2U(SCH_1):PVCCIN_CPU0
  CA74  PVCCIN_CPU0    VCCIN245  @S9S_MB_2U_LIB.S9S_MB_2U(SCH_1):PVCCIN_CPU0
  CA72  PVCCIN_CPU0    VCCIN244  @S9S_MB_2U_LIB.S9S_MB_2U(SCH_1):PVCCIN_CPU0
  CA70  PVCCIN_CPU0    VCCIN243  @S9S_MB_2U_LIB.S9S_MB_2U(SCH_1):PVCCIN_CPU0
  CA68  PVCCIN_CPU0    VCCIN242  @S9S_MB_2U_LIB.S9S_MB_2U(SCH_1):PVCCIN_CPU0
  CA66  PVCCIN_CPU0    VCCIN241  @S9S_MB_2U_LIB.S9S_MB_2U(SCH_1):PVCCIN_CPU0
  CA64  PVCCIN_CPU0    VCCIN240  @S9S_MB_2U_LIB.S9S_MB_2U(SCH_1):PVCCIN_CPU0
  CA62  PVCCIN_CPU0    VCCIN239  @S9S_MB_2U_LIB.S9S_MB_2U(SCH_1):PVCCIN_CPU0
  CA60  PVCCIN_CPU0    VCCIN238  @S9S_MB_2U_LIB.S9S_MB_2U(SCH_1):PVCCIN_CPU0
  CA58  PVCCIN_CPU0    VCCIN237  @S9S_MB_2U_LIB.S9S_MB_2U(SCH_1):PVCCIN_CPU0
  CA56  PVCCIN_CPU0    VCCIN236  @S9S_MB_2U_LIB.S9S_MB_2U(SCH_1):PVCCIN_CPU0
  CA54  PVCCIN_CPU0    VCCIN235  @S9S_MB_2U_LIB.S9S_MB_2U(SCH_1):PVCCIN_CPU0
  CA52  PVCCIN_CPU0    VCCIN234  @S9S_MB_2U_LIB.S9S_MB_2U(SCH_1):PVCCIN_CPU0
  CA50  PVCCIN_CPU0    VCCIN233  @S9S_MB_2U_LIB.S9S_MB_2U(SCH_1):PVCCIN_CPU0
  CA48  PVCCIN_CPU0    VCCIN232  @S9S_MB_2U_LIB.S9S_MB_2U(SCH_1):PVCCIN_CPU0
  CA45  PVCCIN_CPU0    VCCIN231  @S9S_MB_2U_LIB.S9S_MB_2U(SCH_1):PVCCIN_CPU0
  CA43  PVCCIN_CPU0    VCCIN230  @S9S_MB_2U_LIB.S9S_MB_2U(SCH_1):PVCCIN_CPU0
  CA41  PVCCIN_CPU0    VCCIN229  @S9S_MB_2U_LIB.S9S_MB_2U(SCH_1):PVCCIN_CPU0
  CA39  PVCCIN_CPU0    VCCIN228  @S9S_MB_2U_LIB.S9S_MB_2U(SCH_1):PVCCIN_CPU0
  CA37  PVCCIN_CPU0    VCCIN227  @S9S_MB_2U_LIB.S9S_MB_2U(SCH_1):PVCCIN_CPU0
  CA35  PVCCIN_CPU0    VCCIN226  @S9S_MB_2U_LIB.S9S_MB_2U(SCH_1):PVCCIN_CPU0
  CA33  PVCCIN_CPU0    VCCIN225  @S9S_MB_2U_LIB.S9S_MB_2U(SCH_1):PVCCIN_CPU0
  BY89  PVCCIN_CPU0    VCCIN224  @S9S_MB_2U_LIB.S9S_MB_2U(SCH_1):PVCCIN_CPU0
  BY87  PVCCIN_CPU0    VCCIN223  @S9S_MB_2U_LIB.S9S_MB_2U(SCH_1):PVCCIN_CPU0
  BY85  PVCCIN_CPU0    VCCIN222  @S9S_MB_2U_LIB.S9S_MB_2U(SCH_1):PVCCIN_CPU0
  BY83  PVCCIN_CPU0    VCCIN221  @S9S_MB_2U_LIB.S9S_MB_2U(SCH_1):PVCCIN_CPU0
  BY81  PVCCIN_CPU0    VCCIN220  @S9S_MB_2U_LIB.S9S_MB_2U(SCH_1):PVCCIN_CPU0
  BY79  PVCCIN_CPU0    VCCIN219  @S9S_MB_2U_LIB.S9S_MB_2U(SCH_1):PVCCIN_CPU0
  BY77  PVCCIN_CPU0    VCCIN218  @S9S_MB_2U_LIB.S9S_MB_2U(SCH_1):PVCCIN_CPU0
  BY75  PVCCIN_CPU0    VCCIN217  @S9S_MB_2U_LIB.S9S_MB_2U(SCH_1):PVCCIN_CPU0
  BY73  PVCCIN_CPU0    VCCIN216  @S9S_MB_2U_LIB.S9S_MB_2U(SCH_1):PVCCIN_CPU0
  BY71  PVCCIN_CPU0    VCCIN215  @S9S_MB_2U_LIB.S9S_MB_2U(SCH_1):PVCCIN_CPU0
  BY69  PVCCIN_CPU0    VCCIN214  @S9S_MB_2U_LIB.S9S_MB_2U(SCH_1):PVCCIN_CPU0
  BY67  PVCCIN_CPU0    VCCIN213  @S9S_MB_2U_LIB.S9S_MB_2U(SCH_1):PVCCIN_CPU0
  BY65  PVCCIN_CPU0    VCCIN212  @S9S_MB_2U_LIB.S9S_MB_2U(SCH_1):PVCCIN_CPU0
  BY63  PVCCIN_CPU0    VCCIN211  @S9S_MB_2U_LIB.S9S_MB_2U(SCH_1):PVCCIN_CPU0
  BY61  PVCCIN_CPU0    VCCIN210  @S9S_MB_2U_LIB.S9S_MB_2U(SCH_1):PVCCIN_CPU0
  BY59  PVCCIN_CPU0    VCCIN209  @S9S_MB_2U_LIB.S9S_MB_2U(SCH_1):PVCCIN_CPU0
  BY57  PVCCIN_CPU0    VCCIN208  @S9S_MB_2U_LIB.S9S_MB_2U(SCH_1):PVCCIN_CPU0
  BY55  PVCCIN_CPU0    VCCIN207  @S9S_MB_2U_LIB.S9S_MB_2U(SCH_1):PVCCIN_CPU0
  BY53  PVCCIN_CPU0    VCCIN206  @S9S_MB_2U_LIB.S9S_MB_2U(SCH_1):PVCCIN_CPU0
  BY51  PVCCIN_CPU0    VCCIN205  @S9S_MB_2U_LIB.S9S_MB_2U(SCH_1):PVCCIN_CPU0
  BY49  PVCCIN_CPU0    VCCIN204  @S9S_MB_2U_LIB.S9S_MB_2U(SCH_1):PVCCIN_CPU0
  BY47  PVCCIN_CPU0    VCCIN203  @S9S_MB_2U_LIB.S9S_MB_2U(SCH_1):PVCCIN_CPU0
  BY44  PVCCIN_CPU0    VCCIN202  @S9S_MB_2U_LIB.S9S_MB_2U(SCH_1):PVCCIN_CPU0
  BY42  PVCCIN_CPU0    VCCIN201  @S9S_MB_2U_LIB.S9S_MB_2U(SCH_1):PVCCIN_CPU0
  BY40  PVCCIN_CPU0    VCCIN200  @S9S_MB_2U_LIB.S9S_MB_2U(SCH_1):PVCCIN_CPU0
  BY38  PVCCIN_CPU0    VCCIN199  @S9S_MB_2U_LIB.S9S_MB_2U(SCH_1):PVCCIN_CPU0
  BY36  PVCCIN_CPU0    VCCIN198  @S9S_MB_2U_LIB.S9S_MB_2U(SCH_1):PVCCIN_CPU0
  BY34  PVCCIN_CPU0    VCCIN197  @S9S_MB_2U_LIB.S9S_MB_2U(SCH_1):PVCCIN_CPU0
  BY32  PVCCIN_CPU0    VCCIN196  @S9S_MB_2U_LIB.S9S_MB_2U(SCH_1):PVCCIN_CPU0
  BW90  PVCCIN_CPU0    VCCIN195  @S9S_MB_2U_LIB.S9S_MB_2U(SCH_1):PVCCIN_CPU0
  BW88  PVCCIN_CPU0    VCCIN194  @S9S_MB_2U_LIB.S9S_MB_2U(SCH_1):PVCCIN_CPU0
  BW86  PVCCIN_CPU0    VCCIN193  @S9S_MB_2U_LIB.S9S_MB_2U(SCH_1):PVCCIN_CPU0
  BW84  PVCCIN_CPU0    VCCIN192  @S9S_MB_2U_LIB.S9S_MB_2U(SCH_1):PVCCIN_CPU0
  BW82  PVCCIN_CPU0    VCCIN191  @S9S_MB_2U_LIB.S9S_MB_2U(SCH_1):PVCCIN_CPU0
  BW80  PVCCIN_CPU0    VCCIN190  @S9S_MB_2U_LIB.S9S_MB_2U(SCH_1):PVCCIN_CPU0

SOCKET4677_AZIFS054P001C01  I102  U2     [SOCKET4677_AZIFS054P001C01-SOCA]
  DB83  UPI_CPU1_CPU0_P3P3_DP<9>  UPI3_RX_DP14  @S9S_MB_2U_LIB.S9S_MB_2U(SCH_1):UPI_CPU1_CPU0_P3P3_DP<9>
  DD81  UPI_CPU1_CPU0_P3P3_DP<8>  UPI3_RX_DP15  @S9S_MB_2U_LIB.S9S_MB_2U(SCH_1):UPI_CPU1_CPU0_P3P3_DP<8>
  DE78  UPI_CPU1_CPU0_P3P3_DP<7>  UPI3_RX_DP16  @S9S_MB_2U_LIB.S9S_MB_2U(SCH_1):UPI_CPU1_CPU0_P3P3_DP<7>
  CW82  UPI_CPU1_CPU0_P3P3_DP<6>  UPI3_RX_DP17  @S9S_MB_2U_LIB.S9S_MB_2U(SCH_1):UPI_CPU1_CPU0_P3P3_DP<6>
  CT83  UPI_CPU1_CPU0_P3P3_DP<5>  UPI3_RX_DP18  @S9S_MB_2U_LIB.S9S_MB_2U(SCH_1):UPI_CPU1_CPU0_P3P3_DP<5>
  CV81  UPI_CPU1_CPU0_P3P3_DP<4>  UPI3_RX_DP19  @S9S_MB_2U_LIB.S9S_MB_2U(SCH_1):UPI_CPU1_CPU0_P3P3_DP<4>
  CN82  UPI_CPU1_CPU0_P3P3_DP<3>  UPI3_RX_DP20  @S9S_MB_2U_LIB.S9S_MB_2U(SCH_1):UPI_CPU1_CPU0_P3P3_DP<3>
  CR80  UPI_CPU1_CPU0_P3P3_DP<2>  UPI3_RX_DP21  @S9S_MB_2U_LIB.S9S_MB_2U(SCH_1):UPI_CPU1_CPU0_P3P3_DP<2>
  EL80  UPI_CPU1_CPU0_P3P3_DP<23>  UPI3_RX_DP0  @S9S_MB_2U_LIB.S9S_MB_2U(SCH_1):UPI_CPU1_CPU0_P3P3_DP<23>
  ER82  UPI_CPU1_CPU0_P3P3_DP<22>  UPI3_RX_DP1  @S9S_MB_2U_LIB.S9S_MB_2U(SCH_1):UPI_CPU1_CPU0_P3P3_DP<22>
  EN82  UPI_CPU1_CPU0_P3P3_DP<21>  UPI3_RX_DP2  @S9S_MB_2U_LIB.S9S_MB_2U(SCH_1):UPI_CPU1_CPU0_P3P3_DP<21>
  EJ82  UPI_CPU1_CPU0_P3P3_DP<20>  UPI3_RX_DP3  @S9S_MB_2U_LIB.S9S_MB_2U(SCH_1):UPI_CPU1_CPU0_P3P3_DP<20>
  CU80  UPI_CPU1_CPU0_P3P3_DP<1>  UPI3_RX_DP22  @S9S_MB_2U_LIB.S9S_MB_2U(SCH_1):UPI_CPU1_CPU0_P3P3_DP<1>
  EE82  UPI_CPU1_CPU0_P3P3_DP<19>  UPI3_RX_DP4  @S9S_MB_2U_LIB.S9S_MB_2U(SCH_1):UPI_CPU1_CPU0_P3P3_DP<19>
  EF83  UPI_CPU1_CPU0_P3P3_DP<18>  UPI3_RX_DP5  @S9S_MB_2U_LIB.S9S_MB_2U(SCH_1):UPI_CPU1_CPU0_P3P3_DP<18>
  ED81  UPI_CPU1_CPU0_P3P3_DP<17>  UPI3_RX_DP6  @S9S_MB_2U_LIB.S9S_MB_2U(SCH_1):UPI_CPU1_CPU0_P3P3_DP<17>
  DY83  UPI_CPU1_CPU0_P3P3_DP<16>  UPI3_RX_DP7  @S9S_MB_2U_LIB.S9S_MB_2U(SCH_1):UPI_CPU1_CPU0_P3P3_DP<16>
  EB81  UPI_CPU1_CPU0_P3P3_DP<15>  UPI3_RX_DP8  @S9S_MB_2U_LIB.S9S_MB_2U(SCH_1):UPI_CPU1_CPU0_P3P3_DP<15>
  DL78  UPI_CPU1_CPU0_P3P3_DP<14>  UPI3_RX_DP9  @S9S_MB_2U_LIB.S9S_MB_2U(SCH_1):UPI_CPU1_CPU0_P3P3_DP<14>
  DH79  UPI_CPU1_CPU0_P3P3_DP<13>  UPI3_RX_DP10  @S9S_MB_2U_LIB.S9S_MB_2U(SCH_1):UPI_CPU1_CPU0_P3P3_DP<13>
  DG82  UPI_CPU1_CPU0_P3P3_DP<12>  UPI3_RX_DP11  @S9S_MB_2U_LIB.S9S_MB_2U(SCH_1):UPI_CPU1_CPU0_P3P3_DP<12>
  DH83  UPI_CPU1_CPU0_P3P3_DP<11>  UPI3_RX_DP12  @S9S_MB_2U_LIB.S9S_MB_2U(SCH_1):UPI_CPU1_CPU0_P3P3_DP<11>
  DF81  UPI_CPU1_CPU0_P3P3_DP<10>  UPI3_RX_DP13  @S9S_MB_2U_LIB.S9S_MB_2U(SCH_1):UPI_CPU1_CPU0_P3P3_DP<10>
  DB79  UPI_CPU1_CPU0_P3P3_DP<0>  UPI3_RX_DP23  @S9S_MB_2U_LIB.S9S_MB_2U(SCH_1):UPI_CPU1_CPU0_P3P3_DP<0>
  DC82  UPI_CPU1_CPU0_P3P3_DN<9>  UPI3_RX_DN14  @S9S_MB_2U_LIB.S9S_MB_2U(SCH_1):UPI_CPU1_CPU0_P3P3_DN<9>
  DB81  UPI_CPU1_CPU0_P3P3_DN<8>  UPI3_RX_DN15  @S9S_MB_2U_LIB.S9S_MB_2U(SCH_1):UPI_CPU1_CPU0_P3P3_DN<8>
  DF77  UPI_CPU1_CPU0_P3P3_DN<7>  UPI3_RX_DN16  @S9S_MB_2U_LIB.S9S_MB_2U(SCH_1):UPI_CPU1_CPU0_P3P3_DN<7>
  CU82  UPI_CPU1_CPU0_P3P3_DN<6>  UPI3_RX_DN17  @S9S_MB_2U_LIB.S9S_MB_2U(SCH_1):UPI_CPU1_CPU0_P3P3_DN<6>
  CR82  UPI_CPU1_CPU0_P3P3_DN<5>  UPI3_RX_DN18  @S9S_MB_2U_LIB.S9S_MB_2U(SCH_1):UPI_CPU1_CPU0_P3P3_DN<5>
  CW80  UPI_CPU1_CPU0_P3P3_DN<4>  UPI3_RX_DN19  @S9S_MB_2U_LIB.S9S_MB_2U(SCH_1):UPI_CPU1_CPU0_P3P3_DN<4>
  CP81  UPI_CPU1_CPU0_P3P3_DN<3>  UPI3_RX_DN20  @S9S_MB_2U_LIB.S9S_MB_2U(SCH_1):UPI_CPU1_CPU0_P3P3_DN<3>
  CN80  UPI_CPU1_CPU0_P3P3_DN<2>  UPI3_RX_DN21  @S9S_MB_2U_LIB.S9S_MB_2U(SCH_1):UPI_CPU1_CPU0_P3P3_DN<2>
  EJ80  UPI_CPU1_CPU0_P3P3_DN<23>  UPI3_RX_DN0  @S9S_MB_2U_LIB.S9S_MB_2U(SCH_1):UPI_CPU1_CPU0_P3P3_DN<23>
  EP81  UPI_CPU1_CPU0_P3P3_DN<22>  UPI3_RX_DN1  @S9S_MB_2U_LIB.S9S_MB_2U(SCH_1):UPI_CPU1_CPU0_P3P3_DN<22>
  EL82  UPI_CPU1_CPU0_P3P3_DN<21>  UPI3_RX_DN2  @S9S_MB_2U_LIB.S9S_MB_2U(SCH_1):UPI_CPU1_CPU0_P3P3_DN<21>
  EK81  UPI_CPU1_CPU0_P3P3_DN<20>  UPI3_RX_DN3  @S9S_MB_2U_LIB.S9S_MB_2U(SCH_1):UPI_CPU1_CPU0_P3P3_DN<20>
  CT79  UPI_CPU1_CPU0_P3P3_DN<1>  UPI3_RX_DN22  @S9S_MB_2U_LIB.S9S_MB_2U(SCH_1):UPI_CPU1_CPU0_P3P3_DN<1>
  EF81  UPI_CPU1_CPU0_P3P3_DN<19>  UPI3_RX_DN4  @S9S_MB_2U_LIB.S9S_MB_2U(SCH_1):UPI_CPU1_CPU0_P3P3_DN<19>
  ED83  UPI_CPU1_CPU0_P3P3_DN<18>  UPI3_RX_DN5  @S9S_MB_2U_LIB.S9S_MB_2U(SCH_1):UPI_CPU1_CPU0_P3P3_DN<18>
  EC80  UPI_CPU1_CPU0_P3P3_DN<17>  UPI3_RX_DN6  @S9S_MB_2U_LIB.S9S_MB_2U(SCH_1):UPI_CPU1_CPU0_P3P3_DN<17>
  EA82  UPI_CPU1_CPU0_P3P3_DN<16>  UPI3_RX_DN7  @S9S_MB_2U_LIB.S9S_MB_2U(SCH_1):UPI_CPU1_CPU0_P3P3_DN<16>
  DY81  UPI_CPU1_CPU0_P3P3_DN<15>  UPI3_RX_DN8  @S9S_MB_2U_LIB.S9S_MB_2U(SCH_1):UPI_CPU1_CPU0_P3P3_DN<15>
  DJ78  UPI_CPU1_CPU0_P3P3_DN<14>  UPI3_RX_DN9  @S9S_MB_2U_LIB.S9S_MB_2U(SCH_1):UPI_CPU1_CPU0_P3P3_DN<14>
  DG78  UPI_CPU1_CPU0_P3P3_DN<13>  UPI3_RX_DN10  @S9S_MB_2U_LIB.S9S_MB_2U(SCH_1):UPI_CPU1_CPU0_P3P3_DN<13>
  DH81  UPI_CPU1_CPU0_P3P3_DN<12>  UPI3_RX_DN11  @S9S_MB_2U_LIB.S9S_MB_2U(SCH_1):UPI_CPU1_CPU0_P3P3_DN<12>
  DF83  UPI_CPU1_CPU0_P3P3_DN<11>  UPI3_RX_DN12  @S9S_MB_2U_LIB.S9S_MB_2U(SCH_1):UPI_CPU1_CPU0_P3P3_DN<11>
  DE80  UPI_CPU1_CPU0_P3P3_DN<10>  UPI3_RX_DN13  @S9S_MB_2U_LIB.S9S_MB_2U(SCH_1):UPI_CPU1_CPU0_P3P3_DN<10>
  DA78  UPI_CPU1_CPU0_P3P3_DN<0>  UPI3_RX_DN23  @S9S_MB_2U_LIB.S9S_MB_2U(SCH_1):UPI_CPU1_CPU0_P3P3_DN<0>
  CR76  UPI_CPU0_CPU1_P3P3_DP<9>  UPI3_TX_DP14  @S9S_MB_2U_LIB.S9S_MB_2U(SCH_1):UPI_CPU0_CPU1_P3P3_DP<9>
  CR74  UPI_CPU0_CPU1_P3P3_DP<8>  UPI3_TX_DN15  @S9S_MB_2U_LIB.S9S_MB_2U(SCH_1):UPI_CPU0_CPU1_P3P3_DP<8>
  CK77  UPI_CPU0_CPU1_P3P3_DP<7>  UPI3_TX_DN16  @S9S_MB_2U_LIB.S9S_MB_2U(SCH_1):UPI_CPU0_CPU1_P3P3_DP<7>
  CJ78  UPI_CPU0_CPU1_P3P3_DP<6>  UPI3_TX_DP17  @S9S_MB_2U_LIB.S9S_MB_2U(SCH_1):UPI_CPU0_CPU1_P3P3_DP<6>
  CM75  UPI_CPU0_CPU1_P3P3_DP<5>  UPI3_TX_DN18  @S9S_MB_2U_LIB.S9S_MB_2U(SCH_1):UPI_CPU0_CPU1_P3P3_DP<5>
  CF77  UPI_CPU0_CPU1_P3P3_DP<4>  UPI3_TX_DP19  @S9S_MB_2U_LIB.S9S_MB_2U(SCH_1):UPI_CPU0_CPU1_P3P3_DP<4>
  CF75  UPI_CPU0_CPU1_P3P3_DP<3>  UPI3_TX_DN20  @S9S_MB_2U_LIB.S9S_MB_2U(SCH_1):UPI_CPU0_CPU1_P3P3_DP<3>
  CJ74  UPI_CPU0_CPU1_P3P3_DP<2>  UPI3_TX_DN21  @S9S_MB_2U_LIB.S9S_MB_2U(SCH_1):UPI_CPU0_CPU1_P3P3_DP<2>
  EK85  UPI_CPU0_CPU1_P3P3_DP<23>  UPI3_TX_DP0  @S9S_MB_2U_LIB.S9S_MB_2U(SCH_1):UPI_CPU0_CPU1_P3P3_DP<23>
  EM85  UPI_CPU0_CPU1_P3P3_DP<22>  UPI3_TX_DP1  @S9S_MB_2U_LIB.S9S_MB_2U(SCH_1):UPI_CPU0_CPU1_P3P3_DP<22>
  EN86  UPI_CPU0_CPU1_P3P3_DP<21>  UPI3_TX_DP2  @S9S_MB_2U_LIB.S9S_MB_2U(SCH_1):UPI_CPU0_CPU1_P3P3_DP<21>
  EM87  UPI_CPU0_CPU1_P3P3_DP<20>  UPI3_TX_DN3  @S9S_MB_2U_LIB.S9S_MB_2U(SCH_1):UPI_CPU0_CPU1_P3P3_DP<20>
  CV73  UPI_CPU0_CPU1_P3P3_DP<1>  UPI3_TX_DN22  @S9S_MB_2U_LIB.S9S_MB_2U(SCH_1):UPI_CPU0_CPU1_P3P3_DP<1>
  EH87  UPI_CPU0_CPU1_P3P3_DP<19>  UPI3_TX_DP4  @S9S_MB_2U_LIB.S9S_MB_2U(SCH_1):UPI_CPU0_CPU1_P3P3_DP<19>
  EK87  UPI_CPU0_CPU1_P3P3_DP<18>  UPI3_TX_DN5  @S9S_MB_2U_LIB.S9S_MB_2U(SCH_1):UPI_CPU0_CPU1_P3P3_DP<18>
  DT81  UPI_CPU0_CPU1_P3P3_DP<17>  UPI3_TX_DP6  @S9S_MB_2U_LIB.S9S_MB_2U(SCH_1):UPI_CPU0_CPU1_P3P3_DP<17>
  DR82  UPI_CPU0_CPU1_P3P3_DP<16>  UPI3_TX_DN7  @S9S_MB_2U_LIB.S9S_MB_2U(SCH_1):UPI_CPU0_CPU1_P3P3_DP<16>
  DP79  UPI_CPU0_CPU1_P3P3_DP<15>  UPI3_TX_DN8  @S9S_MB_2U_LIB.S9S_MB_2U(SCH_1):UPI_CPU0_CPU1_P3P3_DP<15>
  DP83  UPI_CPU0_CPU1_P3P3_DP<14>  UPI3_TX_DP9  @S9S_MB_2U_LIB.S9S_MB_2U(SCH_1):UPI_CPU0_CPU1_P3P3_DP<14>
  DL82  UPI_CPU0_CPU1_P3P3_DP<13>  UPI3_TX_DP10  @S9S_MB_2U_LIB.S9S_MB_2U(SCH_1):UPI_CPU0_CPU1_P3P3_DP<13>
  DL80  UPI_CPU0_CPU1_P3P3_DP<12>  UPI3_TX_DN11  @S9S_MB_2U_LIB.S9S_MB_2U(SCH_1):UPI_CPU0_CPU1_P3P3_DP<12>
  DA76  UPI_CPU0_CPU1_P3P3_DP<11>  UPI3_TX_DP12  @S9S_MB_2U_LIB.S9S_MB_2U(SCH_1):UPI_CPU0_CPU1_P3P3_DP<11>
  CV77  UPI_CPU0_CPU1_P3P3_DP<10>  UPI3_TX_DP13  @S9S_MB_2U_LIB.S9S_MB_2U(SCH_1):UPI_CPU0_CPU1_P3P3_DP<10>
  CF73  UPI_CPU0_CPU1_P3P3_DP<0>  UPI3_TX_DN23  @S9S_MB_2U_LIB.S9S_MB_2U(SCH_1):UPI_CPU0_CPU1_P3P3_DP<0>
  CT75  UPI_CPU0_CPU1_P3P3_DN<9>  UPI3_TX_DN14  @S9S_MB_2U_LIB.S9S_MB_2U(SCH_1):UPI_CPU0_CPU1_P3P3_DN<9>
  CU74  UPI_CPU0_CPU1_P3P3_DN<8>  UPI3_TX_DP15  @S9S_MB_2U_LIB.S9S_MB_2U(SCH_1):UPI_CPU0_CPU1_P3P3_DN<8>
  CM77  UPI_CPU0_CPU1_P3P3_DN<7>  UPI3_TX_DP16  @S9S_MB_2U_LIB.S9S_MB_2U(SCH_1):UPI_CPU0_CPU1_P3P3_DN<7>
  CH77  UPI_CPU0_CPU1_P3P3_DN<6>  UPI3_TX_DN17  @S9S_MB_2U_LIB.S9S_MB_2U(SCH_1):UPI_CPU0_CPU1_P3P3_DN<6>
  CL76  UPI_CPU0_CPU1_P3P3_DN<5>  UPI3_TX_DP18  @S9S_MB_2U_LIB.S9S_MB_2U(SCH_1):UPI_CPU0_CPU1_P3P3_DN<5>
  CG76  UPI_CPU0_CPU1_P3P3_DN<4>  UPI3_TX_DN19  @S9S_MB_2U_LIB.S9S_MB_2U(SCH_1):UPI_CPU0_CPU1_P3P3_DN<4>
  CH75  UPI_CPU0_CPU1_P3P3_DN<3>  UPI3_TX_DP20  @S9S_MB_2U_LIB.S9S_MB_2U(SCH_1):UPI_CPU0_CPU1_P3P3_DN<3>
  CK75  UPI_CPU0_CPU1_P3P3_DN<2>  UPI3_TX_DP21  @S9S_MB_2U_LIB.S9S_MB_2U(SCH_1):UPI_CPU0_CPU1_P3P3_DN<2>
  EH85  UPI_CPU0_CPU1_P3P3_DN<23>  UPI3_TX_DN0  @S9S_MB_2U_LIB.S9S_MB_2U(SCH_1):UPI_CPU0_CPU1_P3P3_DN<23>
  EL84  UPI_CPU0_CPU1_P3P3_DN<22>  UPI3_TX_DN1  @S9S_MB_2U_LIB.S9S_MB_2U(SCH_1):UPI_CPU0_CPU1_P3P3_DN<22>
  EP85  UPI_CPU0_CPU1_P3P3_DN<21>  UPI3_TX_DN2  @S9S_MB_2U_LIB.S9S_MB_2U(SCH_1):UPI_CPU0_CPU1_P3P3_DN<21>
  EP87  UPI_CPU0_CPU1_P3P3_DN<20>  UPI3_TX_DP3  @S9S_MB_2U_LIB.S9S_MB_2U(SCH_1):UPI_CPU0_CPU1_P3P3_DN<20>
  CW74  UPI_CPU0_CPU1_P3P3_DN<1>  UPI3_TX_DP22  @S9S_MB_2U_LIB.S9S_MB_2U(SCH_1):UPI_CPU0_CPU1_P3P3_DN<1>
  EJ86  UPI_CPU0_CPU1_P3P3_DN<19>  UPI3_TX_DN4  @S9S_MB_2U_LIB.S9S_MB_2U(SCH_1):UPI_CPU0_CPU1_P3P3_DN<19>
  EL88  UPI_CPU0_CPU1_P3P3_DN<18>  UPI3_TX_DP5  @S9S_MB_2U_LIB.S9S_MB_2U(SCH_1):UPI_CPU0_CPU1_P3P3_DN<18>
  DU80  UPI_CPU0_CPU1_P3P3_DN<17>  UPI3_TX_DN6  @S9S_MB_2U_LIB.S9S_MB_2U(SCH_1):UPI_CPU0_CPU1_P3P3_DN<17>
  DU82  UPI_CPU0_CPU1_P3P3_DN<16>  UPI3_TX_DP7  @S9S_MB_2U_LIB.S9S_MB_2U(SCH_1):UPI_CPU0_CPU1_P3P3_DN<16>
  DR80  UPI_CPU0_CPU1_P3P3_DN<15>  UPI3_TX_DP8  @S9S_MB_2U_LIB.S9S_MB_2U(SCH_1):UPI_CPU0_CPU1_P3P3_DN<15>
  DN82  UPI_CPU0_CPU1_P3P3_DN<14>  UPI3_TX_DN9  @S9S_MB_2U_LIB.S9S_MB_2U(SCH_1):UPI_CPU0_CPU1_P3P3_DN<14>
  DM81  UPI_CPU0_CPU1_P3P3_DN<13>  UPI3_TX_DN10  @S9S_MB_2U_LIB.S9S_MB_2U(SCH_1):UPI_CPU0_CPU1_P3P3_DN<13>
  DN80  UPI_CPU0_CPU1_P3P3_DN<12>  UPI3_TX_DP11  @S9S_MB_2U_LIB.S9S_MB_2U(SCH_1):UPI_CPU0_CPU1_P3P3_DN<12>
  CW76  UPI_CPU0_CPU1_P3P3_DN<11>  UPI3_TX_DN12  @S9S_MB_2U_LIB.S9S_MB_2U(SCH_1):UPI_CPU0_CPU1_P3P3_DN<11>
  CU76  UPI_CPU0_CPU1_P3P3_DN<10>  UPI3_TX_DN13  @S9S_MB_2U_LIB.S9S_MB_2U(SCH_1):UPI_CPU0_CPU1_P3P3_DN<10>
  CD73  UPI_CPU0_CPU1_P3P3_DN<0>  UPI3_TX_DP23  @S9S_MB_2U_LIB.S9S_MB_2U(SCH_1):UPI_CPU0_CPU1_P3P3_DN<0>

SOCKET4677_AZIFS054P001C01  I102  U2     [SOCKET4677_AZIFS054P001C01-SOCA]
  BA76  UPI_CPU1_CPU0_P2P2_DP<9>  UPI2_RX_DP14  @S9S_MB_2U_LIB.S9S_MB_2U(SCH_1):UPI_CPU1_CPU0_P2P2_DP<9>
  BB75  UPI_CPU1_CPU0_P2P2_DP<8>  UPI2_RX_DN15  @S9S_MB_2U_LIB.S9S_MB_2U(SCH_1):UPI_CPU1_CPU0_P2P2_DP<8>
  AW74  UPI_CPU1_CPU0_P2P2_DP<7>  UPI2_RX_DN16  @S9S_MB_2U_LIB.S9S_MB_2U(SCH_1):UPI_CPU1_CPU0_P2P2_DP<7>
  BG76  UPI_CPU1_CPU0_P2P2_DP<6>  UPI2_RX_DP17  @S9S_MB_2U_LIB.S9S_MB_2U(SCH_1):UPI_CPU1_CPU0_P2P2_DP<6>
  BK77  UPI_CPU1_CPU0_P2P2_DP<5>  UPI2_RX_DP18  @S9S_MB_2U_LIB.S9S_MB_2U(SCH_1):UPI_CPU1_CPU0_P2P2_DP<5>
  BL76  UPI_CPU1_CPU0_P2P2_DP<4>  UPI2_RX_DN19  @S9S_MB_2U_LIB.S9S_MB_2U(SCH_1):UPI_CPU1_CPU0_P2P2_DP<4>
  BG74  UPI_CPU1_CPU0_P2P2_DP<3>  UPI2_RX_DN20  @S9S_MB_2U_LIB.S9S_MB_2U(SCH_1):UPI_CPU1_CPU0_P2P2_DP<3>
  BN74  UPI_CPU1_CPU0_P2P2_DP<2>  UPI2_RX_DN21  @S9S_MB_2U_LIB.S9S_MB_2U(SCH_1):UPI_CPU1_CPU0_P2P2_DP<2>
  G80  UPI_CPU1_CPU0_P2P2_DP<23>  UPI2_RX_DP0  @S9S_MB_2U_LIB.S9S_MB_2U(SCH_1):UPI_CPU1_CPU0_P2P2_DP<23>
  F81  UPI_CPU1_CPU0_P2P2_DP<22>  UPI2_RX_DN1  @S9S_MB_2U_LIB.S9S_MB_2U(SCH_1):UPI_CPU1_CPU0_P2P2_DP<22>
  H83  UPI_CPU1_CPU0_P2P2_DP<21>  UPI2_RX_DP2  @S9S_MB_2U_LIB.S9S_MB_2U(SCH_1):UPI_CPU1_CPU0_P2P2_DP<21>
  M79  UPI_CPU1_CPU0_P2P2_DP<20>  UPI2_RX_DP3  @S9S_MB_2U_LIB.S9S_MB_2U(SCH_1):UPI_CPU1_CPU0_P2P2_DP<20>
  BL74  UPI_CPU1_CPU0_P2P2_DP<1>  UPI2_RX_DP22  @S9S_MB_2U_LIB.S9S_MB_2U(SCH_1):UPI_CPU1_CPU0_P2P2_DP<1>
  L82  UPI_CPU1_CPU0_P2P2_DP<19>  UPI2_RX_DP4  @S9S_MB_2U_LIB.S9S_MB_2U(SCH_1):UPI_CPU1_CPU0_P2P2_DP<19>
  K81  UPI_CPU1_CPU0_P2P2_DP<18>  UPI2_RX_DP5  @S9S_MB_2U_LIB.S9S_MB_2U(SCH_1):UPI_CPU1_CPU0_P2P2_DP<18>
  AE80  UPI_CPU1_CPU0_P2P2_DP<17>  UPI2_RX_DP6  @S9S_MB_2U_LIB.S9S_MB_2U(SCH_1):UPI_CPU1_CPU0_P2P2_DP<17>
  AD81  UPI_CPU1_CPU0_P2P2_DP<16>  UPI2_RX_DN7  @S9S_MB_2U_LIB.S9S_MB_2U(SCH_1):UPI_CPU1_CPU0_P2P2_DP<16>
  AF79  UPI_CPU1_CPU0_P2P2_DP<15>  UPI2_RX_DN8  @S9S_MB_2U_LIB.S9S_MB_2U(SCH_1):UPI_CPU1_CPU0_P2P2_DP<15>
  AE82  UPI_CPU1_CPU0_P2P2_DP<14>  UPI2_RX_DN9  @S9S_MB_2U_LIB.S9S_MB_2U(SCH_1):UPI_CPU1_CPU0_P2P2_DP<14>
  AH81  UPI_CPU1_CPU0_P2P2_DP<13>  UPI2_RX_DP10  @S9S_MB_2U_LIB.S9S_MB_2U(SCH_1):UPI_CPU1_CPU0_P2P2_DP<13>
  AG82  UPI_CPU1_CPU0_P2P2_DP<12>  UPI2_RX_DN11  @S9S_MB_2U_LIB.S9S_MB_2U(SCH_1):UPI_CPU1_CPU0_P2P2_DP<12>
  BA72  UPI_CPU1_CPU0_P2P2_DP<11>  UPI2_RX_DN12  @S9S_MB_2U_LIB.S9S_MB_2U(SCH_1):UPI_CPU1_CPU0_P2P2_DP<11>
  AY73  UPI_CPU1_CPU0_P2P2_DP<10>  UPI2_RX_DP13  @S9S_MB_2U_LIB.S9S_MB_2U(SCH_1):UPI_CPU1_CPU0_P2P2_DP<10>
  BD73  UPI_CPU1_CPU0_P2P2_DP<0>  UPI2_RX_DN23  @S9S_MB_2U_LIB.S9S_MB_2U(SCH_1):UPI_CPU1_CPU0_P2P2_DP<0>
  AY75  UPI_CPU1_CPU0_P2P2_DN<9>  UPI2_RX_DN14  @S9S_MB_2U_LIB.S9S_MB_2U(SCH_1):UPI_CPU1_CPU0_P2P2_DN<9>
  BD75  UPI_CPU1_CPU0_P2P2_DN<8>  UPI2_RX_DP15  @S9S_MB_2U_LIB.S9S_MB_2U(SCH_1):UPI_CPU1_CPU0_P2P2_DN<8>
  AV75  UPI_CPU1_CPU0_P2P2_DN<7>  UPI2_RX_DP16  @S9S_MB_2U_LIB.S9S_MB_2U(SCH_1):UPI_CPU1_CPU0_P2P2_DN<7>
  BH75  UPI_CPU1_CPU0_P2P2_DN<6>  UPI2_RX_DN17  @S9S_MB_2U_LIB.S9S_MB_2U(SCH_1):UPI_CPU1_CPU0_P2P2_DN<6>
  BJ76  UPI_CPU1_CPU0_P2P2_DN<5>  UPI2_RX_DN18  @S9S_MB_2U_LIB.S9S_MB_2U(SCH_1):UPI_CPU1_CPU0_P2P2_DN<5>
  BN76  UPI_CPU1_CPU0_P2P2_DN<4>  UPI2_RX_DP19  @S9S_MB_2U_LIB.S9S_MB_2U(SCH_1):UPI_CPU1_CPU0_P2P2_DN<4>
  BJ74  UPI_CPU1_CPU0_P2P2_DN<3>  UPI2_RX_DP20  @S9S_MB_2U_LIB.S9S_MB_2U(SCH_1):UPI_CPU1_CPU0_P2P2_DN<3>
  BM75  UPI_CPU1_CPU0_P2P2_DN<2>  UPI2_RX_DP21  @S9S_MB_2U_LIB.S9S_MB_2U(SCH_1):UPI_CPU1_CPU0_P2P2_DN<2>
  E80  UPI_CPU1_CPU0_P2P2_DN<23>  UPI2_RX_DN0  @S9S_MB_2U_LIB.S9S_MB_2U(SCH_1):UPI_CPU1_CPU0_P2P2_DN<23>
  E82  UPI_CPU1_CPU0_P2P2_DN<22>  UPI2_RX_DP1  @S9S_MB_2U_LIB.S9S_MB_2U(SCH_1):UPI_CPU1_CPU0_P2P2_DN<22>
  G82  UPI_CPU1_CPU0_P2P2_DN<21>  UPI2_RX_DN2  @S9S_MB_2U_LIB.S9S_MB_2U(SCH_1):UPI_CPU1_CPU0_P2P2_DN<21>
  K79  UPI_CPU1_CPU0_P2P2_DN<20>  UPI2_RX_DN3  @S9S_MB_2U_LIB.S9S_MB_2U(SCH_1):UPI_CPU1_CPU0_P2P2_DN<20>
  BK73  UPI_CPU1_CPU0_P2P2_DN<1>  UPI2_RX_DN22  @S9S_MB_2U_LIB.S9S_MB_2U(SCH_1):UPI_CPU1_CPU0_P2P2_DN<1>
  J82  UPI_CPU1_CPU0_P2P2_DN<19>  UPI2_RX_DN4  @S9S_MB_2U_LIB.S9S_MB_2U(SCH_1):UPI_CPU1_CPU0_P2P2_DN<19>
  L80  UPI_CPU1_CPU0_P2P2_DN<18>  UPI2_RX_DN5  @S9S_MB_2U_LIB.S9S_MB_2U(SCH_1):UPI_CPU1_CPU0_P2P2_DN<18>
  AC80  UPI_CPU1_CPU0_P2P2_DN<17>  UPI2_RX_DN6  @S9S_MB_2U_LIB.S9S_MB_2U(SCH_1):UPI_CPU1_CPU0_P2P2_DN<17>
  AC82  UPI_CPU1_CPU0_P2P2_DN<16>  UPI2_RX_DP7  @S9S_MB_2U_LIB.S9S_MB_2U(SCH_1):UPI_CPU1_CPU0_P2P2_DN<16>
  AG80  UPI_CPU1_CPU0_P2P2_DN<15>  UPI2_RX_DP8  @S9S_MB_2U_LIB.S9S_MB_2U(SCH_1):UPI_CPU1_CPU0_P2P2_DN<15>
  AF83  UPI_CPU1_CPU0_P2P2_DN<14>  UPI2_RX_DP9  @S9S_MB_2U_LIB.S9S_MB_2U(SCH_1):UPI_CPU1_CPU0_P2P2_DN<14>
  AJ80  UPI_CPU1_CPU0_P2P2_DN<13>  UPI2_RX_DN10  @S9S_MB_2U_LIB.S9S_MB_2U(SCH_1):UPI_CPU1_CPU0_P2P2_DN<13>
  AJ82  UPI_CPU1_CPU0_P2P2_DN<12>  UPI2_RX_DP11  @S9S_MB_2U_LIB.S9S_MB_2U(SCH_1):UPI_CPU1_CPU0_P2P2_DN<12>
  BB73  UPI_CPU1_CPU0_P2P2_DN<11>  UPI2_RX_DP12  @S9S_MB_2U_LIB.S9S_MB_2U(SCH_1):UPI_CPU1_CPU0_P2P2_DN<11>
  AV73  UPI_CPU1_CPU0_P2P2_DN<10>  UPI2_RX_DN13  @S9S_MB_2U_LIB.S9S_MB_2U(SCH_1):UPI_CPU1_CPU0_P2P2_DN<10>
  BC74  UPI_CPU1_CPU0_P2P2_DN<0>  UPI2_RX_DP23  @S9S_MB_2U_LIB.S9S_MB_2U(SCH_1):UPI_CPU1_CPU0_P2P2_DN<0>
  AT81  UPI_CPU0_CPU1_P2P2_DP<9>  UPI2_TX_DP14  @S9S_MB_2U_LIB.S9S_MB_2U(SCH_1):UPI_CPU0_CPU1_P2P2_DP<9>
  AV83  UPI_CPU0_CPU1_P2P2_DP<8>  UPI2_TX_DP15  @S9S_MB_2U_LIB.S9S_MB_2U(SCH_1):UPI_CPU0_CPU1_P2P2_DP<8>
  AU82  UPI_CPU0_CPU1_P2P2_DP<7>  UPI2_TX_DP16  @S9S_MB_2U_LIB.S9S_MB_2U(SCH_1):UPI_CPU0_CPU1_P2P2_DP<7>
  BB81  UPI_CPU0_CPU1_P2P2_DP<6>  UPI2_TX_DP17  @S9S_MB_2U_LIB.S9S_MB_2U(SCH_1):UPI_CPU0_CPU1_P2P2_DP<6>
  BA82  UPI_CPU0_CPU1_P2P2_DP<5>  UPI2_TX_DP18  @S9S_MB_2U_LIB.S9S_MB_2U(SCH_1):UPI_CPU0_CPU1_P2P2_DP<5>
  BD83  UPI_CPU0_CPU1_P2P2_DP<4>  UPI2_TX_DP19  @S9S_MB_2U_LIB.S9S_MB_2U(SCH_1):UPI_CPU0_CPU1_P2P2_DP<4>
  BC80  UPI_CPU0_CPU1_P2P2_DP<3>  UPI2_TX_DP20  @S9S_MB_2U_LIB.S9S_MB_2U(SCH_1):UPI_CPU0_CPU1_P2P2_DP<3>
  BG82  UPI_CPU0_CPU1_P2P2_DP<2>  UPI2_TX_DP21  @S9S_MB_2U_LIB.S9S_MB_2U(SCH_1):UPI_CPU0_CPU1_P2P2_DP<2>
  D85  UPI_CPU0_CPU1_P2P2_DP<23>  UPI2_TX_DP0  @S9S_MB_2U_LIB.S9S_MB_2U(SCH_1):UPI_CPU0_CPU1_P2P2_DP<23>
  F85  UPI_CPU0_CPU1_P2P2_DP<22>  UPI2_TX_DP1  @S9S_MB_2U_LIB.S9S_MB_2U(SCH_1):UPI_CPU0_CPU1_P2P2_DP<22>
  E88  UPI_CPU0_CPU1_P2P2_DP<21>  UPI2_TX_DP2  @S9S_MB_2U_LIB.S9S_MB_2U(SCH_1):UPI_CPU0_CPU1_P2P2_DP<21>
  H87  UPI_CPU0_CPU1_P2P2_DP<20>  UPI2_TX_DP3  @S9S_MB_2U_LIB.S9S_MB_2U(SCH_1):UPI_CPU0_CPU1_P2P2_DP<20>
  BE80  UPI_CPU0_CPU1_P2P2_DP<1>  UPI2_TX_DP22  @S9S_MB_2U_LIB.S9S_MB_2U(SCH_1):UPI_CPU0_CPU1_P2P2_DP<1>
  G86  UPI_CPU0_CPU1_P2P2_DP<19>  UPI2_TX_DP4  @S9S_MB_2U_LIB.S9S_MB_2U(SCH_1):UPI_CPU0_CPU1_P2P2_DP<19>
  T81  UPI_CPU0_CPU1_P2P2_DP<18>  UPI2_TX_DP5  @S9S_MB_2U_LIB.S9S_MB_2U(SCH_1):UPI_CPU0_CPU1_P2P2_DP<18>
  P83  UPI_CPU0_CPU1_P2P2_DP<17>  UPI2_TX_DP6  @S9S_MB_2U_LIB.S9S_MB_2U(SCH_1):UPI_CPU0_CPU1_P2P2_DP<17>
  V81  UPI_CPU0_CPU1_P2P2_DP<16>  UPI2_TX_DP7  @S9S_MB_2U_LIB.S9S_MB_2U(SCH_1):UPI_CPU0_CPU1_P2P2_DP<16>
  Y83  UPI_CPU0_CPU1_P2P2_DP<15>  UPI2_TX_DP8  @S9S_MB_2U_LIB.S9S_MB_2U(SCH_1):UPI_CPU0_CPU1_P2P2_DP<15>
  W82  UPI_CPU0_CPU1_P2P2_DP<14>  UPI2_TX_DP9  @S9S_MB_2U_LIB.S9S_MB_2U(SCH_1):UPI_CPU0_CPU1_P2P2_DP<14>
  BA78  UPI_CPU0_CPU1_P2P2_DP<13>  UPI2_TX_DP10  @S9S_MB_2U_LIB.S9S_MB_2U(SCH_1):UPI_CPU0_CPU1_P2P2_DP<13>
  AV79  UPI_CPU0_CPU1_P2P2_DP<12>  UPI2_TX_DP11  @S9S_MB_2U_LIB.S9S_MB_2U(SCH_1):UPI_CPU0_CPU1_P2P2_DP<12>
  AP81  UPI_CPU0_CPU1_P2P2_DP<11>  UPI2_TX_DP12  @S9S_MB_2U_LIB.S9S_MB_2U(SCH_1):UPI_CPU0_CPU1_P2P2_DP<11>
  AM83  UPI_CPU0_CPU1_P2P2_DP<10>  UPI2_TX_DP13  @S9S_MB_2U_LIB.S9S_MB_2U(SCH_1):UPI_CPU0_CPU1_P2P2_DP<10>
  BN72  UPI_CPU0_CPU1_P2P2_DP<0>  UPI2_TX_DP23  @S9S_MB_2U_LIB.S9S_MB_2U(SCH_1):UPI_CPU0_CPU1_P2P2_DP<0>
  AR80  UPI_CPU0_CPU1_P2P2_DN<9>  UPI2_TX_DN14  @S9S_MB_2U_LIB.S9S_MB_2U(SCH_1):UPI_CPU0_CPU1_P2P2_DN<9>
  AT83  UPI_CPU0_CPU1_P2P2_DN<8>  UPI2_TX_DN15  @S9S_MB_2U_LIB.S9S_MB_2U(SCH_1):UPI_CPU0_CPU1_P2P2_DN<8>
  AV81  UPI_CPU0_CPU1_P2P2_DN<7>  UPI2_TX_DN16  @S9S_MB_2U_LIB.S9S_MB_2U(SCH_1):UPI_CPU0_CPU1_P2P2_DN<7>
  BA80  UPI_CPU0_CPU1_P2P2_DN<6>  UPI2_TX_DN17  @S9S_MB_2U_LIB.S9S_MB_2U(SCH_1):UPI_CPU0_CPU1_P2P2_DN<6>
  BC82  UPI_CPU0_CPU1_P2P2_DN<5>  UPI2_TX_DN18  @S9S_MB_2U_LIB.S9S_MB_2U(SCH_1):UPI_CPU0_CPU1_P2P2_DN<5>
  BE82  UPI_CPU0_CPU1_P2P2_DN<4>  UPI2_TX_DN19  @S9S_MB_2U_LIB.S9S_MB_2U(SCH_1):UPI_CPU0_CPU1_P2P2_DN<4>
  BD79  UPI_CPU0_CPU1_P2P2_DN<3>  UPI2_TX_DN20  @S9S_MB_2U_LIB.S9S_MB_2U(SCH_1):UPI_CPU0_CPU1_P2P2_DN<3>
  BF81  UPI_CPU0_CPU1_P2P2_DN<2>  UPI2_TX_DN21  @S9S_MB_2U_LIB.S9S_MB_2U(SCH_1):UPI_CPU0_CPU1_P2P2_DN<2>
  B85  UPI_CPU0_CPU1_P2P2_DN<23>  UPI2_TX_DN0  @S9S_MB_2U_LIB.S9S_MB_2U(SCH_1):UPI_CPU0_CPU1_P2P2_DN<23>
  E84  UPI_CPU0_CPU1_P2P2_DN<22>  UPI2_TX_DN1  @S9S_MB_2U_LIB.S9S_MB_2U(SCH_1):UPI_CPU0_CPU1_P2P2_DN<22>
  D87  UPI_CPU0_CPU1_P2P2_DN<21>  UPI2_TX_DN2  @S9S_MB_2U_LIB.S9S_MB_2U(SCH_1):UPI_CPU0_CPU1_P2P2_DN<21>
  F87  UPI_CPU0_CPU1_P2P2_DN<20>  UPI2_TX_DN3  @S9S_MB_2U_LIB.S9S_MB_2U(SCH_1):UPI_CPU0_CPU1_P2P2_DN<20>
  BG80  UPI_CPU0_CPU1_P2P2_DN<1>  UPI2_TX_DN22  @S9S_MB_2U_LIB.S9S_MB_2U(SCH_1):UPI_CPU0_CPU1_P2P2_DN<1>
  H85  UPI_CPU0_CPU1_P2P2_DN<19>  UPI2_TX_DN4  @S9S_MB_2U_LIB.S9S_MB_2U(SCH_1):UPI_CPU0_CPU1_P2P2_DN<19>
  P81  UPI_CPU0_CPU1_P2P2_DN<18>  UPI2_TX_DN5  @S9S_MB_2U_LIB.S9S_MB_2U(SCH_1):UPI_CPU0_CPU1_P2P2_DN<18>
  R82  UPI_CPU0_CPU1_P2P2_DN<17>  UPI2_TX_DN6  @S9S_MB_2U_LIB.S9S_MB_2U(SCH_1):UPI_CPU0_CPU1_P2P2_DN<17>
  U80  UPI_CPU0_CPU1_P2P2_DN<16>  UPI2_TX_DN7  @S9S_MB_2U_LIB.S9S_MB_2U(SCH_1):UPI_CPU0_CPU1_P2P2_DN<16>
  V83  UPI_CPU0_CPU1_P2P2_DN<15>  UPI2_TX_DN8  @S9S_MB_2U_LIB.S9S_MB_2U(SCH_1):UPI_CPU0_CPU1_P2P2_DN<15>
  Y81  UPI_CPU0_CPU1_P2P2_DN<14>  UPI2_TX_DN9  @S9S_MB_2U_LIB.S9S_MB_2U(SCH_1):UPI_CPU0_CPU1_P2P2_DN<14>
  AW78  UPI_CPU0_CPU1_P2P2_DN<13>  UPI2_TX_DN10  @S9S_MB_2U_LIB.S9S_MB_2U(SCH_1):UPI_CPU0_CPU1_P2P2_DN<13>
  AU78  UPI_CPU0_CPU1_P2P2_DN<12>  UPI2_TX_DN11  @S9S_MB_2U_LIB.S9S_MB_2U(SCH_1):UPI_CPU0_CPU1_P2P2_DN<12>
  AM81  UPI_CPU0_CPU1_P2P2_DN<11>  UPI2_TX_DN12  @S9S_MB_2U_LIB.S9S_MB_2U(SCH_1):UPI_CPU0_CPU1_P2P2_DN<11>
  AN82  UPI_CPU0_CPU1_P2P2_DN<10>  UPI2_TX_DN13  @S9S_MB_2U_LIB.S9S_MB_2U(SCH_1):UPI_CPU0_CPU1_P2P2_DN<10>
  BM71  UPI_CPU0_CPU1_P2P2_DN<0>  UPI2_TX_DN23  @S9S_MB_2U_LIB.S9S_MB_2U(SCH_1):UPI_CPU0_CPU1_P2P2_DN<0>

SOCKET4677_AZIFS054P001C01  I102  U2     [SOCKET4677_AZIFS054P001C01-SOCA]
  DK2  UPI_CPU1_CPU0_P0P1_DP<9>  UPI1_RX_DP9  @S9S_MB_2U_LIB.S9S_MB_2U(SCH_1):UPI_CPU1_CPU0_P0P1_DP<9>
  DM2  UPI_CPU1_CPU0_P0P1_DP<8>  UPI1_RX_DP8  @S9S_MB_2U_LIB.S9S_MB_2U(SCH_1):UPI_CPU1_CPU0_P0P1_DP<8>
  DP2  UPI_CPU1_CPU0_P0P1_DP<7>  UPI1_RX_DP7  @S9S_MB_2U_LIB.S9S_MB_2U(SCH_1):UPI_CPU1_CPU0_P0P1_DP<7>
  DR3  UPI_CPU1_CPU0_P0P1_DP<6>  UPI1_RX_DP6  @S9S_MB_2U_LIB.S9S_MB_2U(SCH_1):UPI_CPU1_CPU0_P0P1_DP<6>
  DV2  UPI_CPU1_CPU0_P0P1_DP<5>  UPI1_RX_DP5  @S9S_MB_2U_LIB.S9S_MB_2U(SCH_1):UPI_CPU1_CPU0_P0P1_DP<5>
  DW3  UPI_CPU1_CPU0_P0P1_DP<4>  UPI1_RX_DP4  @S9S_MB_2U_LIB.S9S_MB_2U(SCH_1):UPI_CPU1_CPU0_P0P1_DP<4>
  EB2  UPI_CPU1_CPU0_P0P1_DP<3>  UPI1_RX_DP3  @S9S_MB_2U_LIB.S9S_MB_2U(SCH_1):UPI_CPU1_CPU0_P0P1_DP<3>
  ED2  UPI_CPU1_CPU0_P0P1_DP<2>  UPI1_RX_DN2  @S9S_MB_2U_LIB.S9S_MB_2U(SCH_1):UPI_CPU1_CPU0_P0P1_DP<2>
  CB2  UPI_CPU1_CPU0_P0P1_DP<23>  UPI1_RX_DN23  @S9S_MB_2U_LIB.S9S_MB_2U(SCH_1):UPI_CPU1_CPU0_P0P1_DP<23>
  CD2  UPI_CPU1_CPU0_P0P1_DP<22>  UPI1_RX_DN22  @S9S_MB_2U_LIB.S9S_MB_2U(SCH_1):UPI_CPU1_CPU0_P0P1_DP<22>
  CE1  UPI_CPU1_CPU0_P0P1_DP<21>  UPI1_RX_DP21  @S9S_MB_2U_LIB.S9S_MB_2U(SCH_1):UPI_CPU1_CPU0_P0P1_DP<21>
  CH2  UPI_CPU1_CPU0_P0P1_DP<20>  UPI1_RX_DN20  @S9S_MB_2U_LIB.S9S_MB_2U(SCH_1):UPI_CPU1_CPU0_P0P1_DP<20>
  EG3  UPI_CPU1_CPU0_P0P1_DP<1>  UPI1_RX_DP1  @S9S_MB_2U_LIB.S9S_MB_2U(SCH_1):UPI_CPU1_CPU0_P0P1_DP<1>
  CJ1  UPI_CPU1_CPU0_P0P1_DP<19>  UPI1_RX_DN19  @S9S_MB_2U_LIB.S9S_MB_2U(SCH_1):UPI_CPU1_CPU0_P0P1_DP<19>
  CM2  UPI_CPU1_CPU0_P0P1_DP<18>  UPI1_RX_DP18  @S9S_MB_2U_LIB.S9S_MB_2U(SCH_1):UPI_CPU1_CPU0_P0P1_DP<18>
  CN1  UPI_CPU1_CPU0_P0P1_DP<17>  UPI1_RX_DN17  @S9S_MB_2U_LIB.S9S_MB_2U(SCH_1):UPI_CPU1_CPU0_P0P1_DP<17>
  CT2  UPI_CPU1_CPU0_P0P1_DP<16>  UPI1_RX_DP16  @S9S_MB_2U_LIB.S9S_MB_2U(SCH_1):UPI_CPU1_CPU0_P0P1_DP<16>
  CU1  UPI_CPU1_CPU0_P0P1_DP<15>  UPI1_RX_DP15  @S9S_MB_2U_LIB.S9S_MB_2U(SCH_1):UPI_CPU1_CPU0_P0P1_DP<15>
  CW3  UPI_CPU1_CPU0_P0P1_DP<14>  UPI1_RX_DP14  @S9S_MB_2U_LIB.S9S_MB_2U(SCH_1):UPI_CPU1_CPU0_P0P1_DP<14>
  DA1  UPI_CPU1_CPU0_P0P1_DP<13>  UPI1_RX_DP13  @S9S_MB_2U_LIB.S9S_MB_2U(SCH_1):UPI_CPU1_CPU0_P0P1_DP<13>
  DD2  UPI_CPU1_CPU0_P0P1_DP<12>  UPI1_RX_DN12  @S9S_MB_2U_LIB.S9S_MB_2U(SCH_1):UPI_CPU1_CPU0_P0P1_DP<12>
  DF2  UPI_CPU1_CPU0_P0P1_DP<11>  UPI1_RX_DP11  @S9S_MB_2U_LIB.S9S_MB_2U(SCH_1):UPI_CPU1_CPU0_P0P1_DP<11>
  DH2  UPI_CPU1_CPU0_P0P1_DP<10>  UPI1_RX_DP10  @S9S_MB_2U_LIB.S9S_MB_2U(SCH_1):UPI_CPU1_CPU0_P0P1_DP<10>
  EJ3  UPI_CPU1_CPU0_P0P1_DP<0>  UPI1_RX_DP0  @S9S_MB_2U_LIB.S9S_MB_2U(SCH_1):UPI_CPU1_CPU0_P0P1_DP<0>
  DJ1  UPI_CPU1_CPU0_P0P1_DN<9>  UPI1_RX_DN9  @S9S_MB_2U_LIB.S9S_MB_2U(SCH_1):UPI_CPU1_CPU0_P0P1_DN<9>
  DL3  UPI_CPU1_CPU0_P0P1_DN<8>  UPI1_RX_DN8  @S9S_MB_2U_LIB.S9S_MB_2U(SCH_1):UPI_CPU1_CPU0_P0P1_DN<8>
  DN1  UPI_CPU1_CPU0_P0P1_DN<7>  UPI1_RX_DN7  @S9S_MB_2U_LIB.S9S_MB_2U(SCH_1):UPI_CPU1_CPU0_P0P1_DN<7>
  DT2  UPI_CPU1_CPU0_P0P1_DN<6>  UPI1_RX_DN6  @S9S_MB_2U_LIB.S9S_MB_2U(SCH_1):UPI_CPU1_CPU0_P0P1_DN<6>
  DU1  UPI_CPU1_CPU0_P0P1_DN<5>  UPI1_RX_DN5  @S9S_MB_2U_LIB.S9S_MB_2U(SCH_1):UPI_CPU1_CPU0_P0P1_DN<5>
  DY2  UPI_CPU1_CPU0_P0P1_DN<4>  UPI1_RX_DN4  @S9S_MB_2U_LIB.S9S_MB_2U(SCH_1):UPI_CPU1_CPU0_P0P1_DN<4>
  EA1  UPI_CPU1_CPU0_P0P1_DN<3>  UPI1_RX_DN3  @S9S_MB_2U_LIB.S9S_MB_2U(SCH_1):UPI_CPU1_CPU0_P0P1_DN<3>
  EC3  UPI_CPU1_CPU0_P0P1_DN<2>  UPI1_RX_DP2  @S9S_MB_2U_LIB.S9S_MB_2U(SCH_1):UPI_CPU1_CPU0_P0P1_DN<2>
  BY2  UPI_CPU1_CPU0_P0P1_DN<23>  UPI1_RX_DP23  @S9S_MB_2U_LIB.S9S_MB_2U(SCH_1):UPI_CPU1_CPU0_P0P1_DN<23>
  CC3  UPI_CPU1_CPU0_P0P1_DN<22>  UPI1_RX_DP22  @S9S_MB_2U_LIB.S9S_MB_2U(SCH_1):UPI_CPU1_CPU0_P0P1_DN<22>
  CF2  UPI_CPU1_CPU0_P0P1_DN<21>  UPI1_RX_DN21  @S9S_MB_2U_LIB.S9S_MB_2U(SCH_1):UPI_CPU1_CPU0_P0P1_DN<21>
  CG3  UPI_CPU1_CPU0_P0P1_DN<20>  UPI1_RX_DP20  @S9S_MB_2U_LIB.S9S_MB_2U(SCH_1):UPI_CPU1_CPU0_P0P1_DN<20>
  EE3  UPI_CPU1_CPU0_P0P1_DN<1>  UPI1_RX_DN1  @S9S_MB_2U_LIB.S9S_MB_2U(SCH_1):UPI_CPU1_CPU0_P0P1_DN<1>
  CK2  UPI_CPU1_CPU0_P0P1_DN<19>  UPI1_RX_DP19  @S9S_MB_2U_LIB.S9S_MB_2U(SCH_1):UPI_CPU1_CPU0_P0P1_DN<19>
  CL3  UPI_CPU1_CPU0_P0P1_DN<18>  UPI1_RX_DN18  @S9S_MB_2U_LIB.S9S_MB_2U(SCH_1):UPI_CPU1_CPU0_P0P1_DN<18>
  CP2  UPI_CPU1_CPU0_P0P1_DN<17>  UPI1_RX_DP17  @S9S_MB_2U_LIB.S9S_MB_2U(SCH_1):UPI_CPU1_CPU0_P0P1_DN<17>
  CR3  UPI_CPU1_CPU0_P0P1_DN<16>  UPI1_RX_DN16  @S9S_MB_2U_LIB.S9S_MB_2U(SCH_1):UPI_CPU1_CPU0_P0P1_DN<16>
  CV2  UPI_CPU1_CPU0_P0P1_DN<15>  UPI1_RX_DN15  @S9S_MB_2U_LIB.S9S_MB_2U(SCH_1):UPI_CPU1_CPU0_P0P1_DN<15>
  CY2  UPI_CPU1_CPU0_P0P1_DN<14>  UPI1_RX_DN14  @S9S_MB_2U_LIB.S9S_MB_2U(SCH_1):UPI_CPU1_CPU0_P0P1_DN<14>
  DB2  UPI_CPU1_CPU0_P0P1_DN<13>  UPI1_RX_DN13  @S9S_MB_2U_LIB.S9S_MB_2U(SCH_1):UPI_CPU1_CPU0_P0P1_DN<13>
  DC3  UPI_CPU1_CPU0_P0P1_DN<12>  UPI1_RX_DP12  @S9S_MB_2U_LIB.S9S_MB_2U(SCH_1):UPI_CPU1_CPU0_P0P1_DN<12>
  DE1  UPI_CPU1_CPU0_P0P1_DN<11>  UPI1_RX_DN11  @S9S_MB_2U_LIB.S9S_MB_2U(SCH_1):UPI_CPU1_CPU0_P0P1_DN<11>
  DG3  UPI_CPU1_CPU0_P0P1_DN<10>  UPI1_RX_DN10  @S9S_MB_2U_LIB.S9S_MB_2U(SCH_1):UPI_CPU1_CPU0_P0P1_DN<10>
  EH2  UPI_CPU1_CPU0_P0P1_DN<0>  UPI1_RX_DN0  @S9S_MB_2U_LIB.S9S_MB_2U(SCH_1):UPI_CPU1_CPU0_P0P1_DN<0>
  DG7  UPI_CPU0_CPU1_P1P0_DP<9>  UPI1_TX_DP9  @S9S_MB_2U_LIB.S9S_MB_2U(SCH_1):UPI_CPU0_CPU1_P1P0_DP<9>
  DJ5  UPI_CPU0_CPU1_P1P0_DP<8>  UPI1_TX_DP8  @S9S_MB_2U_LIB.S9S_MB_2U(SCH_1):UPI_CPU0_CPU1_P1P0_DP<8>
  DM6  UPI_CPU0_CPU1_P1P0_DP<7>  UPI1_TX_DP7  @S9S_MB_2U_LIB.S9S_MB_2U(SCH_1):UPI_CPU0_CPU1_P1P0_DP<7>
  DN5  UPI_CPU0_CPU1_P1P0_DP<6>  UPI1_TX_DP6  @S9S_MB_2U_LIB.S9S_MB_2U(SCH_1):UPI_CPU0_CPU1_P1P0_DP<6>
  DT6  UPI_CPU0_CPU1_P1P0_DP<5>  UPI1_TX_DN5  @S9S_MB_2U_LIB.S9S_MB_2U(SCH_1):UPI_CPU0_CPU1_P1P0_DP<5>
  DU5  UPI_CPU0_CPU1_P1P0_DP<4>  UPI1_TX_DP4  @S9S_MB_2U_LIB.S9S_MB_2U(SCH_1):UPI_CPU0_CPU1_P1P0_DP<4>
  DY6  UPI_CPU0_CPU1_P1P0_DP<3>  UPI1_TX_DN3  @S9S_MB_2U_LIB.S9S_MB_2U(SCH_1):UPI_CPU0_CPU1_P1P0_DP<3>
  EA5  UPI_CPU0_CPU1_P1P0_DP<2>  UPI1_TX_DP2  @S9S_MB_2U_LIB.S9S_MB_2U(SCH_1):UPI_CPU0_CPU1_P1P0_DP<2>
  BY6  UPI_CPU0_CPU1_P1P0_DP<23>  UPI1_TX_DN23  @S9S_MB_2U_LIB.S9S_MB_2U(SCH_1):UPI_CPU0_CPU1_P1P0_DP<23>
  CB6  UPI_CPU0_CPU1_P1P0_DP<22>  UPI1_TX_DP22  @S9S_MB_2U_LIB.S9S_MB_2U(SCH_1):UPI_CPU0_CPU1_P1P0_DP<22>
  CD6  UPI_CPU0_CPU1_P1P0_DP<21>  UPI1_TX_DN21  @S9S_MB_2U_LIB.S9S_MB_2U(SCH_1):UPI_CPU0_CPU1_P1P0_DP<21>
  CE5  UPI_CPU0_CPU1_P1P0_DP<20>  UPI1_TX_DN20  @S9S_MB_2U_LIB.S9S_MB_2U(SCH_1):UPI_CPU0_CPU1_P1P0_DP<20>
  ED6  UPI_CPU0_CPU1_P1P0_DP<1>  UPI1_TX_DP1  @S9S_MB_2U_LIB.S9S_MB_2U(SCH_1):UPI_CPU0_CPU1_P1P0_DP<1>
  CH6  UPI_CPU0_CPU1_P1P0_DP<19>  UPI1_TX_DN19  @S9S_MB_2U_LIB.S9S_MB_2U(SCH_1):UPI_CPU0_CPU1_P1P0_DP<19>
  CJ5  UPI_CPU0_CPU1_P1P0_DP<18>  UPI1_TX_DN18  @S9S_MB_2U_LIB.S9S_MB_2U(SCH_1):UPI_CPU0_CPU1_P1P0_DP<18>
  CM6  UPI_CPU0_CPU1_P1P0_DP<17>  UPI1_TX_DN17  @S9S_MB_2U_LIB.S9S_MB_2U(SCH_1):UPI_CPU0_CPU1_P1P0_DP<17>
  CN5  UPI_CPU0_CPU1_P1P0_DP<16>  UPI1_TX_DN16  @S9S_MB_2U_LIB.S9S_MB_2U(SCH_1):UPI_CPU0_CPU1_P1P0_DP<16>
  CT6  UPI_CPU0_CPU1_P1P0_DP<15>  UPI1_TX_DN15  @S9S_MB_2U_LIB.S9S_MB_2U(SCH_1):UPI_CPU0_CPU1_P1P0_DP<15>
  CU5  UPI_CPU0_CPU1_P1P0_DP<14>  UPI1_TX_DN14  @S9S_MB_2U_LIB.S9S_MB_2U(SCH_1):UPI_CPU0_CPU1_P1P0_DP<14>
  CY6  UPI_CPU0_CPU1_P1P0_DP<13>  UPI1_TX_DN13  @S9S_MB_2U_LIB.S9S_MB_2U(SCH_1):UPI_CPU0_CPU1_P1P0_DP<13>
  DA5  UPI_CPU0_CPU1_P1P0_DP<12>  UPI1_TX_DN12  @S9S_MB_2U_LIB.S9S_MB_2U(SCH_1):UPI_CPU0_CPU1_P1P0_DP<12>
  DD6  UPI_CPU0_CPU1_P1P0_DP<11>  UPI1_TX_DN11  @S9S_MB_2U_LIB.S9S_MB_2U(SCH_1):UPI_CPU0_CPU1_P1P0_DP<11>
  DE5  UPI_CPU0_CPU1_P1P0_DP<10>  UPI1_TX_DN10  @S9S_MB_2U_LIB.S9S_MB_2U(SCH_1):UPI_CPU0_CPU1_P1P0_DP<10>
  EE5  UPI_CPU0_CPU1_P1P0_DP<0>  UPI1_TX_DP0  @S9S_MB_2U_LIB.S9S_MB_2U(SCH_1):UPI_CPU0_CPU1_P1P0_DP<0>
  DH6  UPI_CPU0_CPU1_P1P0_DN<9>  UPI1_TX_DN9  @S9S_MB_2U_LIB.S9S_MB_2U(SCH_1):UPI_CPU0_CPU1_P1P0_DN<9>
  DK6  UPI_CPU0_CPU1_P1P0_DN<8>  UPI1_TX_DN8  @S9S_MB_2U_LIB.S9S_MB_2U(SCH_1):UPI_CPU0_CPU1_P1P0_DN<8>
  DL7  UPI_CPU0_CPU1_P1P0_DN<7>  UPI1_TX_DN7  @S9S_MB_2U_LIB.S9S_MB_2U(SCH_1):UPI_CPU0_CPU1_P1P0_DN<7>
  DP6  UPI_CPU0_CPU1_P1P0_DN<6>  UPI1_TX_DN6  @S9S_MB_2U_LIB.S9S_MB_2U(SCH_1):UPI_CPU0_CPU1_P1P0_DN<6>
  DR7  UPI_CPU0_CPU1_P1P0_DN<5>  UPI1_TX_DP5  @S9S_MB_2U_LIB.S9S_MB_2U(SCH_1):UPI_CPU0_CPU1_P1P0_DN<5>
  DV6  UPI_CPU0_CPU1_P1P0_DN<4>  UPI1_TX_DN4  @S9S_MB_2U_LIB.S9S_MB_2U(SCH_1):UPI_CPU0_CPU1_P1P0_DN<4>
  DW7  UPI_CPU0_CPU1_P1P0_DN<3>  UPI1_TX_DP3  @S9S_MB_2U_LIB.S9S_MB_2U(SCH_1):UPI_CPU0_CPU1_P1P0_DN<3>
  EB6  UPI_CPU0_CPU1_P1P0_DN<2>  UPI1_TX_DN2  @S9S_MB_2U_LIB.S9S_MB_2U(SCH_1):UPI_CPU0_CPU1_P1P0_DN<2>
  BW7  UPI_CPU0_CPU1_P1P0_DN<23>  UPI1_TX_DP23  @S9S_MB_2U_LIB.S9S_MB_2U(SCH_1):UPI_CPU0_CPU1_P1P0_DN<23>
  CA5  UPI_CPU0_CPU1_P1P0_DN<22>  UPI1_TX_DN22  @S9S_MB_2U_LIB.S9S_MB_2U(SCH_1):UPI_CPU0_CPU1_P1P0_DN<22>
  CC7  UPI_CPU0_CPU1_P1P0_DN<21>  UPI1_TX_DP21  @S9S_MB_2U_LIB.S9S_MB_2U(SCH_1):UPI_CPU0_CPU1_P1P0_DN<21>
  CF6  UPI_CPU0_CPU1_P1P0_DN<20>  UPI1_TX_DP20  @S9S_MB_2U_LIB.S9S_MB_2U(SCH_1):UPI_CPU0_CPU1_P1P0_DN<20>
  EC7  UPI_CPU0_CPU1_P1P0_DN<1>  UPI1_TX_DN1  @S9S_MB_2U_LIB.S9S_MB_2U(SCH_1):UPI_CPU0_CPU1_P1P0_DN<1>
  CG7  UPI_CPU0_CPU1_P1P0_DN<19>  UPI1_TX_DP19  @S9S_MB_2U_LIB.S9S_MB_2U(SCH_1):UPI_CPU0_CPU1_P1P0_DN<19>
  CK6  UPI_CPU0_CPU1_P1P0_DN<18>  UPI1_TX_DP18  @S9S_MB_2U_LIB.S9S_MB_2U(SCH_1):UPI_CPU0_CPU1_P1P0_DN<18>
  CL7  UPI_CPU0_CPU1_P1P0_DN<17>  UPI1_TX_DP17  @S9S_MB_2U_LIB.S9S_MB_2U(SCH_1):UPI_CPU0_CPU1_P1P0_DN<17>
  CP6  UPI_CPU0_CPU1_P1P0_DN<16>  UPI1_TX_DP16  @S9S_MB_2U_LIB.S9S_MB_2U(SCH_1):UPI_CPU0_CPU1_P1P0_DN<16>
  CR7  UPI_CPU0_CPU1_P1P0_DN<15>  UPI1_TX_DP15  @S9S_MB_2U_LIB.S9S_MB_2U(SCH_1):UPI_CPU0_CPU1_P1P0_DN<15>
  CV6  UPI_CPU0_CPU1_P1P0_DN<14>  UPI1_TX_DP14  @S9S_MB_2U_LIB.S9S_MB_2U(SCH_1):UPI_CPU0_CPU1_P1P0_DN<14>
  CW7  UPI_CPU0_CPU1_P1P0_DN<13>  UPI1_TX_DP13  @S9S_MB_2U_LIB.S9S_MB_2U(SCH_1):UPI_CPU0_CPU1_P1P0_DN<13>
  DB6  UPI_CPU0_CPU1_P1P0_DN<12>  UPI1_TX_DP12  @S9S_MB_2U_LIB.S9S_MB_2U(SCH_1):UPI_CPU0_CPU1_P1P0_DN<12>
  DC7  UPI_CPU0_CPU1_P1P0_DN<11>  UPI1_TX_DP11  @S9S_MB_2U_LIB.S9S_MB_2U(SCH_1):UPI_CPU0_CPU1_P1P0_DN<11>
  DF6  UPI_CPU0_CPU1_P1P0_DN<10>  UPI1_TX_DP10  @S9S_MB_2U_LIB.S9S_MB_2U(SCH_1):UPI_CPU0_CPU1_P1P0_DN<10>
  EF6  UPI_CPU0_CPU1_P1P0_DN<0>  UPI1_TX_DN0  @S9S_MB_2U_LIB.S9S_MB_2U(SCH_1):UPI_CPU0_CPU1_P1P0_DN<0>

SOCKET4677_AZIFS054P001C01  I70  U2     [SOCKET4677_AZIFS054P001C01-SOCA]
  AJ5  UPI_CPU1_CPU0_P1P0_DP<9>  UPI0_RX_DP9  @S9S_MB_2U_LIB.S9S_MB_2U(SCH_1):UPI_CPU1_CPU0_P1P0_DP<9>
  AG7  UPI_CPU1_CPU0_P1P0_DP<8>  UPI0_RX_DP8  @S9S_MB_2U_LIB.S9S_MB_2U(SCH_1):UPI_CPU1_CPU0_P1P0_DP<8>
  AD6  UPI_CPU1_CPU0_P1P0_DP<7>  UPI0_RX_DP7  @S9S_MB_2U_LIB.S9S_MB_2U(SCH_1):UPI_CPU1_CPU0_P1P0_DP<7>
  AC7  UPI_CPU1_CPU0_P1P0_DP<6>  UPI0_RX_DP6  @S9S_MB_2U_LIB.S9S_MB_2U(SCH_1):UPI_CPU1_CPU0_P1P0_DP<6>
  AA5  UPI_CPU1_CPU0_P1P0_DP<5>  UPI0_RX_DN5  @S9S_MB_2U_LIB.S9S_MB_2U(SCH_1):UPI_CPU1_CPU0_P1P0_DP<5>
   W7  UPI_CPU1_CPU0_P1P0_DP<4>  UPI0_RX_DP4  @S9S_MB_2U_LIB.S9S_MB_2U(SCH_1):UPI_CPU1_CPU0_P1P0_DP<4>
   U5  UPI_CPU1_CPU0_P1P0_DP<3>  UPI0_RX_DN3  @S9S_MB_2U_LIB.S9S_MB_2U(SCH_1):UPI_CPU1_CPU0_P1P0_DP<3>
   R7  UPI_CPU1_CPU0_P1P0_DP<2>  UPI0_RX_DP2  @S9S_MB_2U_LIB.S9S_MB_2U(SCH_1):UPI_CPU1_CPU0_P1P0_DP<2>
  BU5  UPI_CPU1_CPU0_P1P0_DP<23>  UPI0_RX_DN23  @S9S_MB_2U_LIB.S9S_MB_2U(SCH_1):UPI_CPU1_CPU0_P1P0_DP<23>
  BP6  UPI_CPU1_CPU0_P1P0_DP<22>  UPI0_RX_DP22  @S9S_MB_2U_LIB.S9S_MB_2U(SCH_1):UPI_CPU1_CPU0_P1P0_DP<22>
  BN5  UPI_CPU1_CPU0_P1P0_DP<21>  UPI0_RX_DN21  @S9S_MB_2U_LIB.S9S_MB_2U(SCH_1):UPI_CPU1_CPU0_P1P0_DP<21>
  BK6  UPI_CPU1_CPU0_P1P0_DP<20>  UPI0_RX_DN20  @S9S_MB_2U_LIB.S9S_MB_2U(SCH_1):UPI_CPU1_CPU0_P1P0_DP<20>
   M6  UPI_CPU1_CPU0_P1P0_DP<1>  UPI0_RX_DP1  @S9S_MB_2U_LIB.S9S_MB_2U(SCH_1):UPI_CPU1_CPU0_P1P0_DP<1>
  BJ5  UPI_CPU1_CPU0_P1P0_DP<19>  UPI0_RX_DN19  @S9S_MB_2U_LIB.S9S_MB_2U(SCH_1):UPI_CPU1_CPU0_P1P0_DP<19>
  BF6  UPI_CPU1_CPU0_P1P0_DP<18>  UPI0_RX_DN18  @S9S_MB_2U_LIB.S9S_MB_2U(SCH_1):UPI_CPU1_CPU0_P1P0_DP<18>
  BE5  UPI_CPU1_CPU0_P1P0_DP<17>  UPI0_RX_DN17  @S9S_MB_2U_LIB.S9S_MB_2U(SCH_1):UPI_CPU1_CPU0_P1P0_DP<17>
  BB6  UPI_CPU1_CPU0_P1P0_DP<16>  UPI0_RX_DN16  @S9S_MB_2U_LIB.S9S_MB_2U(SCH_1):UPI_CPU1_CPU0_P1P0_DP<16>
  BA5  UPI_CPU1_CPU0_P1P0_DP<15>  UPI0_RX_DN15  @S9S_MB_2U_LIB.S9S_MB_2U(SCH_1):UPI_CPU1_CPU0_P1P0_DP<15>
  AV6  UPI_CPU1_CPU0_P1P0_DP<14>  UPI0_RX_DN14  @S9S_MB_2U_LIB.S9S_MB_2U(SCH_1):UPI_CPU1_CPU0_P1P0_DP<14>
  AU5  UPI_CPU1_CPU0_P1P0_DP<13>  UPI0_RX_DN13  @S9S_MB_2U_LIB.S9S_MB_2U(SCH_1):UPI_CPU1_CPU0_P1P0_DP<13>
  AP6  UPI_CPU1_CPU0_P1P0_DP<12>  UPI0_RX_DN12  @S9S_MB_2U_LIB.S9S_MB_2U(SCH_1):UPI_CPU1_CPU0_P1P0_DP<12>
  AN5  UPI_CPU1_CPU0_P1P0_DP<11>  UPI0_RX_DN11  @S9S_MB_2U_LIB.S9S_MB_2U(SCH_1):UPI_CPU1_CPU0_P1P0_DP<11>
  AK6  UPI_CPU1_CPU0_P1P0_DP<10>  UPI0_RX_DN10  @S9S_MB_2U_LIB.S9S_MB_2U(SCH_1):UPI_CPU1_CPU0_P1P0_DP<10>
   L7  UPI_CPU1_CPU0_P1P0_DP<0>  UPI0_RX_DP0  @S9S_MB_2U_LIB.S9S_MB_2U(SCH_1):UPI_CPU1_CPU0_P1P0_DP<0>
  AH6  UPI_CPU1_CPU0_P1P0_DN<9>  UPI0_RX_DN9  @S9S_MB_2U_LIB.S9S_MB_2U(SCH_1):UPI_CPU1_CPU0_P1P0_DN<9>
  AF6  UPI_CPU1_CPU0_P1P0_DN<8>  UPI0_RX_DN8  @S9S_MB_2U_LIB.S9S_MB_2U(SCH_1):UPI_CPU1_CPU0_P1P0_DN<8>
  AE5  UPI_CPU1_CPU0_P1P0_DN<7>  UPI0_RX_DN7  @S9S_MB_2U_LIB.S9S_MB_2U(SCH_1):UPI_CPU1_CPU0_P1P0_DN<7>
  AB6  UPI_CPU1_CPU0_P1P0_DN<6>  UPI0_RX_DN6  @S9S_MB_2U_LIB.S9S_MB_2U(SCH_1):UPI_CPU1_CPU0_P1P0_DN<6>
   Y6  UPI_CPU1_CPU0_P1P0_DN<5>  UPI0_RX_DP5  @S9S_MB_2U_LIB.S9S_MB_2U(SCH_1):UPI_CPU1_CPU0_P1P0_DN<5>
   V6  UPI_CPU1_CPU0_P1P0_DN<4>  UPI0_RX_DN4  @S9S_MB_2U_LIB.S9S_MB_2U(SCH_1):UPI_CPU1_CPU0_P1P0_DN<4>
   T6  UPI_CPU1_CPU0_P1P0_DN<3>  UPI0_RX_DP3  @S9S_MB_2U_LIB.S9S_MB_2U(SCH_1):UPI_CPU1_CPU0_P1P0_DN<3>
   P6  UPI_CPU1_CPU0_P1P0_DN<2>  UPI0_RX_DN2  @S9S_MB_2U_LIB.S9S_MB_2U(SCH_1):UPI_CPU1_CPU0_P1P0_DN<2>
  BT6  UPI_CPU1_CPU0_P1P0_DN<23>  UPI0_RX_DP23  @S9S_MB_2U_LIB.S9S_MB_2U(SCH_1):UPI_CPU1_CPU0_P1P0_DN<23>
  BR7  UPI_CPU1_CPU0_P1P0_DN<22>  UPI0_RX_DN22  @S9S_MB_2U_LIB.S9S_MB_2U(SCH_1):UPI_CPU1_CPU0_P1P0_DN<22>
  BM6  UPI_CPU1_CPU0_P1P0_DN<21>  UPI0_RX_DP21  @S9S_MB_2U_LIB.S9S_MB_2U(SCH_1):UPI_CPU1_CPU0_P1P0_DN<21>
  BL7  UPI_CPU1_CPU0_P1P0_DN<20>  UPI0_RX_DP20  @S9S_MB_2U_LIB.S9S_MB_2U(SCH_1):UPI_CPU1_CPU0_P1P0_DN<20>
   N5  UPI_CPU1_CPU0_P1P0_DN<1>  UPI0_RX_DN1  @S9S_MB_2U_LIB.S9S_MB_2U(SCH_1):UPI_CPU1_CPU0_P1P0_DN<1>
  BH6  UPI_CPU1_CPU0_P1P0_DN<19>  UPI0_RX_DP19  @S9S_MB_2U_LIB.S9S_MB_2U(SCH_1):UPI_CPU1_CPU0_P1P0_DN<19>
  BG7  UPI_CPU1_CPU0_P1P0_DN<18>  UPI0_RX_DP18  @S9S_MB_2U_LIB.S9S_MB_2U(SCH_1):UPI_CPU1_CPU0_P1P0_DN<18>
  BD6  UPI_CPU1_CPU0_P1P0_DN<17>  UPI0_RX_DP17  @S9S_MB_2U_LIB.S9S_MB_2U(SCH_1):UPI_CPU1_CPU0_P1P0_DN<17>
  BC7  UPI_CPU1_CPU0_P1P0_DN<16>  UPI0_RX_DP16  @S9S_MB_2U_LIB.S9S_MB_2U(SCH_1):UPI_CPU1_CPU0_P1P0_DN<16>
  AY6  UPI_CPU1_CPU0_P1P0_DN<15>  UPI0_RX_DP15  @S9S_MB_2U_LIB.S9S_MB_2U(SCH_1):UPI_CPU1_CPU0_P1P0_DN<15>
  AW7  UPI_CPU1_CPU0_P1P0_DN<14>  UPI0_RX_DP14  @S9S_MB_2U_LIB.S9S_MB_2U(SCH_1):UPI_CPU1_CPU0_P1P0_DN<14>
  AT6  UPI_CPU1_CPU0_P1P0_DN<13>  UPI0_RX_DP13  @S9S_MB_2U_LIB.S9S_MB_2U(SCH_1):UPI_CPU1_CPU0_P1P0_DN<13>
  AR7  UPI_CPU1_CPU0_P1P0_DN<12>  UPI0_RX_DP12  @S9S_MB_2U_LIB.S9S_MB_2U(SCH_1):UPI_CPU1_CPU0_P1P0_DN<12>
  AM6  UPI_CPU1_CPU0_P1P0_DN<11>  UPI0_RX_DP11  @S9S_MB_2U_LIB.S9S_MB_2U(SCH_1):UPI_CPU1_CPU0_P1P0_DN<11>
  AL7  UPI_CPU1_CPU0_P1P0_DN<10>  UPI0_RX_DP10  @S9S_MB_2U_LIB.S9S_MB_2U(SCH_1):UPI_CPU1_CPU0_P1P0_DN<10>
   K6  UPI_CPU1_CPU0_P1P0_DN<0>  UPI0_RX_DN0  @S9S_MB_2U_LIB.S9S_MB_2U(SCH_1):UPI_CPU1_CPU0_P1P0_DN<0>
  AG3  UPI_CPU0_CPU1_P0P1_DP<9>  UPI0_TX_DP9  @S9S_MB_2U_LIB.S9S_MB_2U(SCH_1):UPI_CPU0_CPU1_P0P1_DP<9>
  AE1  UPI_CPU0_CPU1_P0P1_DP<8>  UPI0_TX_DP8  @S9S_MB_2U_LIB.S9S_MB_2U(SCH_1):UPI_CPU0_CPU1_P0P1_DP<8>
  AC3  UPI_CPU0_CPU1_P0P1_DP<7>  UPI0_TX_DP7  @S9S_MB_2U_LIB.S9S_MB_2U(SCH_1):UPI_CPU0_CPU1_P0P1_DP<7>
  AB2  UPI_CPU0_CPU1_P0P1_DP<6>  UPI0_TX_DP6  @S9S_MB_2U_LIB.S9S_MB_2U(SCH_1):UPI_CPU0_CPU1_P0P1_DP<6>
   W3  UPI_CPU0_CPU1_P0P1_DP<5>  UPI0_TX_DP5  @S9S_MB_2U_LIB.S9S_MB_2U(SCH_1):UPI_CPU0_CPU1_P0P1_DP<5>
   V2  UPI_CPU0_CPU1_P0P1_DP<4>  UPI0_TX_DP4  @S9S_MB_2U_LIB.S9S_MB_2U(SCH_1):UPI_CPU0_CPU1_P0P1_DP<4>
   R3  UPI_CPU0_CPU1_P0P1_DP<3>  UPI0_TX_DP3  @S9S_MB_2U_LIB.S9S_MB_2U(SCH_1):UPI_CPU0_CPU1_P0P1_DP<3>
   P2  UPI_CPU0_CPU1_P0P1_DP<2>  UPI0_TX_DP2  @S9S_MB_2U_LIB.S9S_MB_2U(SCH_1):UPI_CPU0_CPU1_P0P1_DP<2>
  BU3  UPI_CPU0_CPU1_P0P1_DP<23>  UPI0_TX_DP23  @S9S_MB_2U_LIB.S9S_MB_2U(SCH_1):UPI_CPU0_CPU1_P0P1_DP<23>
  BR3  UPI_CPU0_CPU1_P0P1_DP<22>  UPI0_TX_DN22  @S9S_MB_2U_LIB.S9S_MB_2U(SCH_1):UPI_CPU0_CPU1_P0P1_DP<22>
  BM2  UPI_CPU0_CPU1_P0P1_DP<21>  UPI0_TX_DN21  @S9S_MB_2U_LIB.S9S_MB_2U(SCH_1):UPI_CPU0_CPU1_P0P1_DP<21>
  BK2  UPI_CPU0_CPU1_P0P1_DP<20>  UPI0_TX_DN20  @S9S_MB_2U_LIB.S9S_MB_2U(SCH_1):UPI_CPU0_CPU1_P0P1_DP<20>
   L3  UPI_CPU0_CPU1_P0P1_DP<1>  UPI0_TX_DP1  @S9S_MB_2U_LIB.S9S_MB_2U(SCH_1):UPI_CPU0_CPU1_P0P1_DP<1>
  BG3  UPI_CPU0_CPU1_P0P1_DP<19>  UPI0_TX_DP19  @S9S_MB_2U_LIB.S9S_MB_2U(SCH_1):UPI_CPU0_CPU1_P0P1_DP<19>
  BE1  UPI_CPU0_CPU1_P0P1_DP<18>  UPI0_TX_DP18  @S9S_MB_2U_LIB.S9S_MB_2U(SCH_1):UPI_CPU0_CPU1_P0P1_DP<18>
  BC3  UPI_CPU0_CPU1_P0P1_DP<17>  UPI0_TX_DP17  @S9S_MB_2U_LIB.S9S_MB_2U(SCH_1):UPI_CPU0_CPU1_P0P1_DP<17>
  BA1  UPI_CPU0_CPU1_P0P1_DP<16>  UPI0_TX_DP16  @S9S_MB_2U_LIB.S9S_MB_2U(SCH_1):UPI_CPU0_CPU1_P0P1_DP<16>
  AY2  UPI_CPU0_CPU1_P0P1_DP<15>  UPI0_TX_DN15  @S9S_MB_2U_LIB.S9S_MB_2U(SCH_1):UPI_CPU0_CPU1_P0P1_DP<15>
  AV2  UPI_CPU0_CPU1_P0P1_DP<14>  UPI0_TX_DP14  @S9S_MB_2U_LIB.S9S_MB_2U(SCH_1):UPI_CPU0_CPU1_P0P1_DP<14>
  AT2  UPI_CPU0_CPU1_P0P1_DP<13>  UPI0_TX_DN13  @S9S_MB_2U_LIB.S9S_MB_2U(SCH_1):UPI_CPU0_CPU1_P0P1_DP<13>
  AP2  UPI_CPU0_CPU1_P0P1_DP<12>  UPI0_TX_DN12  @S9S_MB_2U_LIB.S9S_MB_2U(SCH_1):UPI_CPU0_CPU1_P0P1_DP<12>
  AL3  UPI_CPU0_CPU1_P0P1_DP<11>  UPI0_TX_DP11  @S9S_MB_2U_LIB.S9S_MB_2U(SCH_1):UPI_CPU0_CPU1_P0P1_DP<11>
  AJ1  UPI_CPU0_CPU1_P0P1_DP<10>  UPI0_TX_DP10  @S9S_MB_2U_LIB.S9S_MB_2U(SCH_1):UPI_CPU0_CPU1_P0P1_DP<10>
   J3  UPI_CPU0_CPU1_P0P1_DP<0>  UPI0_TX_DP0  @S9S_MB_2U_LIB.S9S_MB_2U(SCH_1):UPI_CPU0_CPU1_P0P1_DP<0>
  AH2  UPI_CPU0_CPU1_P0P1_DN<9>  UPI0_TX_DN9  @S9S_MB_2U_LIB.S9S_MB_2U(SCH_1):UPI_CPU0_CPU1_P0P1_DN<9>
  AF2  UPI_CPU0_CPU1_P0P1_DN<8>  UPI0_TX_DN8  @S9S_MB_2U_LIB.S9S_MB_2U(SCH_1):UPI_CPU0_CPU1_P0P1_DN<8>
  AD2  UPI_CPU0_CPU1_P0P1_DN<7>  UPI0_TX_DN7  @S9S_MB_2U_LIB.S9S_MB_2U(SCH_1):UPI_CPU0_CPU1_P0P1_DN<7>
  AA1  UPI_CPU0_CPU1_P0P1_DN<6>  UPI0_TX_DN6  @S9S_MB_2U_LIB.S9S_MB_2U(SCH_1):UPI_CPU0_CPU1_P0P1_DN<6>
   Y2  UPI_CPU0_CPU1_P0P1_DN<5>  UPI0_TX_DN5  @S9S_MB_2U_LIB.S9S_MB_2U(SCH_1):UPI_CPU0_CPU1_P0P1_DN<5>
   U1  UPI_CPU0_CPU1_P0P1_DN<4>  UPI0_TX_DN4  @S9S_MB_2U_LIB.S9S_MB_2U(SCH_1):UPI_CPU0_CPU1_P0P1_DN<4>
   T2  UPI_CPU0_CPU1_P0P1_DN<3>  UPI0_TX_DN3  @S9S_MB_2U_LIB.S9S_MB_2U(SCH_1):UPI_CPU0_CPU1_P0P1_DN<3>
   N1  UPI_CPU0_CPU1_P0P1_DN<2>  UPI0_TX_DN2  @S9S_MB_2U_LIB.S9S_MB_2U(SCH_1):UPI_CPU0_CPU1_P0P1_DN<2>
  BT2  UPI_CPU0_CPU1_P0P1_DN<23>  UPI0_TX_DN23  @S9S_MB_2U_LIB.S9S_MB_2U(SCH_1):UPI_CPU0_CPU1_P0P1_DN<23>
  BN3  UPI_CPU0_CPU1_P0P1_DN<22>  UPI0_TX_DP22  @S9S_MB_2U_LIB.S9S_MB_2U(SCH_1):UPI_CPU0_CPU1_P0P1_DN<22>
  BL3  UPI_CPU0_CPU1_P0P1_DN<21>  UPI0_TX_DP21  @S9S_MB_2U_LIB.S9S_MB_2U(SCH_1):UPI_CPU0_CPU1_P0P1_DN<21>
  BJ1  UPI_CPU0_CPU1_P0P1_DN<20>  UPI0_TX_DP20  @S9S_MB_2U_LIB.S9S_MB_2U(SCH_1):UPI_CPU0_CPU1_P0P1_DN<20>
   M2  UPI_CPU0_CPU1_P0P1_DN<1>  UPI0_TX_DN1  @S9S_MB_2U_LIB.S9S_MB_2U(SCH_1):UPI_CPU0_CPU1_P0P1_DN<1>
  BH2  UPI_CPU0_CPU1_P0P1_DN<19>  UPI0_TX_DN19  @S9S_MB_2U_LIB.S9S_MB_2U(SCH_1):UPI_CPU0_CPU1_P0P1_DN<19>
  BF2  UPI_CPU0_CPU1_P0P1_DN<18>  UPI0_TX_DN18  @S9S_MB_2U_LIB.S9S_MB_2U(SCH_1):UPI_CPU0_CPU1_P0P1_DN<18>
  BD2  UPI_CPU0_CPU1_P0P1_DN<17>  UPI0_TX_DN17  @S9S_MB_2U_LIB.S9S_MB_2U(SCH_1):UPI_CPU0_CPU1_P0P1_DN<17>
  BB2  UPI_CPU0_CPU1_P0P1_DN<16>  UPI0_TX_DN16  @S9S_MB_2U_LIB.S9S_MB_2U(SCH_1):UPI_CPU0_CPU1_P0P1_DN<16>
  AW3  UPI_CPU0_CPU1_P0P1_DN<15>  UPI0_TX_DP15  @S9S_MB_2U_LIB.S9S_MB_2U(SCH_1):UPI_CPU0_CPU1_P0P1_DN<15>
  AU1  UPI_CPU0_CPU1_P0P1_DN<14>  UPI0_TX_DN14  @S9S_MB_2U_LIB.S9S_MB_2U(SCH_1):UPI_CPU0_CPU1_P0P1_DN<14>
  AR3  UPI_CPU0_CPU1_P0P1_DN<13>  UPI0_TX_DP13  @S9S_MB_2U_LIB.S9S_MB_2U(SCH_1):UPI_CPU0_CPU1_P0P1_DN<13>
  AN1  UPI_CPU0_CPU1_P0P1_DN<12>  UPI0_TX_DP12  @S9S_MB_2U_LIB.S9S_MB_2U(SCH_1):UPI_CPU0_CPU1_P0P1_DN<12>
  AM2  UPI_CPU0_CPU1_P0P1_DN<11>  UPI0_TX_DN11  @S9S_MB_2U_LIB.S9S_MB_2U(SCH_1):UPI_CPU0_CPU1_P0P1_DN<11>
  AK2  UPI_CPU0_CPU1_P0P1_DN<10>  UPI0_TX_DN10  @S9S_MB_2U_LIB.S9S_MB_2U(SCH_1):UPI_CPU0_CPU1_P0P1_DN<10>
   K4  UPI_CPU0_CPU1_P0P1_DN<0>  UPI0_TX_DN0  @S9S_MB_2U_LIB.S9S_MB_2U(SCH_1):UPI_CPU0_CPU1_P0P1_DN<0>

SOCKET4677_AZIFS054P001C01  I139  U2     [SOCKET4677_AZIFS054P001C01-SOCA]
  AD87  P5E_CPU0_PE4_TX_DP<9>  PE4_TX_DP6  @S9S_MB_2U_LIB.S9S_MB_2U(SCH_1):P5E_CPU0_PE4_TX_DP<9>
  AF85  P5E_CPU0_PE4_TX_DP<8>  PE4_TX_DP7  @S9S_MB_2U_LIB.S9S_MB_2U(SCH_1):P5E_CPU0_PE4_TX_DP<8>
  AH87  P5E_CPU0_PE4_TX_DP<7>  PE4_TX_DP8  @S9S_MB_2U_LIB.S9S_MB_2U(SCH_1):P5E_CPU0_PE4_TX_DP<7>
  AK85  P5E_CPU0_PE4_TX_DP<6>  PE4_TX_DP9  @S9S_MB_2U_LIB.S9S_MB_2U(SCH_1):P5E_CPU0_PE4_TX_DP<6>
  AM87  P5E_CPU0_PE4_TX_DP<5>  PE4_TX_DP10  @S9S_MB_2U_LIB.S9S_MB_2U(SCH_1):P5E_CPU0_PE4_TX_DP<5>
  AN86  P5E_CPU0_PE4_TX_DP<4>  PE4_TX_DP11  @S9S_MB_2U_LIB.S9S_MB_2U(SCH_1):P5E_CPU0_PE4_TX_DP<4>
  AT87  P5E_CPU0_PE4_TX_DP<3>  PE4_TX_DP12  @S9S_MB_2U_LIB.S9S_MB_2U(SCH_1):P5E_CPU0_PE4_TX_DP<3>
  AV85  P5E_CPU0_PE4_TX_DP<2>  PE4_TX_DP13  @S9S_MB_2U_LIB.S9S_MB_2U(SCH_1):P5E_CPU0_PE4_TX_DP<2>
  AY87  P5E_CPU0_PE4_TX_DP<1>  PE4_TX_DP14  @S9S_MB_2U_LIB.S9S_MB_2U(SCH_1):P5E_CPU0_PE4_TX_DP<1>
  M87  P5E_CPU0_PE4_TX_DP<15>  PE4_TX_DP0  @S9S_MB_2U_LIB.S9S_MB_2U(SCH_1):P5E_CPU0_PE4_TX_DP<15>
  N86  P5E_CPU0_PE4_TX_DP<14>  PE4_TX_DP1  @S9S_MB_2U_LIB.S9S_MB_2U(SCH_1):P5E_CPU0_PE4_TX_DP<14>
  T87  P5E_CPU0_PE4_TX_DP<13>  PE4_TX_DP2  @S9S_MB_2U_LIB.S9S_MB_2U(SCH_1):P5E_CPU0_PE4_TX_DP<13>
  V85  P5E_CPU0_PE4_TX_DP<12>  PE4_TX_DP3  @S9S_MB_2U_LIB.S9S_MB_2U(SCH_1):P5E_CPU0_PE4_TX_DP<12>
  Y87  P5E_CPU0_PE4_TX_DP<11>  PE4_TX_DP4  @S9S_MB_2U_LIB.S9S_MB_2U(SCH_1):P5E_CPU0_PE4_TX_DP<11>
  AB85  P5E_CPU0_PE4_TX_DP<10>  PE4_TX_DP5  @S9S_MB_2U_LIB.S9S_MB_2U(SCH_1):P5E_CPU0_PE4_TX_DP<10>
  BB85  P5E_CPU0_PE4_TX_DP<0>  PE4_TX_DP15  @S9S_MB_2U_LIB.S9S_MB_2U(SCH_1):P5E_CPU0_PE4_TX_DP<0>
  AC86  P5E_CPU0_PE4_TX_DN<9>  PE4_TX_DN6  @S9S_MB_2U_LIB.S9S_MB_2U(SCH_1):P5E_CPU0_PE4_TX_DN<9>
  AE86  P5E_CPU0_PE4_TX_DN<8>  PE4_TX_DN7  @S9S_MB_2U_LIB.S9S_MB_2U(SCH_1):P5E_CPU0_PE4_TX_DN<8>
  AG86  P5E_CPU0_PE4_TX_DN<7>  PE4_TX_DN8  @S9S_MB_2U_LIB.S9S_MB_2U(SCH_1):P5E_CPU0_PE4_TX_DN<7>
  AJ86  P5E_CPU0_PE4_TX_DN<6>  PE4_TX_DN9  @S9S_MB_2U_LIB.S9S_MB_2U(SCH_1):P5E_CPU0_PE4_TX_DN<6>
  AL86  P5E_CPU0_PE4_TX_DN<5>  PE4_TX_DN10  @S9S_MB_2U_LIB.S9S_MB_2U(SCH_1):P5E_CPU0_PE4_TX_DN<5>
  AP85  P5E_CPU0_PE4_TX_DN<4>  PE4_TX_DN11  @S9S_MB_2U_LIB.S9S_MB_2U(SCH_1):P5E_CPU0_PE4_TX_DN<4>
  AR86  P5E_CPU0_PE4_TX_DN<3>  PE4_TX_DN12  @S9S_MB_2U_LIB.S9S_MB_2U(SCH_1):P5E_CPU0_PE4_TX_DN<3>
  AU86  P5E_CPU0_PE4_TX_DN<2>  PE4_TX_DN13  @S9S_MB_2U_LIB.S9S_MB_2U(SCH_1):P5E_CPU0_PE4_TX_DN<2>
  AW86  P5E_CPU0_PE4_TX_DN<1>  PE4_TX_DN14  @S9S_MB_2U_LIB.S9S_MB_2U(SCH_1):P5E_CPU0_PE4_TX_DN<1>
  L86  P5E_CPU0_PE4_TX_DN<15>  PE4_TX_DN0  @S9S_MB_2U_LIB.S9S_MB_2U(SCH_1):P5E_CPU0_PE4_TX_DN<15>
  P85  P5E_CPU0_PE4_TX_DN<14>  PE4_TX_DN1  @S9S_MB_2U_LIB.S9S_MB_2U(SCH_1):P5E_CPU0_PE4_TX_DN<14>
  R86  P5E_CPU0_PE4_TX_DN<13>  PE4_TX_DN2  @S9S_MB_2U_LIB.S9S_MB_2U(SCH_1):P5E_CPU0_PE4_TX_DN<13>
  U86  P5E_CPU0_PE4_TX_DN<12>  PE4_TX_DN3  @S9S_MB_2U_LIB.S9S_MB_2U(SCH_1):P5E_CPU0_PE4_TX_DN<12>
  W86  P5E_CPU0_PE4_TX_DN<11>  PE4_TX_DN4  @S9S_MB_2U_LIB.S9S_MB_2U(SCH_1):P5E_CPU0_PE4_TX_DN<11>
  AA86  P5E_CPU0_PE4_TX_DN<10>  PE4_TX_DN5  @S9S_MB_2U_LIB.S9S_MB_2U(SCH_1):P5E_CPU0_PE4_TX_DN<10>
  BA86  P5E_CPU0_PE4_TX_DN<0>  PE4_TX_DN15  @S9S_MB_2U_LIB.S9S_MB_2U(SCH_1):P5E_CPU0_PE4_TX_DN<0>
  AC90  P5E_CPU0_PE4_RX_DP<9>  PE4_RX_DP6  @S9S_MB_2U_LIB.S9S_MB_2U(SCH_1):P5E_CPU0_PE4_RX_DP<9>
  AE90  P5E_CPU0_PE4_RX_DP<8>  PE4_RX_DP7  @S9S_MB_2U_LIB.S9S_MB_2U(SCH_1):P5E_CPU0_PE4_RX_DP<8>
  AG90  P5E_CPU0_PE4_RX_DP<7>  PE4_RX_DP8  @S9S_MB_2U_LIB.S9S_MB_2U(SCH_1):P5E_CPU0_PE4_RX_DP<7>
  AJ90  P5E_CPU0_PE4_RX_DP<6>  PE4_RX_DP9  @S9S_MB_2U_LIB.S9S_MB_2U(SCH_1):P5E_CPU0_PE4_RX_DP<6>
  AL90  P5E_CPU0_PE4_RX_DP<5>  PE4_RX_DP10  @S9S_MB_2U_LIB.S9S_MB_2U(SCH_1):P5E_CPU0_PE4_RX_DP<5>
  AN90  P5E_CPU0_PE4_RX_DP<4>  PE4_RX_DP11  @S9S_MB_2U_LIB.S9S_MB_2U(SCH_1):P5E_CPU0_PE4_RX_DP<4>
  AR90  P5E_CPU0_PE4_RX_DP<3>  PE4_RX_DP12  @S9S_MB_2U_LIB.S9S_MB_2U(SCH_1):P5E_CPU0_PE4_RX_DP<3>
  AU90  P5E_CPU0_PE4_RX_DP<2>  PE4_RX_DP13  @S9S_MB_2U_LIB.S9S_MB_2U(SCH_1):P5E_CPU0_PE4_RX_DP<2>
  AW90  P5E_CPU0_PE4_RX_DP<1>  PE4_RX_DP14  @S9S_MB_2U_LIB.S9S_MB_2U(SCH_1):P5E_CPU0_PE4_RX_DP<1>
  K89  P5E_CPU0_PE4_RX_DP<15>  PE4_RX_DP0  @S9S_MB_2U_LIB.S9S_MB_2U(SCH_1):P5E_CPU0_PE4_RX_DP<15>
  N90  P5E_CPU0_PE4_RX_DP<14>  PE4_RX_DP1  @S9S_MB_2U_LIB.S9S_MB_2U(SCH_1):P5E_CPU0_PE4_RX_DP<14>
  R90  P5E_CPU0_PE4_RX_DP<13>  PE4_RX_DP2  @S9S_MB_2U_LIB.S9S_MB_2U(SCH_1):P5E_CPU0_PE4_RX_DP<13>
  U90  P5E_CPU0_PE4_RX_DP<12>  PE4_RX_DP3  @S9S_MB_2U_LIB.S9S_MB_2U(SCH_1):P5E_CPU0_PE4_RX_DP<12>
  W90  P5E_CPU0_PE4_RX_DP<11>  PE4_RX_DP4  @S9S_MB_2U_LIB.S9S_MB_2U(SCH_1):P5E_CPU0_PE4_RX_DP<11>
  AA90  P5E_CPU0_PE4_RX_DP<10>  PE4_RX_DP5  @S9S_MB_2U_LIB.S9S_MB_2U(SCH_1):P5E_CPU0_PE4_RX_DP<10>
  BA90  P5E_CPU0_PE4_RX_DP<0>  PE4_RX_DP15  @S9S_MB_2U_LIB.S9S_MB_2U(SCH_1):P5E_CPU0_PE4_RX_DP<0>
  AD91  P5E_CPU0_PE4_RX_DN<9>  PE4_RX_DN6  @S9S_MB_2U_LIB.S9S_MB_2U(SCH_1):P5E_CPU0_PE4_RX_DN<9>
  AF89  P5E_CPU0_PE4_RX_DN<8>  PE4_RX_DN7  @S9S_MB_2U_LIB.S9S_MB_2U(SCH_1):P5E_CPU0_PE4_RX_DN<8>
  AH91  P5E_CPU0_PE4_RX_DN<7>  PE4_RX_DN8  @S9S_MB_2U_LIB.S9S_MB_2U(SCH_1):P5E_CPU0_PE4_RX_DN<7>
  AK89  P5E_CPU0_PE4_RX_DN<6>  PE4_RX_DN9  @S9S_MB_2U_LIB.S9S_MB_2U(SCH_1):P5E_CPU0_PE4_RX_DN<6>
  AM91  P5E_CPU0_PE4_RX_DN<5>  PE4_RX_DN10  @S9S_MB_2U_LIB.S9S_MB_2U(SCH_1):P5E_CPU0_PE4_RX_DN<5>
  AP89  P5E_CPU0_PE4_RX_DN<4>  PE4_RX_DN11  @S9S_MB_2U_LIB.S9S_MB_2U(SCH_1):P5E_CPU0_PE4_RX_DN<4>
  AT91  P5E_CPU0_PE4_RX_DN<3>  PE4_RX_DN12  @S9S_MB_2U_LIB.S9S_MB_2U(SCH_1):P5E_CPU0_PE4_RX_DN<3>
  AV89  P5E_CPU0_PE4_RX_DN<2>  PE4_RX_DN13  @S9S_MB_2U_LIB.S9S_MB_2U(SCH_1):P5E_CPU0_PE4_RX_DN<2>
  AY91  P5E_CPU0_PE4_RX_DN<1>  PE4_RX_DN14  @S9S_MB_2U_LIB.S9S_MB_2U(SCH_1):P5E_CPU0_PE4_RX_DN<1>
  J90  P5E_CPU0_PE4_RX_DN<15>  PE4_RX_DN0  @S9S_MB_2U_LIB.S9S_MB_2U(SCH_1):P5E_CPU0_PE4_RX_DN<15>
  P89  P5E_CPU0_PE4_RX_DN<14>  PE4_RX_DN1  @S9S_MB_2U_LIB.S9S_MB_2U(SCH_1):P5E_CPU0_PE4_RX_DN<14>
  T91  P5E_CPU0_PE4_RX_DN<13>  PE4_RX_DN2  @S9S_MB_2U_LIB.S9S_MB_2U(SCH_1):P5E_CPU0_PE4_RX_DN<13>
  V89  P5E_CPU0_PE4_RX_DN<12>  PE4_RX_DN3  @S9S_MB_2U_LIB.S9S_MB_2U(SCH_1):P5E_CPU0_PE4_RX_DN<12>
  Y91  P5E_CPU0_PE4_RX_DN<11>  PE4_RX_DN4  @S9S_MB_2U_LIB.S9S_MB_2U(SCH_1):P5E_CPU0_PE4_RX_DN<11>
  AB89  P5E_CPU0_PE4_RX_DN<10>  PE4_RX_DN5  @S9S_MB_2U_LIB.S9S_MB_2U(SCH_1):P5E_CPU0_PE4_RX_DN<10>
  BB89  P5E_CPU0_PE4_RX_DN<0>  PE4_RX_DN15  @S9S_MB_2U_LIB.S9S_MB_2U(SCH_1):P5E_CPU0_PE4_RX_DN<0>

SOCKET4677_AZIFS054P001C01  I140  U2     [SOCKET4677_AZIFS054P001C01-SOCA]
  DG86  P5E_CPU0_PE3_TX_DP<9>  PE3_TX_DP9  @S9S_MB_2U_LIB.S9S_MB_2U(SCH_1):P5E_CPU0_PE3_TX_DP<9>
  DJ86  P5E_CPU0_PE3_TX_DP<8>  PE3_TX_DP8  @S9S_MB_2U_LIB.S9S_MB_2U(SCH_1):P5E_CPU0_PE3_TX_DP<8>
  DL86  P5E_CPU0_PE3_TX_DP<7>  PE3_TX_DP7  @S9S_MB_2U_LIB.S9S_MB_2U(SCH_1):P5E_CPU0_PE3_TX_DP<7>
  DN86  P5E_CPU0_PE3_TX_DP<6>  PE3_TX_DP6  @S9S_MB_2U_LIB.S9S_MB_2U(SCH_1):P5E_CPU0_PE3_TX_DP<6>
  DR86  P5E_CPU0_PE3_TX_DP<5>  PE3_TX_DP5  @S9S_MB_2U_LIB.S9S_MB_2U(SCH_1):P5E_CPU0_PE3_TX_DP<5>
  DU86  P5E_CPU0_PE3_TX_DP<4>  PE3_TX_DP4  @S9S_MB_2U_LIB.S9S_MB_2U(SCH_1):P5E_CPU0_PE3_TX_DP<4>
  DW86  P5E_CPU0_PE3_TX_DP<3>  PE3_TX_DP3  @S9S_MB_2U_LIB.S9S_MB_2U(SCH_1):P5E_CPU0_PE3_TX_DP<3>
  EA86  P5E_CPU0_PE3_TX_DP<2>  PE3_TX_DP2  @S9S_MB_2U_LIB.S9S_MB_2U(SCH_1):P5E_CPU0_PE3_TX_DP<2>
  EC86  P5E_CPU0_PE3_TX_DP<1>  PE3_TX_DP1  @S9S_MB_2U_LIB.S9S_MB_2U(SCH_1):P5E_CPU0_PE3_TX_DP<1>
  CR86  P5E_CPU0_PE3_TX_DP<15>  PE3_TX_DP15  @S9S_MB_2U_LIB.S9S_MB_2U(SCH_1):P5E_CPU0_PE3_TX_DP<15>
  CU86  P5E_CPU0_PE3_TX_DP<14>  PE3_TX_DP14  @S9S_MB_2U_LIB.S9S_MB_2U(SCH_1):P5E_CPU0_PE3_TX_DP<14>
  CW86  P5E_CPU0_PE3_TX_DP<13>  PE3_TX_DP13  @S9S_MB_2U_LIB.S9S_MB_2U(SCH_1):P5E_CPU0_PE3_TX_DP<13>
  DA86  P5E_CPU0_PE3_TX_DP<12>  PE3_TX_DP12  @S9S_MB_2U_LIB.S9S_MB_2U(SCH_1):P5E_CPU0_PE3_TX_DP<12>
  DC86  P5E_CPU0_PE3_TX_DP<11>  PE3_TX_DP11  @S9S_MB_2U_LIB.S9S_MB_2U(SCH_1):P5E_CPU0_PE3_TX_DP<11>
  DE86  P5E_CPU0_PE3_TX_DP<10>  PE3_TX_DP10  @S9S_MB_2U_LIB.S9S_MB_2U(SCH_1):P5E_CPU0_PE3_TX_DP<10>
  ED87  P5E_CPU0_PE3_TX_DP<0>  PE3_TX_DP0  @S9S_MB_2U_LIB.S9S_MB_2U(SCH_1):P5E_CPU0_PE3_TX_DP<0>
  DF85  P5E_CPU0_PE3_TX_DN<9>  PE3_TX_DN9  @S9S_MB_2U_LIB.S9S_MB_2U(SCH_1):P5E_CPU0_PE3_TX_DN<9>
  DH87  P5E_CPU0_PE3_TX_DN<8>  PE3_TX_DN8  @S9S_MB_2U_LIB.S9S_MB_2U(SCH_1):P5E_CPU0_PE3_TX_DN<8>
  DK85  P5E_CPU0_PE3_TX_DN<7>  PE3_TX_DN7  @S9S_MB_2U_LIB.S9S_MB_2U(SCH_1):P5E_CPU0_PE3_TX_DN<7>
  DM87  P5E_CPU0_PE3_TX_DN<6>  PE3_TX_DN6  @S9S_MB_2U_LIB.S9S_MB_2U(SCH_1):P5E_CPU0_PE3_TX_DN<6>
  DP85  P5E_CPU0_PE3_TX_DN<5>  PE3_TX_DN5  @S9S_MB_2U_LIB.S9S_MB_2U(SCH_1):P5E_CPU0_PE3_TX_DN<5>
  DT87  P5E_CPU0_PE3_TX_DN<4>  PE3_TX_DN4  @S9S_MB_2U_LIB.S9S_MB_2U(SCH_1):P5E_CPU0_PE3_TX_DN<4>
  DV85  P5E_CPU0_PE3_TX_DN<3>  PE3_TX_DN3  @S9S_MB_2U_LIB.S9S_MB_2U(SCH_1):P5E_CPU0_PE3_TX_DN<3>
  DY87  P5E_CPU0_PE3_TX_DN<2>  PE3_TX_DN2  @S9S_MB_2U_LIB.S9S_MB_2U(SCH_1):P5E_CPU0_PE3_TX_DN<2>
  EB85  P5E_CPU0_PE3_TX_DN<1>  PE3_TX_DN1  @S9S_MB_2U_LIB.S9S_MB_2U(SCH_1):P5E_CPU0_PE3_TX_DN<1>
  CP85  P5E_CPU0_PE3_TX_DN<15>  PE3_TX_DN15  @S9S_MB_2U_LIB.S9S_MB_2U(SCH_1):P5E_CPU0_PE3_TX_DN<15>
  CT87  P5E_CPU0_PE3_TX_DN<14>  PE3_TX_DN14  @S9S_MB_2U_LIB.S9S_MB_2U(SCH_1):P5E_CPU0_PE3_TX_DN<14>
  CV85  P5E_CPU0_PE3_TX_DN<13>  PE3_TX_DN13  @S9S_MB_2U_LIB.S9S_MB_2U(SCH_1):P5E_CPU0_PE3_TX_DN<13>
  CY87  P5E_CPU0_PE3_TX_DN<12>  PE3_TX_DN12  @S9S_MB_2U_LIB.S9S_MB_2U(SCH_1):P5E_CPU0_PE3_TX_DN<12>
  DB85  P5E_CPU0_PE3_TX_DN<11>  PE3_TX_DN11  @S9S_MB_2U_LIB.S9S_MB_2U(SCH_1):P5E_CPU0_PE3_TX_DN<11>
  DD87  P5E_CPU0_PE3_TX_DN<10>  PE3_TX_DN10  @S9S_MB_2U_LIB.S9S_MB_2U(SCH_1):P5E_CPU0_PE3_TX_DN<10>
  EE86  P5E_CPU0_PE3_TX_DN<0>  PE3_TX_DN0  @S9S_MB_2U_LIB.S9S_MB_2U(SCH_1):P5E_CPU0_PE3_TX_DN<0>
  DJ90  P5E_CPU0_PE3_RX_DP<9>  PE3_RX_DP9  @S9S_MB_2U_LIB.S9S_MB_2U(SCH_1):P5E_CPU0_PE3_RX_DP<9>
  DK89  P5E_CPU0_PE3_RX_DP<8>  PE3_RX_DP8  @S9S_MB_2U_LIB.S9S_MB_2U(SCH_1):P5E_CPU0_PE3_RX_DP<8>
  DM91  P5E_CPU0_PE3_RX_DP<7>  PE3_RX_DP7  @S9S_MB_2U_LIB.S9S_MB_2U(SCH_1):P5E_CPU0_PE3_RX_DP<7>
  DR90  P5E_CPU0_PE3_RX_DP<6>  PE3_RX_DP6  @S9S_MB_2U_LIB.S9S_MB_2U(SCH_1):P5E_CPU0_PE3_RX_DP<6>
  DT91  P5E_CPU0_PE3_RX_DP<5>  PE3_RX_DP5  @S9S_MB_2U_LIB.S9S_MB_2U(SCH_1):P5E_CPU0_PE3_RX_DP<5>
  DW90  P5E_CPU0_PE3_RX_DP<4>  PE3_RX_DP4  @S9S_MB_2U_LIB.S9S_MB_2U(SCH_1):P5E_CPU0_PE3_RX_DP<4>
  EA90  P5E_CPU0_PE3_RX_DP<3>  PE3_RX_DP3  @S9S_MB_2U_LIB.S9S_MB_2U(SCH_1):P5E_CPU0_PE3_RX_DP<3>
  EB89  P5E_CPU0_PE3_RX_DP<2>  PE3_RX_DP2  @S9S_MB_2U_LIB.S9S_MB_2U(SCH_1):P5E_CPU0_PE3_RX_DP<2>
  EE90  P5E_CPU0_PE3_RX_DP<1>  PE3_RX_DP1  @S9S_MB_2U_LIB.S9S_MB_2U(SCH_1):P5E_CPU0_PE3_RX_DP<1>
  CT91  P5E_CPU0_PE3_RX_DP<15>  PE3_RX_DP15  @S9S_MB_2U_LIB.S9S_MB_2U(SCH_1):P5E_CPU0_PE3_RX_DP<15>
  CW90  P5E_CPU0_PE3_RX_DP<14>  PE3_RX_DP14  @S9S_MB_2U_LIB.S9S_MB_2U(SCH_1):P5E_CPU0_PE3_RX_DP<14>
  CY91  P5E_CPU0_PE3_RX_DP<13>  PE3_RX_DP13  @S9S_MB_2U_LIB.S9S_MB_2U(SCH_1):P5E_CPU0_PE3_RX_DP<13>
  DC90  P5E_CPU0_PE3_RX_DP<12>  PE3_RX_DP12  @S9S_MB_2U_LIB.S9S_MB_2U(SCH_1):P5E_CPU0_PE3_RX_DP<12>
  DE90  P5E_CPU0_PE3_RX_DP<11>  PE3_RX_DP11  @S9S_MB_2U_LIB.S9S_MB_2U(SCH_1):P5E_CPU0_PE3_RX_DP<11>
  DF89  P5E_CPU0_PE3_RX_DP<10>  PE3_RX_DP10  @S9S_MB_2U_LIB.S9S_MB_2U(SCH_1):P5E_CPU0_PE3_RX_DP<10>
  EJ90  P5E_CPU0_PE3_RX_DP<0>  PE3_RX_DP0  @S9S_MB_2U_LIB.S9S_MB_2U(SCH_1):P5E_CPU0_PE3_RX_DP<0>
  DH91  P5E_CPU0_PE3_RX_DN<9>  PE3_RX_DN9  @S9S_MB_2U_LIB.S9S_MB_2U(SCH_1):P5E_CPU0_PE3_RX_DN<9>
  DL90  P5E_CPU0_PE3_RX_DN<8>  PE3_RX_DN8  @S9S_MB_2U_LIB.S9S_MB_2U(SCH_1):P5E_CPU0_PE3_RX_DN<8>
  DN90  P5E_CPU0_PE3_RX_DN<7>  PE3_RX_DN7  @S9S_MB_2U_LIB.S9S_MB_2U(SCH_1):P5E_CPU0_PE3_RX_DN<7>
  DP89  P5E_CPU0_PE3_RX_DN<6>  PE3_RX_DN6  @S9S_MB_2U_LIB.S9S_MB_2U(SCH_1):P5E_CPU0_PE3_RX_DN<6>
  DU90  P5E_CPU0_PE3_RX_DN<5>  PE3_RX_DN5  @S9S_MB_2U_LIB.S9S_MB_2U(SCH_1):P5E_CPU0_PE3_RX_DN<5>
  DV89  P5E_CPU0_PE3_RX_DN<4>  PE3_RX_DN4  @S9S_MB_2U_LIB.S9S_MB_2U(SCH_1):P5E_CPU0_PE3_RX_DN<4>
  DY91  P5E_CPU0_PE3_RX_DN<3>  PE3_RX_DN3  @S9S_MB_2U_LIB.S9S_MB_2U(SCH_1):P5E_CPU0_PE3_RX_DN<3>
  EC90  P5E_CPU0_PE3_RX_DN<2>  PE3_RX_DN2  @S9S_MB_2U_LIB.S9S_MB_2U(SCH_1):P5E_CPU0_PE3_RX_DN<2>
  ED91  P5E_CPU0_PE3_RX_DN<1>  PE3_RX_DN1  @S9S_MB_2U_LIB.S9S_MB_2U(SCH_1):P5E_CPU0_PE3_RX_DN<1>
  CU90  P5E_CPU0_PE3_RX_DN<15>  PE3_RX_DN15  @S9S_MB_2U_LIB.S9S_MB_2U(SCH_1):P5E_CPU0_PE3_RX_DN<15>
  CV89  P5E_CPU0_PE3_RX_DN<14>  PE3_RX_DN14  @S9S_MB_2U_LIB.S9S_MB_2U(SCH_1):P5E_CPU0_PE3_RX_DN<14>
  DA90  P5E_CPU0_PE3_RX_DN<13>  PE3_RX_DN13  @S9S_MB_2U_LIB.S9S_MB_2U(SCH_1):P5E_CPU0_PE3_RX_DN<13>
  DB89  P5E_CPU0_PE3_RX_DN<12>  PE3_RX_DN12  @S9S_MB_2U_LIB.S9S_MB_2U(SCH_1):P5E_CPU0_PE3_RX_DN<12>
  DD91  P5E_CPU0_PE3_RX_DN<11>  PE3_RX_DN11  @S9S_MB_2U_LIB.S9S_MB_2U(SCH_1):P5E_CPU0_PE3_RX_DN<11>
  DG90  P5E_CPU0_PE3_RX_DN<10>  PE3_RX_DN10  @S9S_MB_2U_LIB.S9S_MB_2U(SCH_1):P5E_CPU0_PE3_RX_DN<10>
  EH89  P5E_CPU0_PE3_RX_DN<0>  PE3_RX_DN0  @S9S_MB_2U_LIB.S9S_MB_2U(SCH_1):P5E_CPU0_PE3_RX_DN<0>

SOCKET4677_AZIFS054P001C01  I139  U2     [SOCKET4677_AZIFS054P001C01-SOCA]
  DP14  P5E_CPU0_PE2_TX_DP<9>  PE2_TX_DN9  @S9S_MB_2U_LIB.S9S_MB_2U(SCH_1):P5E_CPU0_PE2_TX_DP<9>
  DN13  P5E_CPU0_PE2_TX_DP<8>  PE2_TX_DN8  @S9S_MB_2U_LIB.S9S_MB_2U(SCH_1):P5E_CPU0_PE2_TX_DP<8>
  DK14  P5E_CPU0_PE2_TX_DP<7>  PE2_TX_DN7  @S9S_MB_2U_LIB.S9S_MB_2U(SCH_1):P5E_CPU0_PE2_TX_DP<7>
  DJ13  P5E_CPU0_PE2_TX_DP<6>  PE2_TX_DN6  @S9S_MB_2U_LIB.S9S_MB_2U(SCH_1):P5E_CPU0_PE2_TX_DP<6>
  DF14  P5E_CPU0_PE2_TX_DP<5>  PE2_TX_DN5  @S9S_MB_2U_LIB.S9S_MB_2U(SCH_1):P5E_CPU0_PE2_TX_DP<5>
  DE13  P5E_CPU0_PE2_TX_DP<4>  PE2_TX_DN4  @S9S_MB_2U_LIB.S9S_MB_2U(SCH_1):P5E_CPU0_PE2_TX_DP<4>
  DB14  P5E_CPU0_PE2_TX_DP<3>  PE2_TX_DN3  @S9S_MB_2U_LIB.S9S_MB_2U(SCH_1):P5E_CPU0_PE2_TX_DP<3>
  DA13  P5E_CPU0_PE2_TX_DP<2>  PE2_TX_DN2  @S9S_MB_2U_LIB.S9S_MB_2U(SCH_1):P5E_CPU0_PE2_TX_DP<2>
  CV14  P5E_CPU0_PE2_TX_DP<1>  PE2_TX_DN1  @S9S_MB_2U_LIB.S9S_MB_2U(SCH_1):P5E_CPU0_PE2_TX_DP<1>
  EF14  P5E_CPU0_PE2_TX_DP<15>  PE2_TX_DN15  @S9S_MB_2U_LIB.S9S_MB_2U(SCH_1):P5E_CPU0_PE2_TX_DP<15>
  EE13  P5E_CPU0_PE2_TX_DP<14>  PE2_TX_DN14  @S9S_MB_2U_LIB.S9S_MB_2U(SCH_1):P5E_CPU0_PE2_TX_DP<14>
  EB14  P5E_CPU0_PE2_TX_DP<13>  PE2_TX_DN13  @S9S_MB_2U_LIB.S9S_MB_2U(SCH_1):P5E_CPU0_PE2_TX_DP<13>
  EA13  P5E_CPU0_PE2_TX_DP<12>  PE2_TX_DN12  @S9S_MB_2U_LIB.S9S_MB_2U(SCH_1):P5E_CPU0_PE2_TX_DP<12>
  DV14  P5E_CPU0_PE2_TX_DP<11>  PE2_TX_DN11  @S9S_MB_2U_LIB.S9S_MB_2U(SCH_1):P5E_CPU0_PE2_TX_DP<11>
  DU13  P5E_CPU0_PE2_TX_DP<10>  PE2_TX_DN10  @S9S_MB_2U_LIB.S9S_MB_2U(SCH_1):P5E_CPU0_PE2_TX_DP<10>
  CU13  P5E_CPU0_PE2_TX_DP<0>  PE2_TX_DN0  @S9S_MB_2U_LIB.S9S_MB_2U(SCH_1):P5E_CPU0_PE2_TX_DP<0>
  DR15  P5E_CPU0_PE2_TX_DN<9>  PE2_TX_DP9  @S9S_MB_2U_LIB.S9S_MB_2U(SCH_1):P5E_CPU0_PE2_TX_DN<9>
  DM14  P5E_CPU0_PE2_TX_DN<8>  PE2_TX_DP8  @S9S_MB_2U_LIB.S9S_MB_2U(SCH_1):P5E_CPU0_PE2_TX_DN<8>
  DL15  P5E_CPU0_PE2_TX_DN<7>  PE2_TX_DP7  @S9S_MB_2U_LIB.S9S_MB_2U(SCH_1):P5E_CPU0_PE2_TX_DN<7>
  DH14  P5E_CPU0_PE2_TX_DN<6>  PE2_TX_DP6  @S9S_MB_2U_LIB.S9S_MB_2U(SCH_1):P5E_CPU0_PE2_TX_DN<6>
  DG15  P5E_CPU0_PE2_TX_DN<5>  PE2_TX_DP5  @S9S_MB_2U_LIB.S9S_MB_2U(SCH_1):P5E_CPU0_PE2_TX_DN<5>
  DD14  P5E_CPU0_PE2_TX_DN<4>  PE2_TX_DP4  @S9S_MB_2U_LIB.S9S_MB_2U(SCH_1):P5E_CPU0_PE2_TX_DN<4>
  DC15  P5E_CPU0_PE2_TX_DN<3>  PE2_TX_DP3  @S9S_MB_2U_LIB.S9S_MB_2U(SCH_1):P5E_CPU0_PE2_TX_DN<3>
  CY14  P5E_CPU0_PE2_TX_DN<2>  PE2_TX_DP2  @S9S_MB_2U_LIB.S9S_MB_2U(SCH_1):P5E_CPU0_PE2_TX_DN<2>
  CW15  P5E_CPU0_PE2_TX_DN<1>  PE2_TX_DP1  @S9S_MB_2U_LIB.S9S_MB_2U(SCH_1):P5E_CPU0_PE2_TX_DN<1>
  EG15  P5E_CPU0_PE2_TX_DN<15>  PE2_TX_DP15  @S9S_MB_2U_LIB.S9S_MB_2U(SCH_1):P5E_CPU0_PE2_TX_DN<15>
  ED14  P5E_CPU0_PE2_TX_DN<14>  PE2_TX_DP14  @S9S_MB_2U_LIB.S9S_MB_2U(SCH_1):P5E_CPU0_PE2_TX_DN<14>
  EC15  P5E_CPU0_PE2_TX_DN<13>  PE2_TX_DP13  @S9S_MB_2U_LIB.S9S_MB_2U(SCH_1):P5E_CPU0_PE2_TX_DN<13>
  DY14  P5E_CPU0_PE2_TX_DN<12>  PE2_TX_DP12  @S9S_MB_2U_LIB.S9S_MB_2U(SCH_1):P5E_CPU0_PE2_TX_DN<12>
  DW15  P5E_CPU0_PE2_TX_DN<11>  PE2_TX_DP11  @S9S_MB_2U_LIB.S9S_MB_2U(SCH_1):P5E_CPU0_PE2_TX_DN<11>
  DT14  P5E_CPU0_PE2_TX_DN<10>  PE2_TX_DP10  @S9S_MB_2U_LIB.S9S_MB_2U(SCH_1):P5E_CPU0_PE2_TX_DN<10>
  CT14  P5E_CPU0_PE2_TX_DN<0>  PE2_TX_DP0  @S9S_MB_2U_LIB.S9S_MB_2U(SCH_1):P5E_CPU0_PE2_TX_DN<0>
  DR11  P5E_CPU0_PE2_RX_DP<9>  PE2_RX_DP9  @S9S_MB_2U_LIB.S9S_MB_2U(SCH_1):P5E_CPU0_PE2_RX_DP<9>
  DP10  P5E_CPU0_PE2_RX_DP<8>  PE2_RX_DP8  @S9S_MB_2U_LIB.S9S_MB_2U(SCH_1):P5E_CPU0_PE2_RX_DP<8>
  DL11  P5E_CPU0_PE2_RX_DP<7>  PE2_RX_DP7  @S9S_MB_2U_LIB.S9S_MB_2U(SCH_1):P5E_CPU0_PE2_RX_DP<7>
  DK10  P5E_CPU0_PE2_RX_DP<6>  PE2_RX_DP6  @S9S_MB_2U_LIB.S9S_MB_2U(SCH_1):P5E_CPU0_PE2_RX_DP<6>
  DG11  P5E_CPU0_PE2_RX_DP<5>  PE2_RX_DP5  @S9S_MB_2U_LIB.S9S_MB_2U(SCH_1):P5E_CPU0_PE2_RX_DP<5>
  DF10  P5E_CPU0_PE2_RX_DP<4>  PE2_RX_DP4  @S9S_MB_2U_LIB.S9S_MB_2U(SCH_1):P5E_CPU0_PE2_RX_DP<4>
  DC11  P5E_CPU0_PE2_RX_DP<3>  PE2_RX_DP3  @S9S_MB_2U_LIB.S9S_MB_2U(SCH_1):P5E_CPU0_PE2_RX_DP<3>
  DB10  P5E_CPU0_PE2_RX_DP<2>  PE2_RX_DP2  @S9S_MB_2U_LIB.S9S_MB_2U(SCH_1):P5E_CPU0_PE2_RX_DP<2>
  CW11  P5E_CPU0_PE2_RX_DP<1>  PE2_RX_DP1  @S9S_MB_2U_LIB.S9S_MB_2U(SCH_1):P5E_CPU0_PE2_RX_DP<1>
  EG11  P5E_CPU0_PE2_RX_DP<15>  PE2_RX_DP15  @S9S_MB_2U_LIB.S9S_MB_2U(SCH_1):P5E_CPU0_PE2_RX_DP<15>
  EF10  P5E_CPU0_PE2_RX_DP<14>  PE2_RX_DP14  @S9S_MB_2U_LIB.S9S_MB_2U(SCH_1):P5E_CPU0_PE2_RX_DP<14>
  EC11  P5E_CPU0_PE2_RX_DP<13>  PE2_RX_DP13  @S9S_MB_2U_LIB.S9S_MB_2U(SCH_1):P5E_CPU0_PE2_RX_DP<13>
  EB10  P5E_CPU0_PE2_RX_DP<12>  PE2_RX_DP12  @S9S_MB_2U_LIB.S9S_MB_2U(SCH_1):P5E_CPU0_PE2_RX_DP<12>
  DW11  P5E_CPU0_PE2_RX_DP<11>  PE2_RX_DP11  @S9S_MB_2U_LIB.S9S_MB_2U(SCH_1):P5E_CPU0_PE2_RX_DP<11>
  DV10  P5E_CPU0_PE2_RX_DP<10>  PE2_RX_DP10  @S9S_MB_2U_LIB.S9S_MB_2U(SCH_1):P5E_CPU0_PE2_RX_DP<10>
  CV10  P5E_CPU0_PE2_RX_DP<0>  PE2_RX_DP0  @S9S_MB_2U_LIB.S9S_MB_2U(SCH_1):P5E_CPU0_PE2_RX_DP<0>
  DT10  P5E_CPU0_PE2_RX_DN<9>  PE2_RX_DN9  @S9S_MB_2U_LIB.S9S_MB_2U(SCH_1):P5E_CPU0_PE2_RX_DN<9>
  DN9  P5E_CPU0_PE2_RX_DN<8>  PE2_RX_DN8  @S9S_MB_2U_LIB.S9S_MB_2U(SCH_1):P5E_CPU0_PE2_RX_DN<8>
  DM10  P5E_CPU0_PE2_RX_DN<7>  PE2_RX_DN7  @S9S_MB_2U_LIB.S9S_MB_2U(SCH_1):P5E_CPU0_PE2_RX_DN<7>
  DJ9  P5E_CPU0_PE2_RX_DN<6>  PE2_RX_DN6  @S9S_MB_2U_LIB.S9S_MB_2U(SCH_1):P5E_CPU0_PE2_RX_DN<6>
  DH10  P5E_CPU0_PE2_RX_DN<5>  PE2_RX_DN5  @S9S_MB_2U_LIB.S9S_MB_2U(SCH_1):P5E_CPU0_PE2_RX_DN<5>
  DE9  P5E_CPU0_PE2_RX_DN<4>  PE2_RX_DN4  @S9S_MB_2U_LIB.S9S_MB_2U(SCH_1):P5E_CPU0_PE2_RX_DN<4>
  DD10  P5E_CPU0_PE2_RX_DN<3>  PE2_RX_DN3  @S9S_MB_2U_LIB.S9S_MB_2U(SCH_1):P5E_CPU0_PE2_RX_DN<3>
  DA9  P5E_CPU0_PE2_RX_DN<2>  PE2_RX_DN2  @S9S_MB_2U_LIB.S9S_MB_2U(SCH_1):P5E_CPU0_PE2_RX_DN<2>
  CY10  P5E_CPU0_PE2_RX_DN<1>  PE2_RX_DN1  @S9S_MB_2U_LIB.S9S_MB_2U(SCH_1):P5E_CPU0_PE2_RX_DN<1>
  EH10  P5E_CPU0_PE2_RX_DN<15>  PE2_RX_DN15  @S9S_MB_2U_LIB.S9S_MB_2U(SCH_1):P5E_CPU0_PE2_RX_DN<15>
  EE9  P5E_CPU0_PE2_RX_DN<14>  PE2_RX_DN14  @S9S_MB_2U_LIB.S9S_MB_2U(SCH_1):P5E_CPU0_PE2_RX_DN<14>
  ED10  P5E_CPU0_PE2_RX_DN<13>  PE2_RX_DN13  @S9S_MB_2U_LIB.S9S_MB_2U(SCH_1):P5E_CPU0_PE2_RX_DN<13>
  EA9  P5E_CPU0_PE2_RX_DN<12>  PE2_RX_DN12  @S9S_MB_2U_LIB.S9S_MB_2U(SCH_1):P5E_CPU0_PE2_RX_DN<12>
  DY10  P5E_CPU0_PE2_RX_DN<11>  PE2_RX_DN11  @S9S_MB_2U_LIB.S9S_MB_2U(SCH_1):P5E_CPU0_PE2_RX_DN<11>
  DU9  P5E_CPU0_PE2_RX_DN<10>  PE2_RX_DN10  @S9S_MB_2U_LIB.S9S_MB_2U(SCH_1):P5E_CPU0_PE2_RX_DN<10>
  CU9  P5E_CPU0_PE2_RX_DN<0>  PE2_RX_DN0  @S9S_MB_2U_LIB.S9S_MB_2U(SCH_1):P5E_CPU0_PE2_RX_DN<0>

SOCKET4677_AZIFS054P001C01  I176  U2     [SOCKET4677_AZIFS054P001C01-SOCA]
  BT14  P5E_CPU0_PE1_TX_DP<9>  PE1_TX_DP9  @S9S_MB_2U_LIB.S9S_MB_2U(SCH_1):P5E_CPU0_PE1_TX_DP<9>
  BW15  P5E_CPU0_PE1_TX_DP<8>  PE1_TX_DP8  @S9S_MB_2U_LIB.S9S_MB_2U(SCH_1):P5E_CPU0_PE1_TX_DP<8>
  BY14  P5E_CPU0_PE1_TX_DP<7>  PE1_TX_DP7  @S9S_MB_2U_LIB.S9S_MB_2U(SCH_1):P5E_CPU0_PE1_TX_DP<7>
  CC15  P5E_CPU0_PE1_TX_DP<6>  PE1_TX_DP6  @S9S_MB_2U_LIB.S9S_MB_2U(SCH_1):P5E_CPU0_PE1_TX_DP<6>
  CD14  P5E_CPU0_PE1_TX_DP<5>  PE1_TX_DP5  @S9S_MB_2U_LIB.S9S_MB_2U(SCH_1):P5E_CPU0_PE1_TX_DP<5>
  CG15  P5E_CPU0_PE1_TX_DP<4>  PE1_TX_DP4  @S9S_MB_2U_LIB.S9S_MB_2U(SCH_1):P5E_CPU0_PE1_TX_DP<4>
  CH14  P5E_CPU0_PE1_TX_DP<3>  PE1_TX_DP3  @S9S_MB_2U_LIB.S9S_MB_2U(SCH_1):P5E_CPU0_PE1_TX_DP<3>
  CL15  P5E_CPU0_PE1_TX_DP<2>  PE1_TX_DP2  @S9S_MB_2U_LIB.S9S_MB_2U(SCH_1):P5E_CPU0_PE1_TX_DP<2>
  CM14  P5E_CPU0_PE1_TX_DP<1>  PE1_TX_DP1  @S9S_MB_2U_LIB.S9S_MB_2U(SCH_1):P5E_CPU0_PE1_TX_DP<1>
  BD14  P5E_CPU0_PE1_TX_DP<15>  PE1_TX_DP15  @S9S_MB_2U_LIB.S9S_MB_2U(SCH_1):P5E_CPU0_PE1_TX_DP<15>
  BG15  P5E_CPU0_PE1_TX_DP<14>  PE1_TX_DP14  @S9S_MB_2U_LIB.S9S_MB_2U(SCH_1):P5E_CPU0_PE1_TX_DP<14>
  BH14  P5E_CPU0_PE1_TX_DP<13>  PE1_TX_DP13  @S9S_MB_2U_LIB.S9S_MB_2U(SCH_1):P5E_CPU0_PE1_TX_DP<13>
  BL15  P5E_CPU0_PE1_TX_DP<12>  PE1_TX_DP12  @S9S_MB_2U_LIB.S9S_MB_2U(SCH_1):P5E_CPU0_PE1_TX_DP<12>
  BM14  P5E_CPU0_PE1_TX_DP<11>  PE1_TX_DP11  @S9S_MB_2U_LIB.S9S_MB_2U(SCH_1):P5E_CPU0_PE1_TX_DP<11>
  BR15  P5E_CPU0_PE1_TX_DP<10>  PE1_TX_DP10  @S9S_MB_2U_LIB.S9S_MB_2U(SCH_1):P5E_CPU0_PE1_TX_DP<10>
  CR15  P5E_CPU0_PE1_TX_DP<0>  PE1_TX_DP0  @S9S_MB_2U_LIB.S9S_MB_2U(SCH_1):P5E_CPU0_PE1_TX_DP<0>
  BU13  P5E_CPU0_PE1_TX_DN<9>  PE1_TX_DN9  @S9S_MB_2U_LIB.S9S_MB_2U(SCH_1):P5E_CPU0_PE1_TX_DN<9>
  BV14  P5E_CPU0_PE1_TX_DN<8>  PE1_TX_DN8  @S9S_MB_2U_LIB.S9S_MB_2U(SCH_1):P5E_CPU0_PE1_TX_DN<8>
  CA13  P5E_CPU0_PE1_TX_DN<7>  PE1_TX_DN7  @S9S_MB_2U_LIB.S9S_MB_2U(SCH_1):P5E_CPU0_PE1_TX_DN<7>
  CB14  P5E_CPU0_PE1_TX_DN<6>  PE1_TX_DN6  @S9S_MB_2U_LIB.S9S_MB_2U(SCH_1):P5E_CPU0_PE1_TX_DN<6>
  CE13  P5E_CPU0_PE1_TX_DN<5>  PE1_TX_DN5  @S9S_MB_2U_LIB.S9S_MB_2U(SCH_1):P5E_CPU0_PE1_TX_DN<5>
  CF14  P5E_CPU0_PE1_TX_DN<4>  PE1_TX_DN4  @S9S_MB_2U_LIB.S9S_MB_2U(SCH_1):P5E_CPU0_PE1_TX_DN<4>
  CJ13  P5E_CPU0_PE1_TX_DN<3>  PE1_TX_DN3  @S9S_MB_2U_LIB.S9S_MB_2U(SCH_1):P5E_CPU0_PE1_TX_DN<3>
  CK14  P5E_CPU0_PE1_TX_DN<2>  PE1_TX_DN2  @S9S_MB_2U_LIB.S9S_MB_2U(SCH_1):P5E_CPU0_PE1_TX_DN<2>
  CN13  P5E_CPU0_PE1_TX_DN<1>  PE1_TX_DN1  @S9S_MB_2U_LIB.S9S_MB_2U(SCH_1):P5E_CPU0_PE1_TX_DN<1>
  BE13  P5E_CPU0_PE1_TX_DN<15>  PE1_TX_DN15  @S9S_MB_2U_LIB.S9S_MB_2U(SCH_1):P5E_CPU0_PE1_TX_DN<15>
  BF14  P5E_CPU0_PE1_TX_DN<14>  PE1_TX_DN14  @S9S_MB_2U_LIB.S9S_MB_2U(SCH_1):P5E_CPU0_PE1_TX_DN<14>
  BJ13  P5E_CPU0_PE1_TX_DN<13>  PE1_TX_DN13  @S9S_MB_2U_LIB.S9S_MB_2U(SCH_1):P5E_CPU0_PE1_TX_DN<13>
  BK14  P5E_CPU0_PE1_TX_DN<12>  PE1_TX_DN12  @S9S_MB_2U_LIB.S9S_MB_2U(SCH_1):P5E_CPU0_PE1_TX_DN<12>
  BN13  P5E_CPU0_PE1_TX_DN<11>  PE1_TX_DN11  @S9S_MB_2U_LIB.S9S_MB_2U(SCH_1):P5E_CPU0_PE1_TX_DN<11>
  BP14  P5E_CPU0_PE1_TX_DN<10>  PE1_TX_DN10  @S9S_MB_2U_LIB.S9S_MB_2U(SCH_1):P5E_CPU0_PE1_TX_DN<10>
  CP14  P5E_CPU0_PE1_TX_DN<0>  PE1_TX_DN0  @S9S_MB_2U_LIB.S9S_MB_2U(SCH_1):P5E_CPU0_PE1_TX_DN<0>
  BR11  P5E_CPU0_PE1_RX_DP<9>  PE1_RX_DN9  @S9S_MB_2U_LIB.S9S_MB_2U(SCH_1):P5E_CPU0_PE1_RX_DP<9>
  BV10  P5E_CPU0_PE1_RX_DP<8>  PE1_RX_DN8  @S9S_MB_2U_LIB.S9S_MB_2U(SCH_1):P5E_CPU0_PE1_RX_DP<8>
  BW11  P5E_CPU0_PE1_RX_DP<7>  PE1_RX_DN7  @S9S_MB_2U_LIB.S9S_MB_2U(SCH_1):P5E_CPU0_PE1_RX_DP<7>
  CB10  P5E_CPU0_PE1_RX_DP<6>  PE1_RX_DN6  @S9S_MB_2U_LIB.S9S_MB_2U(SCH_1):P5E_CPU0_PE1_RX_DP<6>
  CC11  P5E_CPU0_PE1_RX_DP<5>  PE1_RX_DN5  @S9S_MB_2U_LIB.S9S_MB_2U(SCH_1):P5E_CPU0_PE1_RX_DP<5>
  CF10  P5E_CPU0_PE1_RX_DP<4>  PE1_RX_DN4  @S9S_MB_2U_LIB.S9S_MB_2U(SCH_1):P5E_CPU0_PE1_RX_DP<4>
  CG11  P5E_CPU0_PE1_RX_DP<3>  PE1_RX_DN3  @S9S_MB_2U_LIB.S9S_MB_2U(SCH_1):P5E_CPU0_PE1_RX_DP<3>
  CK10  P5E_CPU0_PE1_RX_DP<2>  PE1_RX_DN2  @S9S_MB_2U_LIB.S9S_MB_2U(SCH_1):P5E_CPU0_PE1_RX_DP<2>
  CL11  P5E_CPU0_PE1_RX_DP<1>  PE1_RX_DN1  @S9S_MB_2U_LIB.S9S_MB_2U(SCH_1):P5E_CPU0_PE1_RX_DP<1>
  BC11  P5E_CPU0_PE1_RX_DP<15>  PE1_RX_DN15  @S9S_MB_2U_LIB.S9S_MB_2U(SCH_1):P5E_CPU0_PE1_RX_DP<15>
  BF10  P5E_CPU0_PE1_RX_DP<14>  PE1_RX_DN14  @S9S_MB_2U_LIB.S9S_MB_2U(SCH_1):P5E_CPU0_PE1_RX_DP<14>
  BG11  P5E_CPU0_PE1_RX_DP<13>  PE1_RX_DN13  @S9S_MB_2U_LIB.S9S_MB_2U(SCH_1):P5E_CPU0_PE1_RX_DP<13>
  BK10  P5E_CPU0_PE1_RX_DP<12>  PE1_RX_DN12  @S9S_MB_2U_LIB.S9S_MB_2U(SCH_1):P5E_CPU0_PE1_RX_DP<12>
  BL11  P5E_CPU0_PE1_RX_DP<11>  PE1_RX_DN11  @S9S_MB_2U_LIB.S9S_MB_2U(SCH_1):P5E_CPU0_PE1_RX_DP<11>
  BP10  P5E_CPU0_PE1_RX_DP<10>  PE1_RX_DN10  @S9S_MB_2U_LIB.S9S_MB_2U(SCH_1):P5E_CPU0_PE1_RX_DP<10>
  CP10  P5E_CPU0_PE1_RX_DP<0>  PE1_RX_DN0  @S9S_MB_2U_LIB.S9S_MB_2U(SCH_1):P5E_CPU0_PE1_RX_DP<0>
  BT10  P5E_CPU0_PE1_RX_DN<9>  PE1_RX_DP9  @S9S_MB_2U_LIB.S9S_MB_2U(SCH_1):P5E_CPU0_PE1_RX_DN<9>
  BU9  P5E_CPU0_PE1_RX_DN<8>  PE1_RX_DP8  @S9S_MB_2U_LIB.S9S_MB_2U(SCH_1):P5E_CPU0_PE1_RX_DN<8>
  BY10  P5E_CPU0_PE1_RX_DN<7>  PE1_RX_DP7  @S9S_MB_2U_LIB.S9S_MB_2U(SCH_1):P5E_CPU0_PE1_RX_DN<7>
  CA9  P5E_CPU0_PE1_RX_DN<6>  PE1_RX_DP6  @S9S_MB_2U_LIB.S9S_MB_2U(SCH_1):P5E_CPU0_PE1_RX_DN<6>
  CD10  P5E_CPU0_PE1_RX_DN<5>  PE1_RX_DP5  @S9S_MB_2U_LIB.S9S_MB_2U(SCH_1):P5E_CPU0_PE1_RX_DN<5>
  CE9  P5E_CPU0_PE1_RX_DN<4>  PE1_RX_DP4  @S9S_MB_2U_LIB.S9S_MB_2U(SCH_1):P5E_CPU0_PE1_RX_DN<4>
  CH10  P5E_CPU0_PE1_RX_DN<3>  PE1_RX_DP3  @S9S_MB_2U_LIB.S9S_MB_2U(SCH_1):P5E_CPU0_PE1_RX_DN<3>
  CJ9  P5E_CPU0_PE1_RX_DN<2>  PE1_RX_DP2  @S9S_MB_2U_LIB.S9S_MB_2U(SCH_1):P5E_CPU0_PE1_RX_DN<2>
  CM10  P5E_CPU0_PE1_RX_DN<1>  PE1_RX_DP1  @S9S_MB_2U_LIB.S9S_MB_2U(SCH_1):P5E_CPU0_PE1_RX_DN<1>
  BD10  P5E_CPU0_PE1_RX_DN<15>  PE1_RX_DP15  @S9S_MB_2U_LIB.S9S_MB_2U(SCH_1):P5E_CPU0_PE1_RX_DN<15>
  BE9  P5E_CPU0_PE1_RX_DN<14>  PE1_RX_DP14  @S9S_MB_2U_LIB.S9S_MB_2U(SCH_1):P5E_CPU0_PE1_RX_DN<14>
  BH10  P5E_CPU0_PE1_RX_DN<13>  PE1_RX_DP13  @S9S_MB_2U_LIB.S9S_MB_2U(SCH_1):P5E_CPU0_PE1_RX_DN<13>
  BJ9  P5E_CPU0_PE1_RX_DN<12>  PE1_RX_DP12  @S9S_MB_2U_LIB.S9S_MB_2U(SCH_1):P5E_CPU0_PE1_RX_DN<12>
  BM10  P5E_CPU0_PE1_RX_DN<11>  PE1_RX_DP11  @S9S_MB_2U_LIB.S9S_MB_2U(SCH_1):P5E_CPU0_PE1_RX_DN<11>
  BN9  P5E_CPU0_PE1_RX_DN<10>  PE1_RX_DP10  @S9S_MB_2U_LIB.S9S_MB_2U(SCH_1):P5E_CPU0_PE1_RX_DN<10>
  CN9  P5E_CPU0_PE1_RX_DN<0>  PE1_RX_DP0  @S9S_MB_2U_LIB.S9S_MB_2U(SCH_1):P5E_CPU0_PE1_RX_DN<0>

SOCKET4677_AZIFS054P001C01  I37  U2     [SOCKET4677_AZIFS054P001C01-SOCA]
  AD14  P5E_CPU0_PE0_TX_DP<9>  PE0_TX_DP6  @S9S_MB_2U_LIB.S9S_MB_2U(SCH_1):P5E_CPU0_PE0_TX_DP<9>
  AG15  P5E_CPU0_PE0_TX_DP<8>  PE0_TX_DP7  @S9S_MB_2U_LIB.S9S_MB_2U(SCH_1):P5E_CPU0_PE0_TX_DP<8>
  AH14  P5E_CPU0_PE0_TX_DP<7>  PE0_TX_DP8  @S9S_MB_2U_LIB.S9S_MB_2U(SCH_1):P5E_CPU0_PE0_TX_DP<7>
  AL15  P5E_CPU0_PE0_TX_DP<6>  PE0_TX_DP9  @S9S_MB_2U_LIB.S9S_MB_2U(SCH_1):P5E_CPU0_PE0_TX_DP<6>
  AM14  P5E_CPU0_PE0_TX_DP<5>  PE0_TX_DP10  @S9S_MB_2U_LIB.S9S_MB_2U(SCH_1):P5E_CPU0_PE0_TX_DP<5>
  AR15  P5E_CPU0_PE0_TX_DP<4>  PE0_TX_DP11  @S9S_MB_2U_LIB.S9S_MB_2U(SCH_1):P5E_CPU0_PE0_TX_DP<4>
  AT14  P5E_CPU0_PE0_TX_DP<3>  PE0_TX_DP12  @S9S_MB_2U_LIB.S9S_MB_2U(SCH_1):P5E_CPU0_PE0_TX_DP<3>
  AW15  P5E_CPU0_PE0_TX_DP<2>  PE0_TX_DP13  @S9S_MB_2U_LIB.S9S_MB_2U(SCH_1):P5E_CPU0_PE0_TX_DP<2>
  AY14  P5E_CPU0_PE0_TX_DP<1>  PE0_TX_DP14  @S9S_MB_2U_LIB.S9S_MB_2U(SCH_1):P5E_CPU0_PE0_TX_DP<1>
  M14  P5E_CPU0_PE0_TX_DP<15>  PE0_TX_DP0  @S9S_MB_2U_LIB.S9S_MB_2U(SCH_1):P5E_CPU0_PE0_TX_DP<15>
  R15  P5E_CPU0_PE0_TX_DP<14>  PE0_TX_DP1  @S9S_MB_2U_LIB.S9S_MB_2U(SCH_1):P5E_CPU0_PE0_TX_DP<14>
  T14  P5E_CPU0_PE0_TX_DP<13>  PE0_TX_DP2  @S9S_MB_2U_LIB.S9S_MB_2U(SCH_1):P5E_CPU0_PE0_TX_DP<13>
  W15  P5E_CPU0_PE0_TX_DP<12>  PE0_TX_DP3  @S9S_MB_2U_LIB.S9S_MB_2U(SCH_1):P5E_CPU0_PE0_TX_DP<12>
  Y14  P5E_CPU0_PE0_TX_DP<11>  PE0_TX_DP4  @S9S_MB_2U_LIB.S9S_MB_2U(SCH_1):P5E_CPU0_PE0_TX_DP<11>
  AC15  P5E_CPU0_PE0_TX_DP<10>  PE0_TX_DP5  @S9S_MB_2U_LIB.S9S_MB_2U(SCH_1):P5E_CPU0_PE0_TX_DP<10>
  BC15  P5E_CPU0_PE0_TX_DP<0>  PE0_TX_DP15  @S9S_MB_2U_LIB.S9S_MB_2U(SCH_1):P5E_CPU0_PE0_TX_DP<0>
  AE13  P5E_CPU0_PE0_TX_DN<9>  PE0_TX_DN6  @S9S_MB_2U_LIB.S9S_MB_2U(SCH_1):P5E_CPU0_PE0_TX_DN<9>
  AF14  P5E_CPU0_PE0_TX_DN<8>  PE0_TX_DN7  @S9S_MB_2U_LIB.S9S_MB_2U(SCH_1):P5E_CPU0_PE0_TX_DN<8>
  AJ13  P5E_CPU0_PE0_TX_DN<7>  PE0_TX_DN8  @S9S_MB_2U_LIB.S9S_MB_2U(SCH_1):P5E_CPU0_PE0_TX_DN<7>
  AK14  P5E_CPU0_PE0_TX_DN<6>  PE0_TX_DN9  @S9S_MB_2U_LIB.S9S_MB_2U(SCH_1):P5E_CPU0_PE0_TX_DN<6>
  AN13  P5E_CPU0_PE0_TX_DN<5>  PE0_TX_DN10  @S9S_MB_2U_LIB.S9S_MB_2U(SCH_1):P5E_CPU0_PE0_TX_DN<5>
  AP14  P5E_CPU0_PE0_TX_DN<4>  PE0_TX_DN11  @S9S_MB_2U_LIB.S9S_MB_2U(SCH_1):P5E_CPU0_PE0_TX_DN<4>
  AU13  P5E_CPU0_PE0_TX_DN<3>  PE0_TX_DN12  @S9S_MB_2U_LIB.S9S_MB_2U(SCH_1):P5E_CPU0_PE0_TX_DN<3>
  AV14  P5E_CPU0_PE0_TX_DN<2>  PE0_TX_DN13  @S9S_MB_2U_LIB.S9S_MB_2U(SCH_1):P5E_CPU0_PE0_TX_DN<2>
  BA13  P5E_CPU0_PE0_TX_DN<1>  PE0_TX_DN14  @S9S_MB_2U_LIB.S9S_MB_2U(SCH_1):P5E_CPU0_PE0_TX_DN<1>
  N13  P5E_CPU0_PE0_TX_DN<15>  PE0_TX_DN0  @S9S_MB_2U_LIB.S9S_MB_2U(SCH_1):P5E_CPU0_PE0_TX_DN<15>
  P14  P5E_CPU0_PE0_TX_DN<14>  PE0_TX_DN1  @S9S_MB_2U_LIB.S9S_MB_2U(SCH_1):P5E_CPU0_PE0_TX_DN<14>
  U13  P5E_CPU0_PE0_TX_DN<13>  PE0_TX_DN2  @S9S_MB_2U_LIB.S9S_MB_2U(SCH_1):P5E_CPU0_PE0_TX_DN<13>
  V14  P5E_CPU0_PE0_TX_DN<12>  PE0_TX_DN3  @S9S_MB_2U_LIB.S9S_MB_2U(SCH_1):P5E_CPU0_PE0_TX_DN<12>
  AA13  P5E_CPU0_PE0_TX_DN<11>  PE0_TX_DN4  @S9S_MB_2U_LIB.S9S_MB_2U(SCH_1):P5E_CPU0_PE0_TX_DN<11>
  AB14  P5E_CPU0_PE0_TX_DN<10>  PE0_TX_DN5  @S9S_MB_2U_LIB.S9S_MB_2U(SCH_1):P5E_CPU0_PE0_TX_DN<10>
  BB14  P5E_CPU0_PE0_TX_DN<0>  PE0_TX_DN15  @S9S_MB_2U_LIB.S9S_MB_2U(SCH_1):P5E_CPU0_PE0_TX_DN<0>
  AC11  P5E_CPU0_PE0_RX_DP<9>  PE0_RX_DP6  @S9S_MB_2U_LIB.S9S_MB_2U(SCH_1):P5E_CPU0_PE0_RX_DP<9>
  AD10  P5E_CPU0_PE0_RX_DP<8>  PE0_RX_DP7  @S9S_MB_2U_LIB.S9S_MB_2U(SCH_1):P5E_CPU0_PE0_RX_DP<8>
  AG11  P5E_CPU0_PE0_RX_DP<7>  PE0_RX_DP8  @S9S_MB_2U_LIB.S9S_MB_2U(SCH_1):P5E_CPU0_PE0_RX_DP<7>
  AH10  P5E_CPU0_PE0_RX_DP<6>  PE0_RX_DP9  @S9S_MB_2U_LIB.S9S_MB_2U(SCH_1):P5E_CPU0_PE0_RX_DP<6>
  AL11  P5E_CPU0_PE0_RX_DP<5>  PE0_RX_DP10  @S9S_MB_2U_LIB.S9S_MB_2U(SCH_1):P5E_CPU0_PE0_RX_DP<5>
  AN9  P5E_CPU0_PE0_RX_DP<4>  PE0_RX_DP11  @S9S_MB_2U_LIB.S9S_MB_2U(SCH_1):P5E_CPU0_PE0_RX_DP<4>
  AR11  P5E_CPU0_PE0_RX_DP<3>  PE0_RX_DP12  @S9S_MB_2U_LIB.S9S_MB_2U(SCH_1):P5E_CPU0_PE0_RX_DP<3>
  AT10  P5E_CPU0_PE0_RX_DP<2>  PE0_RX_DP13  @S9S_MB_2U_LIB.S9S_MB_2U(SCH_1):P5E_CPU0_PE0_RX_DP<2>
  AW11  P5E_CPU0_PE0_RX_DP<1>  PE0_RX_DP14  @S9S_MB_2U_LIB.S9S_MB_2U(SCH_1):P5E_CPU0_PE0_RX_DP<1>
  L11  P5E_CPU0_PE0_RX_DP<15>  PE0_RX_DP0  @S9S_MB_2U_LIB.S9S_MB_2U(SCH_1):P5E_CPU0_PE0_RX_DP<15>
   N9  P5E_CPU0_PE0_RX_DP<14>  PE0_RX_DP1  @S9S_MB_2U_LIB.S9S_MB_2U(SCH_1):P5E_CPU0_PE0_RX_DP<14>
  R11  P5E_CPU0_PE0_RX_DP<13>  PE0_RX_DP2  @S9S_MB_2U_LIB.S9S_MB_2U(SCH_1):P5E_CPU0_PE0_RX_DP<13>
   U9  P5E_CPU0_PE0_RX_DP<12>  PE0_RX_DP3  @S9S_MB_2U_LIB.S9S_MB_2U(SCH_1):P5E_CPU0_PE0_RX_DP<12>
  W11  P5E_CPU0_PE0_RX_DP<11>  PE0_RX_DP4  @S9S_MB_2U_LIB.S9S_MB_2U(SCH_1):P5E_CPU0_PE0_RX_DP<11>
  Y10  P5E_CPU0_PE0_RX_DP<10>  PE0_RX_DP5  @S9S_MB_2U_LIB.S9S_MB_2U(SCH_1):P5E_CPU0_PE0_RX_DP<10>
  AY10  P5E_CPU0_PE0_RX_DP<0>  PE0_RX_DP15  @S9S_MB_2U_LIB.S9S_MB_2U(SCH_1):P5E_CPU0_PE0_RX_DP<0>
  AB10  P5E_CPU0_PE0_RX_DN<9>  PE0_RX_DN6  @S9S_MB_2U_LIB.S9S_MB_2U(SCH_1):P5E_CPU0_PE0_RX_DN<9>
  AE9  P5E_CPU0_PE0_RX_DN<8>  PE0_RX_DN7  @S9S_MB_2U_LIB.S9S_MB_2U(SCH_1):P5E_CPU0_PE0_RX_DN<8>
  AF10  P5E_CPU0_PE0_RX_DN<7>  PE0_RX_DN8  @S9S_MB_2U_LIB.S9S_MB_2U(SCH_1):P5E_CPU0_PE0_RX_DN<7>
  AJ9  P5E_CPU0_PE0_RX_DN<6>  PE0_RX_DN9  @S9S_MB_2U_LIB.S9S_MB_2U(SCH_1):P5E_CPU0_PE0_RX_DN<6>
  AK10  P5E_CPU0_PE0_RX_DN<5>  PE0_RX_DN10  @S9S_MB_2U_LIB.S9S_MB_2U(SCH_1):P5E_CPU0_PE0_RX_DN<5>
  AM10  P5E_CPU0_PE0_RX_DN<4>  PE0_RX_DN11  @S9S_MB_2U_LIB.S9S_MB_2U(SCH_1):P5E_CPU0_PE0_RX_DN<4>
  AP10  P5E_CPU0_PE0_RX_DN<3>  PE0_RX_DN12  @S9S_MB_2U_LIB.S9S_MB_2U(SCH_1):P5E_CPU0_PE0_RX_DN<3>
  AU9  P5E_CPU0_PE0_RX_DN<2>  PE0_RX_DN13  @S9S_MB_2U_LIB.S9S_MB_2U(SCH_1):P5E_CPU0_PE0_RX_DN<2>
  AV10  P5E_CPU0_PE0_RX_DN<1>  PE0_RX_DN14  @S9S_MB_2U_LIB.S9S_MB_2U(SCH_1):P5E_CPU0_PE0_RX_DN<1>
  K10  P5E_CPU0_PE0_RX_DN<15>  PE0_RX_DN0  @S9S_MB_2U_LIB.S9S_MB_2U(SCH_1):P5E_CPU0_PE0_RX_DN<15>
  M10  P5E_CPU0_PE0_RX_DN<14>  PE0_RX_DN1  @S9S_MB_2U_LIB.S9S_MB_2U(SCH_1):P5E_CPU0_PE0_RX_DN<14>
  P10  P5E_CPU0_PE0_RX_DN<13>  PE0_RX_DN2  @S9S_MB_2U_LIB.S9S_MB_2U(SCH_1):P5E_CPU0_PE0_RX_DN<13>
  T10  P5E_CPU0_PE0_RX_DN<12>  PE0_RX_DN3  @S9S_MB_2U_LIB.S9S_MB_2U(SCH_1):P5E_CPU0_PE0_RX_DN<12>
  V10  P5E_CPU0_PE0_RX_DN<11>  PE0_RX_DN4  @S9S_MB_2U_LIB.S9S_MB_2U(SCH_1):P5E_CPU0_PE0_RX_DN<11>
  AA9  P5E_CPU0_PE0_RX_DN<10>  PE0_RX_DN5  @S9S_MB_2U_LIB.S9S_MB_2U(SCH_1):P5E_CPU0_PE0_RX_DN<10>
  BA9  P5E_CPU0_PE0_RX_DN<0>  PE0_RX_DN15  @S9S_MB_2U_LIB.S9S_MB_2U(SCH_1):P5E_CPU0_PE0_RX_DN<0>

SOCKET4677_AZIFS054P001C01  I169  U2     [SOCKET4677_AZIFS054P001C01-SOCA]
  CN17  DMI_CPU0_PCH_TX_DP<7>  DMI_TX_DN7  @S9S_MB_2U_LIB.S9S_MB_2U(SCH_1):DMI_CPU0_PCH_TX_DP<7>
  CK18  DMI_CPU0_PCH_TX_DP<6>  DMI_TX_DN6  @S9S_MB_2U_LIB.S9S_MB_2U(SCH_1):DMI_CPU0_PCH_TX_DP<6>
  CH18  DMI_CPU0_PCH_TX_DP<5>  DMI_TX_DP5  @S9S_MB_2U_LIB.S9S_MB_2U(SCH_1):DMI_CPU0_PCH_TX_DP<5>
  CG19  DMI_CPU0_PCH_TX_DP<4>  DMI_TX_DP4  @S9S_MB_2U_LIB.S9S_MB_2U(SCH_1):DMI_CPU0_PCH_TX_DP<4>
  CD18  DMI_CPU0_PCH_TX_DP<3>  DMI_TX_DP3  @S9S_MB_2U_LIB.S9S_MB_2U(SCH_1):DMI_CPU0_PCH_TX_DP<3>
  CB18  DMI_CPU0_PCH_TX_DP<2>  DMI_TX_DN2  @S9S_MB_2U_LIB.S9S_MB_2U(SCH_1):DMI_CPU0_PCH_TX_DP<2>
  CA17  DMI_CPU0_PCH_TX_DP<1>  DMI_TX_DN1  @S9S_MB_2U_LIB.S9S_MB_2U(SCH_1):DMI_CPU0_PCH_TX_DP<1>
  BW19  DMI_CPU0_PCH_TX_DP<0>  DMI_TX_DN0  @S9S_MB_2U_LIB.S9S_MB_2U(SCH_1):DMI_CPU0_PCH_TX_DP<0>
  CM18  DMI_CPU0_PCH_TX_DN<7>  DMI_TX_DP7  @S9S_MB_2U_LIB.S9S_MB_2U(SCH_1):DMI_CPU0_PCH_TX_DN<7>
  CL19  DMI_CPU0_PCH_TX_DN<6>  DMI_TX_DP6  @S9S_MB_2U_LIB.S9S_MB_2U(SCH_1):DMI_CPU0_PCH_TX_DN<6>
  CJ17  DMI_CPU0_PCH_TX_DN<5>  DMI_TX_DN5  @S9S_MB_2U_LIB.S9S_MB_2U(SCH_1):DMI_CPU0_PCH_TX_DN<5>
  CF18  DMI_CPU0_PCH_TX_DN<4>  DMI_TX_DN4  @S9S_MB_2U_LIB.S9S_MB_2U(SCH_1):DMI_CPU0_PCH_TX_DN<4>
  CE17  DMI_CPU0_PCH_TX_DN<3>  DMI_TX_DN3  @S9S_MB_2U_LIB.S9S_MB_2U(SCH_1):DMI_CPU0_PCH_TX_DN<3>
  CC19  DMI_CPU0_PCH_TX_DN<2>  DMI_TX_DP2  @S9S_MB_2U_LIB.S9S_MB_2U(SCH_1):DMI_CPU0_PCH_TX_DN<2>
  BY18  DMI_CPU0_PCH_TX_DN<1>  DMI_TX_DP1  @S9S_MB_2U_LIB.S9S_MB_2U(SCH_1):DMI_CPU0_PCH_TX_DN<1>
  CA19  DMI_CPU0_PCH_TX_DN<0>  DMI_TX_DP0  @S9S_MB_2U_LIB.S9S_MB_2U(SCH_1):DMI_CPU0_PCH_TX_DN<0>
  BT18  DMI_CPU0_PCH_RX_C_DP<7>  DMI_RX_DP7  @S9S_MB_2U_LIB.S9S_MB_2U(SCH_1):DMI_CPU0_PCH_RX_C_DP<7>
  BP18  DMI_CPU0_PCH_RX_C_DP<6>  DMI_RX_DN6  @S9S_MB_2U_LIB.S9S_MB_2U(SCH_1):DMI_CPU0_PCH_RX_C_DP<6>
  BN17  DMI_CPU0_PCH_RX_C_DP<5>  DMI_RX_DN5  @S9S_MB_2U_LIB.S9S_MB_2U(SCH_1):DMI_CPU0_PCH_RX_C_DP<5>
  BK18  DMI_CPU0_PCH_RX_C_DP<4>  DMI_RX_DN4  @S9S_MB_2U_LIB.S9S_MB_2U(SCH_1):DMI_CPU0_PCH_RX_C_DP<4>
  BJ17  DMI_CPU0_PCH_RX_C_DP<3>  DMI_RX_DN3  @S9S_MB_2U_LIB.S9S_MB_2U(SCH_1):DMI_CPU0_PCH_RX_C_DP<3>
  BG19  DMI_CPU0_PCH_RX_C_DP<2>  DMI_RX_DP2  @S9S_MB_2U_LIB.S9S_MB_2U(SCH_1):DMI_CPU0_PCH_RX_C_DP<2>
  BE17  DMI_CPU0_PCH_RX_C_DP<1>  DMI_RX_DN1  @S9S_MB_2U_LIB.S9S_MB_2U(SCH_1):DMI_CPU0_PCH_RX_C_DP<1>
  BC19  DMI_CPU0_PCH_RX_C_DP<0>  DMI_RX_DP0  @S9S_MB_2U_LIB.S9S_MB_2U(SCH_1):DMI_CPU0_PCH_RX_C_DP<0>
  BU17  DMI_CPU0_PCH_RX_C_DN<7>  DMI_RX_DN7  @S9S_MB_2U_LIB.S9S_MB_2U(SCH_1):DMI_CPU0_PCH_RX_C_DN<7>
  BR19  DMI_CPU0_PCH_RX_C_DN<6>  DMI_RX_DP6  @S9S_MB_2U_LIB.S9S_MB_2U(SCH_1):DMI_CPU0_PCH_RX_C_DN<6>
  BM18  DMI_CPU0_PCH_RX_C_DN<5>  DMI_RX_DP5  @S9S_MB_2U_LIB.S9S_MB_2U(SCH_1):DMI_CPU0_PCH_RX_C_DN<5>
  BL19  DMI_CPU0_PCH_RX_C_DN<4>  DMI_RX_DP4  @S9S_MB_2U_LIB.S9S_MB_2U(SCH_1):DMI_CPU0_PCH_RX_C_DN<4>
  BH18  DMI_CPU0_PCH_RX_C_DN<3>  DMI_RX_DP3  @S9S_MB_2U_LIB.S9S_MB_2U(SCH_1):DMI_CPU0_PCH_RX_C_DN<3>
  BF18  DMI_CPU0_PCH_RX_C_DN<2>  DMI_RX_DN2  @S9S_MB_2U_LIB.S9S_MB_2U(SCH_1):DMI_CPU0_PCH_RX_C_DN<2>
  BD18  DMI_CPU0_PCH_RX_C_DN<1>  DMI_RX_DP1  @S9S_MB_2U_LIB.S9S_MB_2U(SCH_1):DMI_CPU0_PCH_RX_C_DN<1>
  BB18  DMI_CPU0_PCH_RX_C_DN<0>  DMI_RX_DN0  @S9S_MB_2U_LIB.S9S_MB_2U(SCH_1):DMI_CPU0_PCH_RX_C_DN<0>

SOCKET4677_AZIFS054P001C01  I169  U2     [SOCKET4677_AZIFS054P001C01-SOCA]
  ED47  M_H_CPU0_SB_RSP<1>  DDR7_B_RSP1  @S9S_MB_2U_LIB.S9S_MB_2U(SCH_1):M_H_CPU0_SB_RSP<1>
  EE48  M_H_CPU0_SB_RSP<0>  DDR7_B_RSP0  @S9S_MB_2U_LIB.S9S_MB_2U(SCH_1):M_H_CPU0_SB_RSP<0>
  DR39  M_H_CPU0_SB_PAR  DDR7_SB_PAR  @S9S_MB_2U_LIB.S9S_MB_2U(SCH_1):M_H_CPU0_SB_PAR
  DB36  M_H_CPU0_SB_DQS_DP<9>  DDR7_SB_DQS_DP9  @S9S_MB_2U_LIB.S9S_MB_2U(SCH_1):M_H_CPU0_SB_DQS_DP<9>
  DH18  M_H_CPU0_SB_DQS_DP<8>  DDR7_SB_DQS_DP8  @S9S_MB_2U_LIB.S9S_MB_2U(SCH_1):M_H_CPU0_SB_DQS_DP<8>
  DN21  M_H_CPU0_SB_DQS_DP<7>  DDR7_SB_DQS_DP7  @S9S_MB_2U_LIB.S9S_MB_2U(SCH_1):M_H_CPU0_SB_DQS_DP<7>
  DF24  M_H_CPU0_SB_DQS_DP<6>  DDR7_SB_DQS_DP6  @S9S_MB_2U_LIB.S9S_MB_2U(SCH_1):M_H_CPU0_SB_DQS_DP<6>
  DF30  M_H_CPU0_SB_DQS_DP<5>  DDR7_SB_DQS_DP5  @S9S_MB_2U_LIB.S9S_MB_2U(SCH_1):M_H_CPU0_SB_DQS_DP<5>
  DF36  M_H_CPU0_SB_DQS_DP<4>  DDR7_SB_DQS_DP4  @S9S_MB_2U_LIB.S9S_MB_2U(SCH_1):M_H_CPU0_SB_DQS_DP<4>
  DD18  M_H_CPU0_SB_DQS_DP<3>  DDR7_SB_DQS_DP3  @S9S_MB_2U_LIB.S9S_MB_2U(SCH_1):M_H_CPU0_SB_DQS_DP<3>
  DJ21  M_H_CPU0_SB_DQS_DP<2>  DDR7_SB_DQS_DP2  @S9S_MB_2U_LIB.S9S_MB_2U(SCH_1):M_H_CPU0_SB_DQS_DP<2>
  DB24  M_H_CPU0_SB_DQS_DP<1>  DDR7_SB_DQS_DP1  @S9S_MB_2U_LIB.S9S_MB_2U(SCH_1):M_H_CPU0_SB_DQS_DP<1>
  DB30  M_H_CPU0_SB_DQS_DP<0>  DDR7_SB_DQS_DP0  @S9S_MB_2U_LIB.S9S_MB_2U(SCH_1):M_H_CPU0_SB_DQS_DP<0>
  DD36  M_H_CPU0_SB_DQS_DN<9>  DDR7_SB_DQS_DN9  @S9S_MB_2U_LIB.S9S_MB_2U(SCH_1):M_H_CPU0_SB_DQS_DN<9>
  DF18  M_H_CPU0_SB_DQS_DN<8>  DDR7_SB_DQS_DN8  @S9S_MB_2U_LIB.S9S_MB_2U(SCH_1):M_H_CPU0_SB_DQS_DN<8>
  DR21  M_H_CPU0_SB_DQS_DN<7>  DDR7_SB_DQS_DN7  @S9S_MB_2U_LIB.S9S_MB_2U(SCH_1):M_H_CPU0_SB_DQS_DN<7>
  DH24  M_H_CPU0_SB_DQS_DN<6>  DDR7_SB_DQS_DN6  @S9S_MB_2U_LIB.S9S_MB_2U(SCH_1):M_H_CPU0_SB_DQS_DN<6>
  DH30  M_H_CPU0_SB_DQS_DN<5>  DDR7_SB_DQS_DN5  @S9S_MB_2U_LIB.S9S_MB_2U(SCH_1):M_H_CPU0_SB_DQS_DN<5>
  DH36  M_H_CPU0_SB_DQS_DN<4>  DDR7_SB_DQS_DN4  @S9S_MB_2U_LIB.S9S_MB_2U(SCH_1):M_H_CPU0_SB_DQS_DN<4>
  DB18  M_H_CPU0_SB_DQS_DN<3>  DDR7_SB_DQS_DN3  @S9S_MB_2U_LIB.S9S_MB_2U(SCH_1):M_H_CPU0_SB_DQS_DN<3>
  DL21  M_H_CPU0_SB_DQS_DN<2>  DDR7_SB_DQS_DN2  @S9S_MB_2U_LIB.S9S_MB_2U(SCH_1):M_H_CPU0_SB_DQS_DN<2>
  DD24  M_H_CPU0_SB_DQS_DN<1>  DDR7_SB_DQS_DN1  @S9S_MB_2U_LIB.S9S_MB_2U(SCH_1):M_H_CPU0_SB_DQS_DN<1>
  DD30  M_H_CPU0_SB_DQS_DN<0>  DDR7_SB_DQS_DN0  @S9S_MB_2U_LIB.S9S_MB_2U(SCH_1):M_H_CPU0_SB_DQS_DN<0>
  DC25  M_H_CPU0_SB_DQ<9>  DDR7_SB_DQ9  @S9S_MB_2U_LIB.S9S_MB_2U(SCH_1):M_H_CPU0_SB_DQ<9>
  DD26  M_H_CPU0_SB_DQ<8>  DDR7_SB_DQ8  @S9S_MB_2U_LIB.S9S_MB_2U(SCH_1):M_H_CPU0_SB_DQ<8>
  DD28  M_H_CPU0_SB_DQ<7>  DDR7_SB_DQ7  @S9S_MB_2U_LIB.S9S_MB_2U(SCH_1):M_H_CPU0_SB_DQ<7>
  DG29  M_H_CPU0_SB_DQ<6>  DDR7_SB_DQ6  @S9S_MB_2U_LIB.S9S_MB_2U(SCH_1):M_H_CPU0_SB_DQ<6>
  DF28  M_H_CPU0_SB_DQ<5>  DDR7_SB_DQ5  @S9S_MB_2U_LIB.S9S_MB_2U(SCH_1):M_H_CPU0_SB_DQ<5>
  DC29  M_H_CPU0_SB_DQ<4>  DDR7_SB_DQ4  @S9S_MB_2U_LIB.S9S_MB_2U(SCH_1):M_H_CPU0_SB_DQ<4>
  DG31  M_H_CPU0_SB_DQ<3>  DDR7_SB_DQ3  @S9S_MB_2U_LIB.S9S_MB_2U(SCH_1):M_H_CPU0_SB_DQ<3>
  DC17  M_H_CPU0_SB_DQ<31>  DDR7_SB_DQ31  @S9S_MB_2U_LIB.S9S_MB_2U(SCH_1):M_H_CPU0_SB_DQ<31>
  DJ17  M_H_CPU0_SB_DQ<30>  DDR7_SB_DQ30  @S9S_MB_2U_LIB.S9S_MB_2U(SCH_1):M_H_CPU0_SB_DQ<30>
  DF32  M_H_CPU0_SB_DQ<2>  DDR7_SB_DQ2  @S9S_MB_2U_LIB.S9S_MB_2U(SCH_1):M_H_CPU0_SB_DQ<2>
  DA17  M_H_CPU0_SB_DQ<29>  DDR7_SB_DQ29  @S9S_MB_2U_LIB.S9S_MB_2U(SCH_1):M_H_CPU0_SB_DQ<29>
  DG17  M_H_CPU0_SB_DQ<28>  DDR7_SB_DQ28  @S9S_MB_2U_LIB.S9S_MB_2U(SCH_1):M_H_CPU0_SB_DQ<28>
  DG19  M_H_CPU0_SB_DQ<27>  DDR7_SB_DQ27  @S9S_MB_2U_LIB.S9S_MB_2U(SCH_1):M_H_CPU0_SB_DQ<27>
  DF20  M_H_CPU0_SB_DQ<26>  DDR7_SB_DQ26  @S9S_MB_2U_LIB.S9S_MB_2U(SCH_1):M_H_CPU0_SB_DQ<26>
  DC19  M_H_CPU0_SB_DQ<25>  DDR7_SB_DQ25  @S9S_MB_2U_LIB.S9S_MB_2U(SCH_1):M_H_CPU0_SB_DQ<25>
  DD20  M_H_CPU0_SB_DQ<24>  DDR7_SB_DQ24  @S9S_MB_2U_LIB.S9S_MB_2U(SCH_1):M_H_CPU0_SB_DQ<24>
  DN19  M_H_CPU0_SB_DQ<23>  DDR7_SB_DQ23  @S9S_MB_2U_LIB.S9S_MB_2U(SCH_1):M_H_CPU0_SB_DQ<23>
  DP20  M_H_CPU0_SB_DQ<22>  DDR7_SB_DQ22  @S9S_MB_2U_LIB.S9S_MB_2U(SCH_1):M_H_CPU0_SB_DQ<22>
  DL19  M_H_CPU0_SB_DQ<21>  DDR7_SB_DQ21  @S9S_MB_2U_LIB.S9S_MB_2U(SCH_1):M_H_CPU0_SB_DQ<21>
  DK20  M_H_CPU0_SB_DQ<20>  DDR7_SB_DQ20  @S9S_MB_2U_LIB.S9S_MB_2U(SCH_1):M_H_CPU0_SB_DQ<20>
  DC31  M_H_CPU0_SB_DQ<1>  DDR7_SB_DQ1  @S9S_MB_2U_LIB.S9S_MB_2U(SCH_1):M_H_CPU0_SB_DQ<1>
  DP22  M_H_CPU0_SB_DQ<19>  DDR7_SB_DQ19  @S9S_MB_2U_LIB.S9S_MB_2U(SCH_1):M_H_CPU0_SB_DQ<19>
  DN23  M_H_CPU0_SB_DQ<18>  DDR7_SB_DQ18  @S9S_MB_2U_LIB.S9S_MB_2U(SCH_1):M_H_CPU0_SB_DQ<18>
  DK22  M_H_CPU0_SB_DQ<17>  DDR7_SB_DQ17  @S9S_MB_2U_LIB.S9S_MB_2U(SCH_1):M_H_CPU0_SB_DQ<17>
  DL23  M_H_CPU0_SB_DQ<16>  DDR7_SB_DQ16  @S9S_MB_2U_LIB.S9S_MB_2U(SCH_1):M_H_CPU0_SB_DQ<16>
  DF22  M_H_CPU0_SB_DQ<15>  DDR7_SB_DQ15  @S9S_MB_2U_LIB.S9S_MB_2U(SCH_1):M_H_CPU0_SB_DQ<15>
  DG23  M_H_CPU0_SB_DQ<14>  DDR7_SB_DQ14  @S9S_MB_2U_LIB.S9S_MB_2U(SCH_1):M_H_CPU0_SB_DQ<14>
  DD22  M_H_CPU0_SB_DQ<13>  DDR7_SB_DQ13  @S9S_MB_2U_LIB.S9S_MB_2U(SCH_1):M_H_CPU0_SB_DQ<13>
  DC23  M_H_CPU0_SB_DQ<12>  DDR7_SB_DQ12  @S9S_MB_2U_LIB.S9S_MB_2U(SCH_1):M_H_CPU0_SB_DQ<12>
  DG25  M_H_CPU0_SB_DQ<11>  DDR7_SB_DQ11  @S9S_MB_2U_LIB.S9S_MB_2U(SCH_1):M_H_CPU0_SB_DQ<11>
  DF26  M_H_CPU0_SB_DQ<10>  DDR7_SB_DQ10  @S9S_MB_2U_LIB.S9S_MB_2U(SCH_1):M_H_CPU0_SB_DQ<10>
  DD32  M_H_CPU0_SB_DQ<0>  DDR7_SB_DQ0  @S9S_MB_2U_LIB.S9S_MB_2U(SCH_1):M_H_CPU0_SB_DQ<0>
  DP38  M_H_CPU0_SB_CS_N<3>  DDR7_SB_CS3_N  @S9S_MB_2U_LIB.S9S_MB_2U(SCH_1):M_H_CPU0_SB_CS_N<3>
  DK38  M_H_CPU0_SB_CS_N<2>  DDR7_SB_CS2_N  @S9S_MB_2U_LIB.S9S_MB_2U(SCH_1):M_H_CPU0_SB_CS_N<2>
  DN37  M_H_CPU0_SB_CS_N<1>  DDR7_SB_CS1_N  @S9S_MB_2U_LIB.S9S_MB_2U(SCH_1):M_H_CPU0_SB_CS_N<1>
  DL37  M_H_CPU0_SB_CS_N<0>  DDR7_SB_CS0_N  @S9S_MB_2U_LIB.S9S_MB_2U(SCH_1):M_H_CPU0_SB_CS_N<0>
  DC37  M_H_CPU0_SB_CB<7>  DDR7_SB_ECC7  @S9S_MB_2U_LIB.S9S_MB_2U(SCH_1):M_H_CPU0_SB_CB<7>
  DD38  M_H_CPU0_SB_CB<6>  DDR7_SB_ECC6  @S9S_MB_2U_LIB.S9S_MB_2U(SCH_1):M_H_CPU0_SB_CB<6>
  DG37  M_H_CPU0_SB_CB<5>  DDR7_SB_ECC5  @S9S_MB_2U_LIB.S9S_MB_2U(SCH_1):M_H_CPU0_SB_CB<5>
  DF38  M_H_CPU0_SB_CB<4>  DDR7_SB_ECC4  @S9S_MB_2U_LIB.S9S_MB_2U(SCH_1):M_H_CPU0_SB_CB<4>
  DF34  M_H_CPU0_SB_CB<3>  DDR7_SB_ECC3  @S9S_MB_2U_LIB.S9S_MB_2U(SCH_1):M_H_CPU0_SB_CB<3>
  DG35  M_H_CPU0_SB_CB<2>  DDR7_SB_ECC2  @S9S_MB_2U_LIB.S9S_MB_2U(SCH_1):M_H_CPU0_SB_CB<2>
  DD34  M_H_CPU0_SB_CB<1>  DDR7_SB_ECC1  @S9S_MB_2U_LIB.S9S_MB_2U(SCH_1):M_H_CPU0_SB_CB<1>
  DC35  M_H_CPU0_SB_CB<0>  DDR7_SB_ECC0  @S9S_MB_2U_LIB.S9S_MB_2U(SCH_1):M_H_CPU0_SB_CB<0>
  DJ39  M_H_CPU0_SB_CA<6>  DDR7_SB_CA6  @S9S_MB_2U_LIB.S9S_MB_2U(SCH_1):M_H_CPU0_SB_CA<6>
  DP40  M_H_CPU0_SB_CA<5>  DDR7_SB_CA5  @S9S_MB_2U_LIB.S9S_MB_2U(SCH_1):M_H_CPU0_SB_CA<5>
  DK40  M_H_CPU0_SB_CA<4>  DDR7_SB_CA4  @S9S_MB_2U_LIB.S9S_MB_2U(SCH_1):M_H_CPU0_SB_CA<4>
  DN41  M_H_CPU0_SB_CA<3>  DDR7_SB_CA3  @S9S_MB_2U_LIB.S9S_MB_2U(SCH_1):M_H_CPU0_SB_CA<3>
  DL41  M_H_CPU0_SB_CA<2>  DDR7_SB_CA2  @S9S_MB_2U_LIB.S9S_MB_2U(SCH_1):M_H_CPU0_SB_CA<2>
  DG41  M_H_CPU0_SB_CA<1>  DDR7_SB_CA1  @S9S_MB_2U_LIB.S9S_MB_2U(SCH_1):M_H_CPU0_SB_CA<1>
  DF40  M_H_CPU0_SB_CA<0>  DDR7_SB_CA0  @S9S_MB_2U_LIB.S9S_MB_2U(SCH_1):M_H_CPU0_SB_CA<0>
  EH47  M_H_CPU0_SA_RSP<1>  DDR7_A_RSP1  @S9S_MB_2U_LIB.S9S_MB_2U(SCH_1):M_H_CPU0_SA_RSP<1>
  EG48  M_H_CPU0_SA_RSP<0>  DDR7_A_RSP0  @S9S_MB_2U_LIB.S9S_MB_2U(SCH_1):M_H_CPU0_SA_RSP<0>
  DD40  M_H_CPU0_SA_PAR  DDR7_SA_PAR  @S9S_MB_2U_LIB.S9S_MB_2U(SCH_1):M_H_CPU0_SA_PAR
  DF55  M_H_CPU0_SA_DQS_DP<9>  DDR7_SA_DQS_DP9  @S9S_MB_2U_LIB.S9S_MB_2U(SCH_1):M_H_CPU0_SA_DQS_DP<9>
  DF61  M_H_CPU0_SA_DQS_DP<8>  DDR7_SA_DQS_DP8  @S9S_MB_2U_LIB.S9S_MB_2U(SCH_1):M_H_CPU0_SA_DQS_DP<8>
  DF67  M_H_CPU0_SA_DQS_DP<7>  DDR7_SA_DQS_DP7  @S9S_MB_2U_LIB.S9S_MB_2U(SCH_1):M_H_CPU0_SA_DQS_DP<7>
  DF73  M_H_CPU0_SA_DQS_DP<6>  DDR7_SA_DQS_DP6  @S9S_MB_2U_LIB.S9S_MB_2U(SCH_1):M_H_CPU0_SA_DQS_DP<6>
  DN76  M_H_CPU0_SA_DQS_DP<5>  DDR7_SA_DQS_DP5  @S9S_MB_2U_LIB.S9S_MB_2U(SCH_1):M_H_CPU0_SA_DQS_DP<5>
  DB55  M_H_CPU0_SA_DQS_DP<4>  DDR7_SA_DQS_DP4  @S9S_MB_2U_LIB.S9S_MB_2U(SCH_1):M_H_CPU0_SA_DQS_DP<4>
  DB61  M_H_CPU0_SA_DQS_DP<3>  DDR7_SA_DQS_DP3  @S9S_MB_2U_LIB.S9S_MB_2U(SCH_1):M_H_CPU0_SA_DQS_DP<3>
  DB67  M_H_CPU0_SA_DQS_DP<2>  DDR7_SA_DQS_DP2  @S9S_MB_2U_LIB.S9S_MB_2U(SCH_1):M_H_CPU0_SA_DQS_DP<2>
  DD73  M_H_CPU0_SA_DQS_DP<1>  DDR7_SA_DQS_DP1  @S9S_MB_2U_LIB.S9S_MB_2U(SCH_1):M_H_CPU0_SA_DQS_DP<1>
  DL76  M_H_CPU0_SA_DQS_DP<0>  DDR7_SA_DQS_DP0  @S9S_MB_2U_LIB.S9S_MB_2U(SCH_1):M_H_CPU0_SA_DQS_DP<0>
  DH55  M_H_CPU0_SA_DQS_DN<9>  DDR7_SA_DQS_DN9  @S9S_MB_2U_LIB.S9S_MB_2U(SCH_1):M_H_CPU0_SA_DQS_DN<9>
  DH61  M_H_CPU0_SA_DQS_DN<8>  DDR7_SA_DQS_DN8  @S9S_MB_2U_LIB.S9S_MB_2U(SCH_1):M_H_CPU0_SA_DQS_DN<8>
  DH67  M_H_CPU0_SA_DQS_DN<7>  DDR7_SA_DQS_DN7  @S9S_MB_2U_LIB.S9S_MB_2U(SCH_1):M_H_CPU0_SA_DQS_DN<7>
  DH73  M_H_CPU0_SA_DQS_DN<6>  DDR7_SA_DQS_DN6  @S9S_MB_2U_LIB.S9S_MB_2U(SCH_1):M_H_CPU0_SA_DQS_DN<6>
  DR76  M_H_CPU0_SA_DQS_DN<5>  DDR7_SA_DQS_DN5  @S9S_MB_2U_LIB.S9S_MB_2U(SCH_1):M_H_CPU0_SA_DQS_DN<5>
  DD55  M_H_CPU0_SA_DQS_DN<4>  DDR7_SA_DQS_DN4  @S9S_MB_2U_LIB.S9S_MB_2U(SCH_1):M_H_CPU0_SA_DQS_DN<4>
  DD61  M_H_CPU0_SA_DQS_DN<3>  DDR7_SA_DQS_DN3  @S9S_MB_2U_LIB.S9S_MB_2U(SCH_1):M_H_CPU0_SA_DQS_DN<3>
  DD67  M_H_CPU0_SA_DQS_DN<2>  DDR7_SA_DQS_DN2  @S9S_MB_2U_LIB.S9S_MB_2U(SCH_1):M_H_CPU0_SA_DQS_DN<2>
  DB73  M_H_CPU0_SA_DQS_DN<1>  DDR7_SA_DQS_DN1  @S9S_MB_2U_LIB.S9S_MB_2U(SCH_1):M_H_CPU0_SA_DQS_DN<1>
  DJ76  M_H_CPU0_SA_DQS_DN<0>  DDR7_SA_DQS_DN0  @S9S_MB_2U_LIB.S9S_MB_2U(SCH_1):M_H_CPU0_SA_DQS_DN<0>
  DC74  M_H_CPU0_SA_DQ<9>  DDR7_SA_DQ9  @S9S_MB_2U_LIB.S9S_MB_2U(SCH_1):M_H_CPU0_SA_DQ<9>
  DD75  M_H_CPU0_SA_DQ<8>  DDR7_SA_DQ8  @S9S_MB_2U_LIB.S9S_MB_2U(SCH_1):M_H_CPU0_SA_DQ<8>
  DN74  M_H_CPU0_SA_DQ<7>  DDR7_SA_DQ7  @S9S_MB_2U_LIB.S9S_MB_2U(SCH_1):M_H_CPU0_SA_DQ<7>
  DP75  M_H_CPU0_SA_DQ<6>  DDR7_SA_DQ6  @S9S_MB_2U_LIB.S9S_MB_2U(SCH_1):M_H_CPU0_SA_DQ<6>
  DL74  M_H_CPU0_SA_DQ<5>  DDR7_SA_DQ5  @S9S_MB_2U_LIB.S9S_MB_2U(SCH_1):M_H_CPU0_SA_DQ<5>
  DK75  M_H_CPU0_SA_DQ<4>  DDR7_SA_DQ4  @S9S_MB_2U_LIB.S9S_MB_2U(SCH_1):M_H_CPU0_SA_DQ<4>
  DP77  M_H_CPU0_SA_DQ<3>  DDR7_SA_DQ3  @S9S_MB_2U_LIB.S9S_MB_2U(SCH_1):M_H_CPU0_SA_DQ<3>
  DF59  M_H_CPU0_SA_DQ<31>  DDR7_SA_DQ31  @S9S_MB_2U_LIB.S9S_MB_2U(SCH_1):M_H_CPU0_SA_DQ<31>
  DG60  M_H_CPU0_SA_DQ<30>  DDR7_SA_DQ30  @S9S_MB_2U_LIB.S9S_MB_2U(SCH_1):M_H_CPU0_SA_DQ<30>
  DW78  M_H_CPU0_SA_DQ<2>  DDR7_SA_DQ2  @S9S_MB_2U_LIB.S9S_MB_2U(SCH_1):M_H_CPU0_SA_DQ<2>
  DD59  M_H_CPU0_SA_DQ<29>  DDR7_SA_DQ29  @S9S_MB_2U_LIB.S9S_MB_2U(SCH_1):M_H_CPU0_SA_DQ<29>
  DC60  M_H_CPU0_SA_DQ<28>  DDR7_SA_DQ28  @S9S_MB_2U_LIB.S9S_MB_2U(SCH_1):M_H_CPU0_SA_DQ<28>
  DG62  M_H_CPU0_SA_DQ<27>  DDR7_SA_DQ27  @S9S_MB_2U_LIB.S9S_MB_2U(SCH_1):M_H_CPU0_SA_DQ<27>
  DF63  M_H_CPU0_SA_DQ<26>  DDR7_SA_DQ26  @S9S_MB_2U_LIB.S9S_MB_2U(SCH_1):M_H_CPU0_SA_DQ<26>
  DC62  M_H_CPU0_SA_DQ<25>  DDR7_SA_DQ25  @S9S_MB_2U_LIB.S9S_MB_2U(SCH_1):M_H_CPU0_SA_DQ<25>
  DD63  M_H_CPU0_SA_DQ<24>  DDR7_SA_DQ24  @S9S_MB_2U_LIB.S9S_MB_2U(SCH_1):M_H_CPU0_SA_DQ<24>
  DF65  M_H_CPU0_SA_DQ<23>  DDR7_SA_DQ23  @S9S_MB_2U_LIB.S9S_MB_2U(SCH_1):M_H_CPU0_SA_DQ<23>
  DG66  M_H_CPU0_SA_DQ<22>  DDR7_SA_DQ22  @S9S_MB_2U_LIB.S9S_MB_2U(SCH_1):M_H_CPU0_SA_DQ<22>
  DD65  M_H_CPU0_SA_DQ<21>  DDR7_SA_DQ21  @S9S_MB_2U_LIB.S9S_MB_2U(SCH_1):M_H_CPU0_SA_DQ<21>
  DC66  M_H_CPU0_SA_DQ<20>  DDR7_SA_DQ20  @S9S_MB_2U_LIB.S9S_MB_2U(SCH_1):M_H_CPU0_SA_DQ<20>
  DT77  M_H_CPU0_SA_DQ<1>  DDR7_SA_DQ1  @S9S_MB_2U_LIB.S9S_MB_2U(SCH_1):M_H_CPU0_SA_DQ<1>
  DG68  M_H_CPU0_SA_DQ<19>  DDR7_SA_DQ19  @S9S_MB_2U_LIB.S9S_MB_2U(SCH_1):M_H_CPU0_SA_DQ<19>
  DF69  M_H_CPU0_SA_DQ<18>  DDR7_SA_DQ18  @S9S_MB_2U_LIB.S9S_MB_2U(SCH_1):M_H_CPU0_SA_DQ<18>
  DC68  M_H_CPU0_SA_DQ<17>  DDR7_SA_DQ17  @S9S_MB_2U_LIB.S9S_MB_2U(SCH_1):M_H_CPU0_SA_DQ<17>
  DD69  M_H_CPU0_SA_DQ<16>  DDR7_SA_DQ16  @S9S_MB_2U_LIB.S9S_MB_2U(SCH_1):M_H_CPU0_SA_DQ<16>
  DF71  M_H_CPU0_SA_DQ<15>  DDR7_SA_DQ15  @S9S_MB_2U_LIB.S9S_MB_2U(SCH_1):M_H_CPU0_SA_DQ<15>
  DG72  M_H_CPU0_SA_DQ<14>  DDR7_SA_DQ14  @S9S_MB_2U_LIB.S9S_MB_2U(SCH_1):M_H_CPU0_SA_DQ<14>
  DD71  M_H_CPU0_SA_DQ<13>  DDR7_SA_DQ13  @S9S_MB_2U_LIB.S9S_MB_2U(SCH_1):M_H_CPU0_SA_DQ<13>
  DC72  M_H_CPU0_SA_DQ<12>  DDR7_SA_DQ12  @S9S_MB_2U_LIB.S9S_MB_2U(SCH_1):M_H_CPU0_SA_DQ<12>
  DG74  M_H_CPU0_SA_DQ<11>  DDR7_SA_DQ11  @S9S_MB_2U_LIB.S9S_MB_2U(SCH_1):M_H_CPU0_SA_DQ<11>
  DF75  M_H_CPU0_SA_DQ<10>  DDR7_SA_DQ10  @S9S_MB_2U_LIB.S9S_MB_2U(SCH_1):M_H_CPU0_SA_DQ<10>
  DY79  M_H_CPU0_SA_DQ<0>  DDR7_SA_DQ0  @S9S_MB_2U_LIB.S9S_MB_2U(SCH_1):M_H_CPU0_SA_DQ<0>
  DC50  M_H_CPU0_SA_CS_N<3>  DDR7_SA_CS3_N  @S9S_MB_2U_LIB.S9S_MB_2U(SCH_1):M_H_CPU0_SA_CS_N<3>
  DD51  M_H_CPU0_SA_CS_N<2>  DDR7_SA_CS2_N  @S9S_MB_2U_LIB.S9S_MB_2U(SCH_1):M_H_CPU0_SA_CS_N<2>
  DG50  M_H_CPU0_SA_CS_N<1>  DDR7_SA_CS1_N  @S9S_MB_2U_LIB.S9S_MB_2U(SCH_1):M_H_CPU0_SA_CS_N<1>
  DF51  M_H_CPU0_SA_CS_N<0>  DDR7_SA_CS0_N  @S9S_MB_2U_LIB.S9S_MB_2U(SCH_1):M_H_CPU0_SA_CS_N<0>
  DF53  M_H_CPU0_SA_CB<7>  DDR7_SA_ECC7  @S9S_MB_2U_LIB.S9S_MB_2U(SCH_1):M_H_CPU0_SA_CB<7>
  DG54  M_H_CPU0_SA_CB<6>  DDR7_SA_ECC6  @S9S_MB_2U_LIB.S9S_MB_2U(SCH_1):M_H_CPU0_SA_CB<6>
  DD53  M_H_CPU0_SA_CB<5>  DDR7_SA_ECC5  @S9S_MB_2U_LIB.S9S_MB_2U(SCH_1):M_H_CPU0_SA_CB<5>
  DC54  M_H_CPU0_SA_CB<4>  DDR7_SA_ECC4  @S9S_MB_2U_LIB.S9S_MB_2U(SCH_1):M_H_CPU0_SA_CB<4>
  DG56  M_H_CPU0_SA_CB<3>  DDR7_SA_ECC3  @S9S_MB_2U_LIB.S9S_MB_2U(SCH_1):M_H_CPU0_SA_CB<3>
  DF57  M_H_CPU0_SA_CB<2>  DDR7_SA_ECC2  @S9S_MB_2U_LIB.S9S_MB_2U(SCH_1):M_H_CPU0_SA_CB<2>
  DC56  M_H_CPU0_SA_CB<1>  DDR7_SA_ECC1  @S9S_MB_2U_LIB.S9S_MB_2U(SCH_1):M_H_CPU0_SA_CB<1>
  DD57  M_H_CPU0_SA_CB<0>  DDR7_SA_ECC0  @S9S_MB_2U_LIB.S9S_MB_2U(SCH_1):M_H_CPU0_SA_CB<0>
  DC41  M_H_CPU0_SA_CA<6>  DDR7_SA_CA6  @S9S_MB_2U_LIB.S9S_MB_2U(SCH_1):M_H_CPU0_SA_CA<6>
  DF47  M_H_CPU0_SA_CA<5>  DDR7_SA_CA5  @S9S_MB_2U_LIB.S9S_MB_2U(SCH_1):M_H_CPU0_SA_CA<5>
  DD47  M_H_CPU0_SA_CA<4>  DDR7_SA_CA4  @S9S_MB_2U_LIB.S9S_MB_2U(SCH_1):M_H_CPU0_SA_CA<4>
  DG48  M_H_CPU0_SA_CA<3>  DDR7_SA_CA3  @S9S_MB_2U_LIB.S9S_MB_2U(SCH_1):M_H_CPU0_SA_CA<3>
  DC48  M_H_CPU0_SA_CA<2>  DDR7_SA_CA2  @S9S_MB_2U_LIB.S9S_MB_2U(SCH_1):M_H_CPU0_SA_CA<2>
  DH49  M_H_CPU0_SA_CA<1>  DDR7_SA_CA1  @S9S_MB_2U_LIB.S9S_MB_2U(SCH_1):M_H_CPU0_SA_CA<1>
  DB49  M_H_CPU0_SA_CA<0>  DDR7_SA_CA0  @S9S_MB_2U_LIB.S9S_MB_2U(SCH_1):M_H_CPU0_SA_CA<0>
  DB42  M_H_CPU0_CLK_DP<1>  DDR7_CLK_DP1  @S9S_MB_2U_LIB.S9S_MB_2U(SCH_1):M_H_CPU0_CLK_DP<1>
  DF42  M_H_CPU0_CLK_DP<0>  DDR7_CLK_DP0  @S9S_MB_2U_LIB.S9S_MB_2U(SCH_1):M_H_CPU0_CLK_DP<0>
  DD42  M_H_CPU0_CLK_DN<1>  DDR7_CLK_DN1  @S9S_MB_2U_LIB.S9S_MB_2U(SCH_1):M_H_CPU0_CLK_DN<1>
  DH42  M_H_CPU0_CLK_DN<0>  DDR7_CLK_DN0  @S9S_MB_2U_LIB.S9S_MB_2U(SCH_1):M_H_CPU0_CLK_DN<0>
  CY51  M_H_CPU0_ALERT_N  DDR7_ALERT_N  @S9S_MB_2U_LIB.S9S_MB_2U(SCH_1):M_H_CPU0_ALERT_N

SOCKET4677_AZIFS054P001C01  I169  U2     [SOCKET4677_AZIFS054P001C01-SOCA]
  DV47  M_G_CPU0_SB_RSP<1>  DDR6_B_RSP1  @S9S_MB_2U_LIB.S9S_MB_2U(SCH_1):M_G_CPU0_SB_RSP<1>
  DU48  M_G_CPU0_SB_RSP<0>  DDR6_B_RSP0  @S9S_MB_2U_LIB.S9S_MB_2U(SCH_1):M_G_CPU0_SB_RSP<0>
  EB42  M_G_CPU0_SB_PAR  DDR6_SB_PAR  @S9S_MB_2U_LIB.S9S_MB_2U(SCH_1):M_G_CPU0_SB_PAR
  DT36  M_G_CPU0_SB_DQS_DP<9>  DDR6_SB_DQS_DP9  @S9S_MB_2U_LIB.S9S_MB_2U(SCH_1):M_G_CPU0_SB_DQS_DP<9>
  EN5  M_G_CPU0_SB_DQS_DP<8>  DDR6_SB_DQS_DP8  @S9S_MB_2U_LIB.S9S_MB_2U(SCH_1):M_G_CPU0_SB_DQS_DP<8>
  DY24  M_G_CPU0_SB_DQS_DP<7>  DDR6_SB_DQS_DP7  @S9S_MB_2U_LIB.S9S_MB_2U(SCH_1):M_G_CPU0_SB_DQS_DP<7>
  DR27  M_G_CPU0_SB_DQS_DP<6>  DDR6_SB_DQS_DP6  @S9S_MB_2U_LIB.S9S_MB_2U(SCH_1):M_G_CPU0_SB_DQS_DP<6>
  DN33  M_G_CPU0_SB_DQS_DP<5>  DDR6_SB_DQS_DP5  @S9S_MB_2U_LIB.S9S_MB_2U(SCH_1):M_G_CPU0_SB_DQS_DP<5>
  DY36  M_G_CPU0_SB_DQS_DP<4>  DDR6_SB_DQS_DP4  @S9S_MB_2U_LIB.S9S_MB_2U(SCH_1):M_G_CPU0_SB_DQS_DP<4>
  EN7  M_G_CPU0_SB_DQS_DP<3>  DDR6_SB_DQS_DP3  @S9S_MB_2U_LIB.S9S_MB_2U(SCH_1):M_G_CPU0_SB_DQS_DP<3>
  DT24  M_G_CPU0_SB_DQS_DP<2>  DDR6_SB_DQS_DP2  @S9S_MB_2U_LIB.S9S_MB_2U(SCH_1):M_G_CPU0_SB_DQS_DP<2>
  DL27  M_G_CPU0_SB_DQS_DP<1>  DDR6_SB_DQS_DP1  @S9S_MB_2U_LIB.S9S_MB_2U(SCH_1):M_G_CPU0_SB_DQS_DP<1>
  DL33  M_G_CPU0_SB_DQS_DP<0>  DDR6_SB_DQS_DP0  @S9S_MB_2U_LIB.S9S_MB_2U(SCH_1):M_G_CPU0_SB_DQS_DP<0>
  DV36  M_G_CPU0_SB_DQS_DN<9>  DDR6_SB_DQS_DN9  @S9S_MB_2U_LIB.S9S_MB_2U(SCH_1):M_G_CPU0_SB_DQS_DN<9>
  EM6  M_G_CPU0_SB_DQS_DN<8>  DDR6_SB_DQS_DN8  @S9S_MB_2U_LIB.S9S_MB_2U(SCH_1):M_G_CPU0_SB_DQS_DN<8>
  EB24  M_G_CPU0_SB_DQS_DN<7>  DDR6_SB_DQS_DN7  @S9S_MB_2U_LIB.S9S_MB_2U(SCH_1):M_G_CPU0_SB_DQS_DN<7>
  DN27  M_G_CPU0_SB_DQS_DN<6>  DDR6_SB_DQS_DN6  @S9S_MB_2U_LIB.S9S_MB_2U(SCH_1):M_G_CPU0_SB_DQS_DN<6>
  DR33  M_G_CPU0_SB_DQS_DN<5>  DDR6_SB_DQS_DN5  @S9S_MB_2U_LIB.S9S_MB_2U(SCH_1):M_G_CPU0_SB_DQS_DN<5>
  EB36  M_G_CPU0_SB_DQS_DN<4>  DDR6_SB_DQS_DN4  @S9S_MB_2U_LIB.S9S_MB_2U(SCH_1):M_G_CPU0_SB_DQS_DN<4>
  EP6  M_G_CPU0_SB_DQS_DN<3>  DDR6_SB_DQS_DN3  @S9S_MB_2U_LIB.S9S_MB_2U(SCH_1):M_G_CPU0_SB_DQS_DN<3>
  DV24  M_G_CPU0_SB_DQS_DN<2>  DDR6_SB_DQS_DN2  @S9S_MB_2U_LIB.S9S_MB_2U(SCH_1):M_G_CPU0_SB_DQS_DN<2>
  DJ27  M_G_CPU0_SB_DQS_DN<1>  DDR6_SB_DQS_DN1  @S9S_MB_2U_LIB.S9S_MB_2U(SCH_1):M_G_CPU0_SB_DQS_DN<1>
  DJ33  M_G_CPU0_SB_DQS_DN<0>  DDR6_SB_DQS_DN0  @S9S_MB_2U_LIB.S9S_MB_2U(SCH_1):M_G_CPU0_SB_DQS_DN<0>
  DK28  M_G_CPU0_SB_DQ<9>  DDR6_SB_DQ9  @S9S_MB_2U_LIB.S9S_MB_2U(SCH_1):M_G_CPU0_SB_DQ<9>
  DN29  M_G_CPU0_SB_DQ<8>  DDR6_SB_DQ8  @S9S_MB_2U_LIB.S9S_MB_2U(SCH_1):M_G_CPU0_SB_DQ<8>
  DN31  M_G_CPU0_SB_DQ<7>  DDR6_SB_DQ7  @S9S_MB_2U_LIB.S9S_MB_2U(SCH_1):M_G_CPU0_SB_DQ<7>
  DP32  M_G_CPU0_SB_DQ<6>  DDR6_SB_DQ6  @S9S_MB_2U_LIB.S9S_MB_2U(SCH_1):M_G_CPU0_SB_DQ<6>
  DL31  M_G_CPU0_SB_DQ<5>  DDR6_SB_DQ5  @S9S_MB_2U_LIB.S9S_MB_2U(SCH_1):M_G_CPU0_SB_DQ<5>
  DK32  M_G_CPU0_SB_DQ<4>  DDR6_SB_DQ4  @S9S_MB_2U_LIB.S9S_MB_2U(SCH_1):M_G_CPU0_SB_DQ<4>
  DP34  M_G_CPU0_SB_DQ<3>  DDR6_SB_DQ3  @S9S_MB_2U_LIB.S9S_MB_2U(SCH_1):M_G_CPU0_SB_DQ<3>
  EM4  M_G_CPU0_SB_DQ<31>  DDR6_SB_DQ31  @S9S_MB_2U_LIB.S9S_MB_2U(SCH_1):M_G_CPU0_SB_DQ<31>
  EP4  M_G_CPU0_SB_DQ<30>  DDR6_SB_DQ30  @S9S_MB_2U_LIB.S9S_MB_2U(SCH_1):M_G_CPU0_SB_DQ<30>
  DN35  M_G_CPU0_SB_DQ<2>  DDR6_SB_DQ2  @S9S_MB_2U_LIB.S9S_MB_2U(SCH_1):M_G_CPU0_SB_DQ<2>
  EJ5  M_G_CPU0_SB_DQ<29>  DDR6_SB_DQ29  @S9S_MB_2U_LIB.S9S_MB_2U(SCH_1):M_G_CPU0_SB_DQ<29>
  EK6  M_G_CPU0_SB_DQ<28>  DDR6_SB_DQ28  @S9S_MB_2U_LIB.S9S_MB_2U(SCH_1):M_G_CPU0_SB_DQ<28>
  ET8  M_G_CPU0_SB_DQ<27>  DDR6_SB_DQ27  @S9S_MB_2U_LIB.S9S_MB_2U(SCH_1):M_G_CPU0_SB_DQ<27>
  EP8  M_G_CPU0_SB_DQ<26>  DDR6_SB_DQ26  @S9S_MB_2U_LIB.S9S_MB_2U(SCH_1):M_G_CPU0_SB_DQ<26>
  EH8  M_G_CPU0_SB_DQ<25>  DDR6_SB_DQ25  @S9S_MB_2U_LIB.S9S_MB_2U(SCH_1):M_G_CPU0_SB_DQ<25>
  EK8  M_G_CPU0_SB_DQ<24>  DDR6_SB_DQ24  @S9S_MB_2U_LIB.S9S_MB_2U(SCH_1):M_G_CPU0_SB_DQ<24>
  DY22  M_G_CPU0_SB_DQ<23>  DDR6_SB_DQ23  @S9S_MB_2U_LIB.S9S_MB_2U(SCH_1):M_G_CPU0_SB_DQ<23>
  EA23  M_G_CPU0_SB_DQ<22>  DDR6_SB_DQ22  @S9S_MB_2U_LIB.S9S_MB_2U(SCH_1):M_G_CPU0_SB_DQ<22>
  DV22  M_G_CPU0_SB_DQ<21>  DDR6_SB_DQ21  @S9S_MB_2U_LIB.S9S_MB_2U(SCH_1):M_G_CPU0_SB_DQ<21>
  DU23  M_G_CPU0_SB_DQ<20>  DDR6_SB_DQ20  @S9S_MB_2U_LIB.S9S_MB_2U(SCH_1):M_G_CPU0_SB_DQ<20>
  DK34  M_G_CPU0_SB_DQ<1>  DDR6_SB_DQ1  @S9S_MB_2U_LIB.S9S_MB_2U(SCH_1):M_G_CPU0_SB_DQ<1>
  EA25  M_G_CPU0_SB_DQ<19>  DDR6_SB_DQ19  @S9S_MB_2U_LIB.S9S_MB_2U(SCH_1):M_G_CPU0_SB_DQ<19>
  DY26  M_G_CPU0_SB_DQ<18>  DDR6_SB_DQ18  @S9S_MB_2U_LIB.S9S_MB_2U(SCH_1):M_G_CPU0_SB_DQ<18>
  DU25  M_G_CPU0_SB_DQ<17>  DDR6_SB_DQ17  @S9S_MB_2U_LIB.S9S_MB_2U(SCH_1):M_G_CPU0_SB_DQ<17>
  DV26  M_G_CPU0_SB_DQ<16>  DDR6_SB_DQ16  @S9S_MB_2U_LIB.S9S_MB_2U(SCH_1):M_G_CPU0_SB_DQ<16>
  DN25  M_G_CPU0_SB_DQ<15>  DDR6_SB_DQ15  @S9S_MB_2U_LIB.S9S_MB_2U(SCH_1):M_G_CPU0_SB_DQ<15>
  DP26  M_G_CPU0_SB_DQ<14>  DDR6_SB_DQ14  @S9S_MB_2U_LIB.S9S_MB_2U(SCH_1):M_G_CPU0_SB_DQ<14>
  DL25  M_G_CPU0_SB_DQ<13>  DDR6_SB_DQ13  @S9S_MB_2U_LIB.S9S_MB_2U(SCH_1):M_G_CPU0_SB_DQ<13>
  DK26  M_G_CPU0_SB_DQ<12>  DDR6_SB_DQ12  @S9S_MB_2U_LIB.S9S_MB_2U(SCH_1):M_G_CPU0_SB_DQ<12>
  DP28  M_G_CPU0_SB_DQ<11>  DDR6_SB_DQ11  @S9S_MB_2U_LIB.S9S_MB_2U(SCH_1):M_G_CPU0_SB_DQ<11>
  DL29  M_G_CPU0_SB_DQ<10>  DDR6_SB_DQ10  @S9S_MB_2U_LIB.S9S_MB_2U(SCH_1):M_G_CPU0_SB_DQ<10>
  DL35  M_G_CPU0_SB_DQ<0>  DDR6_SB_DQ0  @S9S_MB_2U_LIB.S9S_MB_2U(SCH_1):M_G_CPU0_SB_DQ<0>
  DV40  M_G_CPU0_SB_CS_N<3>  DDR6_SB_CS3_N  @S9S_MB_2U_LIB.S9S_MB_2U(SCH_1):M_G_CPU0_SB_CS_N<3>
  DU41  M_G_CPU0_SB_CS_N<2>  DDR6_SB_CS2_N  @S9S_MB_2U_LIB.S9S_MB_2U(SCH_1):M_G_CPU0_SB_CS_N<2>
  DY40  M_G_CPU0_SB_CS_N<1>  DDR6_SB_CS1_N  @S9S_MB_2U_LIB.S9S_MB_2U(SCH_1):M_G_CPU0_SB_CS_N<1>
  EA41  M_G_CPU0_SB_CS_N<0>  DDR6_SB_CS0_N  @S9S_MB_2U_LIB.S9S_MB_2U(SCH_1):M_G_CPU0_SB_CS_N<0>
  EA37  M_G_CPU0_SB_CB<7>  DDR6_SB_ECC7  @S9S_MB_2U_LIB.S9S_MB_2U(SCH_1):M_G_CPU0_SB_CB<7>
  DY38  M_G_CPU0_SB_CB<6>  DDR6_SB_ECC6  @S9S_MB_2U_LIB.S9S_MB_2U(SCH_1):M_G_CPU0_SB_CB<6>
  DU37  M_G_CPU0_SB_CB<5>  DDR6_SB_ECC5  @S9S_MB_2U_LIB.S9S_MB_2U(SCH_1):M_G_CPU0_SB_CB<5>
  DV38  M_G_CPU0_SB_CB<4>  DDR6_SB_ECC4  @S9S_MB_2U_LIB.S9S_MB_2U(SCH_1):M_G_CPU0_SB_CB<4>
  DY34  M_G_CPU0_SB_CB<3>  DDR6_SB_ECC3  @S9S_MB_2U_LIB.S9S_MB_2U(SCH_1):M_G_CPU0_SB_CB<3>
  EA35  M_G_CPU0_SB_CB<2>  DDR6_SB_ECC2  @S9S_MB_2U_LIB.S9S_MB_2U(SCH_1):M_G_CPU0_SB_CB<2>
  DV34  M_G_CPU0_SB_CB<1>  DDR6_SB_ECC1  @S9S_MB_2U_LIB.S9S_MB_2U(SCH_1):M_G_CPU0_SB_CB<1>
  DU35  M_G_CPU0_SB_CB<0>  DDR6_SB_ECC0  @S9S_MB_2U_LIB.S9S_MB_2U(SCH_1):M_G_CPU0_SB_CB<0>
  DT42  M_G_CPU0_SB_CA<6>  DDR6_SB_CA6  @S9S_MB_2U_LIB.S9S_MB_2U(SCH_1):M_G_CPU0_SB_CA<6>
  EA43  M_G_CPU0_SB_CA<5>  DDR6_SB_CA5  @S9S_MB_2U_LIB.S9S_MB_2U(SCH_1):M_G_CPU0_SB_CA<5>
  DU43  M_G_CPU0_SB_CA<4>  DDR6_SB_CA4  @S9S_MB_2U_LIB.S9S_MB_2U(SCH_1):M_G_CPU0_SB_CA<4>
  DY44  M_G_CPU0_SB_CA<3>  DDR6_SB_CA3  @S9S_MB_2U_LIB.S9S_MB_2U(SCH_1):M_G_CPU0_SB_CA<3>
  DV44  M_G_CPU0_SB_CA<2>  DDR6_SB_CA2  @S9S_MB_2U_LIB.S9S_MB_2U(SCH_1):M_G_CPU0_SB_CA<2>
  DP44  M_G_CPU0_SB_CA<1>  DDR6_SB_CA1  @S9S_MB_2U_LIB.S9S_MB_2U(SCH_1):M_G_CPU0_SB_CA<1>
  DN43  M_G_CPU0_SB_CA<0>  DDR6_SB_CA0  @S9S_MB_2U_LIB.S9S_MB_2U(SCH_1):M_G_CPU0_SB_CA<0>
  DY47  M_G_CPU0_SA_RSP<1>  DDR6_A_RSP1  @S9S_MB_2U_LIB.S9S_MB_2U(SCH_1):M_G_CPU0_SA_RSP<1>
  EA48  M_G_CPU0_SA_RSP<0>  DDR6_A_RSP0  @S9S_MB_2U_LIB.S9S_MB_2U(SCH_1):M_G_CPU0_SA_RSP<0>
  DL43  M_G_CPU0_SA_PAR  DDR6_SA_PAR  @S9S_MB_2U_LIB.S9S_MB_2U(SCH_1):M_G_CPU0_SA_PAR
  DN58  M_G_CPU0_SA_DQS_DP<9>  DDR6_SA_DQS_DP9  @S9S_MB_2U_LIB.S9S_MB_2U(SCH_1):M_G_CPU0_SA_DQS_DP<9>
  DN64  M_G_CPU0_SA_DQS_DP<8>  DDR6_SA_DQS_DP8  @S9S_MB_2U_LIB.S9S_MB_2U(SCH_1):M_G_CPU0_SA_DQS_DP<8>
  DY61  M_G_CPU0_SA_DQS_DP<7>  DDR6_SA_DQS_DP7  @S9S_MB_2U_LIB.S9S_MB_2U(SCH_1):M_G_CPU0_SA_DQS_DP<7>
  DN70  M_G_CPU0_SA_DQS_DP<6>  DDR6_SA_DQS_DP6  @S9S_MB_2U_LIB.S9S_MB_2U(SCH_1):M_G_CPU0_SA_DQS_DP<6>
  DY73  M_G_CPU0_SA_DQS_DP<5>  DDR6_SA_DQS_DP5  @S9S_MB_2U_LIB.S9S_MB_2U(SCH_1):M_G_CPU0_SA_DQS_DP<5>
  DJ58  M_G_CPU0_SA_DQS_DP<4>  DDR6_SA_DQS_DP4  @S9S_MB_2U_LIB.S9S_MB_2U(SCH_1):M_G_CPU0_SA_DQS_DP<4>
  DJ64  M_G_CPU0_SA_DQS_DP<3>  DDR6_SA_DQS_DP3  @S9S_MB_2U_LIB.S9S_MB_2U(SCH_1):M_G_CPU0_SA_DQS_DP<3>
  DV61  M_G_CPU0_SA_DQS_DP<2>  DDR6_SA_DQS_DP2  @S9S_MB_2U_LIB.S9S_MB_2U(SCH_1):M_G_CPU0_SA_DQS_DP<2>
  DL70  M_G_CPU0_SA_DQS_DP<1>  DDR6_SA_DQS_DP1  @S9S_MB_2U_LIB.S9S_MB_2U(SCH_1):M_G_CPU0_SA_DQS_DP<1>
  DT73  M_G_CPU0_SA_DQS_DP<0>  DDR6_SA_DQS_DP0  @S9S_MB_2U_LIB.S9S_MB_2U(SCH_1):M_G_CPU0_SA_DQS_DP<0>
  DR58  M_G_CPU0_SA_DQS_DN<9>  DDR6_SA_DQS_DN9  @S9S_MB_2U_LIB.S9S_MB_2U(SCH_1):M_G_CPU0_SA_DQS_DN<9>
  DR64  M_G_CPU0_SA_DQS_DN<8>  DDR6_SA_DQS_DN8  @S9S_MB_2U_LIB.S9S_MB_2U(SCH_1):M_G_CPU0_SA_DQS_DN<8>
  EB61  M_G_CPU0_SA_DQS_DN<7>  DDR6_SA_DQS_DN7  @S9S_MB_2U_LIB.S9S_MB_2U(SCH_1):M_G_CPU0_SA_DQS_DN<7>
  DR70  M_G_CPU0_SA_DQS_DN<6>  DDR6_SA_DQS_DN6  @S9S_MB_2U_LIB.S9S_MB_2U(SCH_1):M_G_CPU0_SA_DQS_DN<6>
  EB73  M_G_CPU0_SA_DQS_DN<5>  DDR6_SA_DQS_DN5  @S9S_MB_2U_LIB.S9S_MB_2U(SCH_1):M_G_CPU0_SA_DQS_DN<5>
  DL58  M_G_CPU0_SA_DQS_DN<4>  DDR6_SA_DQS_DN4  @S9S_MB_2U_LIB.S9S_MB_2U(SCH_1):M_G_CPU0_SA_DQS_DN<4>
  DL64  M_G_CPU0_SA_DQS_DN<3>  DDR6_SA_DQS_DN3  @S9S_MB_2U_LIB.S9S_MB_2U(SCH_1):M_G_CPU0_SA_DQS_DN<3>
  DT61  M_G_CPU0_SA_DQS_DN<2>  DDR6_SA_DQS_DN2  @S9S_MB_2U_LIB.S9S_MB_2U(SCH_1):M_G_CPU0_SA_DQS_DN<2>
  DJ70  M_G_CPU0_SA_DQS_DN<1>  DDR6_SA_DQS_DN1  @S9S_MB_2U_LIB.S9S_MB_2U(SCH_1):M_G_CPU0_SA_DQS_DN<1>
  DV73  M_G_CPU0_SA_DQS_DN<0>  DDR6_SA_DQS_DN0  @S9S_MB_2U_LIB.S9S_MB_2U(SCH_1):M_G_CPU0_SA_DQS_DN<0>
  DK71  M_G_CPU0_SA_DQ<9>  DDR6_SA_DQ9  @S9S_MB_2U_LIB.S9S_MB_2U(SCH_1):M_G_CPU0_SA_DQ<9>
  DL72  M_G_CPU0_SA_DQ<8>  DDR6_SA_DQ8  @S9S_MB_2U_LIB.S9S_MB_2U(SCH_1):M_G_CPU0_SA_DQ<8>
  DY71  M_G_CPU0_SA_DQ<7>  DDR6_SA_DQ7  @S9S_MB_2U_LIB.S9S_MB_2U(SCH_1):M_G_CPU0_SA_DQ<7>
  EA72  M_G_CPU0_SA_DQ<6>  DDR6_SA_DQ6  @S9S_MB_2U_LIB.S9S_MB_2U(SCH_1):M_G_CPU0_SA_DQ<6>
  DV71  M_G_CPU0_SA_DQ<5>  DDR6_SA_DQ5  @S9S_MB_2U_LIB.S9S_MB_2U(SCH_1):M_G_CPU0_SA_DQ<5>
  DU72  M_G_CPU0_SA_DQ<4>  DDR6_SA_DQ4  @S9S_MB_2U_LIB.S9S_MB_2U(SCH_1):M_G_CPU0_SA_DQ<4>
  EA74  M_G_CPU0_SA_DQ<3>  DDR6_SA_DQ3  @S9S_MB_2U_LIB.S9S_MB_2U(SCH_1):M_G_CPU0_SA_DQ<3>
  DN62  M_G_CPU0_SA_DQ<31>  DDR6_SA_DQ31  @S9S_MB_2U_LIB.S9S_MB_2U(SCH_1):M_G_CPU0_SA_DQ<31>
  DP63  M_G_CPU0_SA_DQ<30>  DDR6_SA_DQ30  @S9S_MB_2U_LIB.S9S_MB_2U(SCH_1):M_G_CPU0_SA_DQ<30>
  DY75  M_G_CPU0_SA_DQ<2>  DDR6_SA_DQ2  @S9S_MB_2U_LIB.S9S_MB_2U(SCH_1):M_G_CPU0_SA_DQ<2>
  DL62  M_G_CPU0_SA_DQ<29>  DDR6_SA_DQ29  @S9S_MB_2U_LIB.S9S_MB_2U(SCH_1):M_G_CPU0_SA_DQ<29>
  DK63  M_G_CPU0_SA_DQ<28>  DDR6_SA_DQ28  @S9S_MB_2U_LIB.S9S_MB_2U(SCH_1):M_G_CPU0_SA_DQ<28>
  DP65  M_G_CPU0_SA_DQ<27>  DDR6_SA_DQ27  @S9S_MB_2U_LIB.S9S_MB_2U(SCH_1):M_G_CPU0_SA_DQ<27>
  DN66  M_G_CPU0_SA_DQ<26>  DDR6_SA_DQ26  @S9S_MB_2U_LIB.S9S_MB_2U(SCH_1):M_G_CPU0_SA_DQ<26>
  DK65  M_G_CPU0_SA_DQ<25>  DDR6_SA_DQ25  @S9S_MB_2U_LIB.S9S_MB_2U(SCH_1):M_G_CPU0_SA_DQ<25>
  DL66  M_G_CPU0_SA_DQ<24>  DDR6_SA_DQ24  @S9S_MB_2U_LIB.S9S_MB_2U(SCH_1):M_G_CPU0_SA_DQ<24>
  DY59  M_G_CPU0_SA_DQ<23>  DDR6_SA_DQ23  @S9S_MB_2U_LIB.S9S_MB_2U(SCH_1):M_G_CPU0_SA_DQ<23>
  EA60  M_G_CPU0_SA_DQ<22>  DDR6_SA_DQ22  @S9S_MB_2U_LIB.S9S_MB_2U(SCH_1):M_G_CPU0_SA_DQ<22>
  DV59  M_G_CPU0_SA_DQ<21>  DDR6_SA_DQ21  @S9S_MB_2U_LIB.S9S_MB_2U(SCH_1):M_G_CPU0_SA_DQ<21>
  DU60  M_G_CPU0_SA_DQ<20>  DDR6_SA_DQ20  @S9S_MB_2U_LIB.S9S_MB_2U(SCH_1):M_G_CPU0_SA_DQ<20>
  DU74  M_G_CPU0_SA_DQ<1>  DDR6_SA_DQ1  @S9S_MB_2U_LIB.S9S_MB_2U(SCH_1):M_G_CPU0_SA_DQ<1>
  EA62  M_G_CPU0_SA_DQ<19>  DDR6_SA_DQ19  @S9S_MB_2U_LIB.S9S_MB_2U(SCH_1):M_G_CPU0_SA_DQ<19>
  DY63  M_G_CPU0_SA_DQ<18>  DDR6_SA_DQ18  @S9S_MB_2U_LIB.S9S_MB_2U(SCH_1):M_G_CPU0_SA_DQ<18>
  DU62  M_G_CPU0_SA_DQ<17>  DDR6_SA_DQ17  @S9S_MB_2U_LIB.S9S_MB_2U(SCH_1):M_G_CPU0_SA_DQ<17>
  DV63  M_G_CPU0_SA_DQ<16>  DDR6_SA_DQ16  @S9S_MB_2U_LIB.S9S_MB_2U(SCH_1):M_G_CPU0_SA_DQ<16>
  DN68  M_G_CPU0_SA_DQ<15>  DDR6_SA_DQ15  @S9S_MB_2U_LIB.S9S_MB_2U(SCH_1):M_G_CPU0_SA_DQ<15>
  DP69  M_G_CPU0_SA_DQ<14>  DDR6_SA_DQ14  @S9S_MB_2U_LIB.S9S_MB_2U(SCH_1):M_G_CPU0_SA_DQ<14>
  DL68  M_G_CPU0_SA_DQ<13>  DDR6_SA_DQ13  @S9S_MB_2U_LIB.S9S_MB_2U(SCH_1):M_G_CPU0_SA_DQ<13>
  DK69  M_G_CPU0_SA_DQ<12>  DDR6_SA_DQ12  @S9S_MB_2U_LIB.S9S_MB_2U(SCH_1):M_G_CPU0_SA_DQ<12>
  DP71  M_G_CPU0_SA_DQ<11>  DDR6_SA_DQ11  @S9S_MB_2U_LIB.S9S_MB_2U(SCH_1):M_G_CPU0_SA_DQ<11>
  DN72  M_G_CPU0_SA_DQ<10>  DDR6_SA_DQ10  @S9S_MB_2U_LIB.S9S_MB_2U(SCH_1):M_G_CPU0_SA_DQ<10>
  DV75  M_G_CPU0_SA_DQ<0>  DDR6_SA_DQ0  @S9S_MB_2U_LIB.S9S_MB_2U(SCH_1):M_G_CPU0_SA_DQ<0>
  DK53  M_G_CPU0_SA_CS_N<3>  DDR6_SA_CS3_N  @S9S_MB_2U_LIB.S9S_MB_2U(SCH_1):M_G_CPU0_SA_CS_N<3>
  DL54  M_G_CPU0_SA_CS_N<2>  DDR6_SA_CS2_N  @S9S_MB_2U_LIB.S9S_MB_2U(SCH_1):M_G_CPU0_SA_CS_N<2>
  DP53  M_G_CPU0_SA_CS_N<1>  DDR6_SA_CS1_N  @S9S_MB_2U_LIB.S9S_MB_2U(SCH_1):M_G_CPU0_SA_CS_N<1>
  DN54  M_G_CPU0_SA_CS_N<0>  DDR6_SA_CS0_N  @S9S_MB_2U_LIB.S9S_MB_2U(SCH_1):M_G_CPU0_SA_CS_N<0>
  DN56  M_G_CPU0_SA_CB<7>  DDR6_SA_ECC7  @S9S_MB_2U_LIB.S9S_MB_2U(SCH_1):M_G_CPU0_SA_CB<7>
  DP57  M_G_CPU0_SA_CB<6>  DDR6_SA_ECC6  @S9S_MB_2U_LIB.S9S_MB_2U(SCH_1):M_G_CPU0_SA_CB<6>
  DL56  M_G_CPU0_SA_CB<5>  DDR6_SA_ECC5  @S9S_MB_2U_LIB.S9S_MB_2U(SCH_1):M_G_CPU0_SA_CB<5>
  DK57  M_G_CPU0_SA_CB<4>  DDR6_SA_ECC4  @S9S_MB_2U_LIB.S9S_MB_2U(SCH_1):M_G_CPU0_SA_CB<4>
  DP59  M_G_CPU0_SA_CB<3>  DDR6_SA_ECC3  @S9S_MB_2U_LIB.S9S_MB_2U(SCH_1):M_G_CPU0_SA_CB<3>
  DN60  M_G_CPU0_SA_CB<2>  DDR6_SA_ECC2  @S9S_MB_2U_LIB.S9S_MB_2U(SCH_1):M_G_CPU0_SA_CB<2>
  DK59  M_G_CPU0_SA_CB<1>  DDR6_SA_ECC1  @S9S_MB_2U_LIB.S9S_MB_2U(SCH_1):M_G_CPU0_SA_CB<1>
  DL60  M_G_CPU0_SA_CB<0>  DDR6_SA_ECC0  @S9S_MB_2U_LIB.S9S_MB_2U(SCH_1):M_G_CPU0_SA_CB<0>
  DK44  M_G_CPU0_SA_CA<6>  DDR6_SA_CA6  @S9S_MB_2U_LIB.S9S_MB_2U(SCH_1):M_G_CPU0_SA_CA<6>
  DN50  M_G_CPU0_SA_CA<5>  DDR6_SA_CA5  @S9S_MB_2U_LIB.S9S_MB_2U(SCH_1):M_G_CPU0_SA_CA<5>
  DL50  M_G_CPU0_SA_CA<4>  DDR6_SA_CA4  @S9S_MB_2U_LIB.S9S_MB_2U(SCH_1):M_G_CPU0_SA_CA<4>
  DP51  M_G_CPU0_SA_CA<3>  DDR6_SA_CA3  @S9S_MB_2U_LIB.S9S_MB_2U(SCH_1):M_G_CPU0_SA_CA<3>
  DK51  M_G_CPU0_SA_CA<2>  DDR6_SA_CA2  @S9S_MB_2U_LIB.S9S_MB_2U(SCH_1):M_G_CPU0_SA_CA<2>
  DR52  M_G_CPU0_SA_CA<1>  DDR6_SA_CA1  @S9S_MB_2U_LIB.S9S_MB_2U(SCH_1):M_G_CPU0_SA_CA<1>
  DJ52  M_G_CPU0_SA_CA<0>  DDR6_SA_CA0  @S9S_MB_2U_LIB.S9S_MB_2U(SCH_1):M_G_CPU0_SA_CA<0>
  DJ45  M_G_CPU0_CLK_DP<1>  DDR6_CLK_DP1  @S9S_MB_2U_LIB.S9S_MB_2U(SCH_1):M_G_CPU0_CLK_DP<1>
  DN45  M_G_CPU0_CLK_DP<0>  DDR6_CLK_DP0  @S9S_MB_2U_LIB.S9S_MB_2U(SCH_1):M_G_CPU0_CLK_DP<0>
  DL45  M_G_CPU0_CLK_DN<1>  DDR6_CLK_DN1  @S9S_MB_2U_LIB.S9S_MB_2U(SCH_1):M_G_CPU0_CLK_DN<1>
  DR45  M_G_CPU0_CLK_DN<0>  DDR6_CLK_DN0  @S9S_MB_2U_LIB.S9S_MB_2U(SCH_1):M_G_CPU0_CLK_DN<0>
  CW50  M_G_CPU0_ALERT_N  DDR6_ALERT_N  @S9S_MB_2U_LIB.S9S_MB_2U(SCH_1):M_G_CPU0_ALERT_N

SOCKET4677_AZIFS054P001C01  I169  U2     [SOCKET4677_AZIFS054P001C01-SOCA]
  DK47  M_F_CPU0_SB_RSP<1>  DDR5_B_RSP1  @S9S_MB_2U_LIB.S9S_MB_2U(SCH_1):M_F_CPU0_SB_RSP<1>
  DL48  M_F_CPU0_SB_RSP<0>  DDR5_B_RSP0  @S9S_MB_2U_LIB.S9S_MB_2U(SCH_1):M_F_CPU0_SB_RSP<0>
  EJ39  M_F_CPU0_SB_PAR  DDR5_SB_PAR  @S9S_MB_2U_LIB.S9S_MB_2U(SCH_1):M_F_CPU0_SB_PAR
  EC33  M_F_CPU0_SB_DQS_DP<9>  DDR5_SB_DQS_DP9  @S9S_MB_2U_LIB.S9S_MB_2U(SCH_1):M_F_CPU0_SB_DQS_DP<9>
  EB18  M_F_CPU0_SB_DQS_DP<8>  DDR5_SB_DQS_DP8  @S9S_MB_2U_LIB.S9S_MB_2U(SCH_1):M_F_CPU0_SB_DQS_DP<8>
  EP12  M_F_CPU0_SB_DQS_DP<7>  DDR5_SB_DQS_DP7  @S9S_MB_2U_LIB.S9S_MB_2U(SCH_1):M_F_CPU0_SB_DQS_DP<7>
  EG21  M_F_CPU0_SB_DQS_DP<6>  DDR5_SB_DQS_DP6  @S9S_MB_2U_LIB.S9S_MB_2U(SCH_1):M_F_CPU0_SB_DQS_DP<6>
  DY30  M_F_CPU0_SB_DQS_DP<5>  DDR5_SB_DQS_DP5  @S9S_MB_2U_LIB.S9S_MB_2U(SCH_1):M_F_CPU0_SB_DQS_DP<5>
  EG33  M_F_CPU0_SB_DQS_DP<4>  DDR5_SB_DQS_DP4  @S9S_MB_2U_LIB.S9S_MB_2U(SCH_1):M_F_CPU0_SB_DQS_DP<4>
  DV18  M_F_CPU0_SB_DQS_DP<3>  DDR5_SB_DQS_DP3  @S9S_MB_2U_LIB.S9S_MB_2U(SCH_1):M_F_CPU0_SB_DQS_DP<3>
  EK12  M_F_CPU0_SB_DQS_DP<2>  DDR5_SB_DQS_DP2  @S9S_MB_2U_LIB.S9S_MB_2U(SCH_1):M_F_CPU0_SB_DQS_DP<2>
  EC21  M_F_CPU0_SB_DQS_DP<1>  DDR5_SB_DQS_DP1  @S9S_MB_2U_LIB.S9S_MB_2U(SCH_1):M_F_CPU0_SB_DQS_DP<1>
  DT30  M_F_CPU0_SB_DQS_DP<0>  DDR5_SB_DQS_DP0  @S9S_MB_2U_LIB.S9S_MB_2U(SCH_1):M_F_CPU0_SB_DQS_DP<0>
  EE33  M_F_CPU0_SB_DQS_DN<9>  DDR5_SB_DQS_DN9  @S9S_MB_2U_LIB.S9S_MB_2U(SCH_1):M_F_CPU0_SB_DQS_DN<9>
  DY18  M_F_CPU0_SB_DQS_DN<8>  DDR5_SB_DQS_DN8  @S9S_MB_2U_LIB.S9S_MB_2U(SCH_1):M_F_CPU0_SB_DQS_DN<8>
  ET12  M_F_CPU0_SB_DQS_DN<7>  DDR5_SB_DQS_DN7  @S9S_MB_2U_LIB.S9S_MB_2U(SCH_1):M_F_CPU0_SB_DQS_DN<7>
  EJ21  M_F_CPU0_SB_DQS_DN<6>  DDR5_SB_DQS_DN6  @S9S_MB_2U_LIB.S9S_MB_2U(SCH_1):M_F_CPU0_SB_DQS_DN<6>
  EB30  M_F_CPU0_SB_DQS_DN<5>  DDR5_SB_DQS_DN5  @S9S_MB_2U_LIB.S9S_MB_2U(SCH_1):M_F_CPU0_SB_DQS_DN<5>
  EJ33  M_F_CPU0_SB_DQS_DN<4>  DDR5_SB_DQS_DN4  @S9S_MB_2U_LIB.S9S_MB_2U(SCH_1):M_F_CPU0_SB_DQS_DN<4>
  DT18  M_F_CPU0_SB_DQS_DN<3>  DDR5_SB_DQS_DN3  @S9S_MB_2U_LIB.S9S_MB_2U(SCH_1):M_F_CPU0_SB_DQS_DN<3>
  EM12  M_F_CPU0_SB_DQS_DN<2>  DDR5_SB_DQS_DN2  @S9S_MB_2U_LIB.S9S_MB_2U(SCH_1):M_F_CPU0_SB_DQS_DN<2>
  EE21  M_F_CPU0_SB_DQS_DN<1>  DDR5_SB_DQS_DN1  @S9S_MB_2U_LIB.S9S_MB_2U(SCH_1):M_F_CPU0_SB_DQS_DN<1>
  DV30  M_F_CPU0_SB_DQS_DN<0>  DDR5_SB_DQS_DN0  @S9S_MB_2U_LIB.S9S_MB_2U(SCH_1):M_F_CPU0_SB_DQS_DN<0>
  ED22  M_F_CPU0_SB_DQ<9>  DDR5_SB_DQ9  @S9S_MB_2U_LIB.S9S_MB_2U(SCH_1):M_F_CPU0_SB_DQ<9>
  EE23  M_F_CPU0_SB_DQ<8>  DDR5_SB_DQ8  @S9S_MB_2U_LIB.S9S_MB_2U(SCH_1):M_F_CPU0_SB_DQ<8>
  DY28  M_F_CPU0_SB_DQ<7>  DDR5_SB_DQ7  @S9S_MB_2U_LIB.S9S_MB_2U(SCH_1):M_F_CPU0_SB_DQ<7>
  EA29  M_F_CPU0_SB_DQ<6>  DDR5_SB_DQ6  @S9S_MB_2U_LIB.S9S_MB_2U(SCH_1):M_F_CPU0_SB_DQ<6>
  DV28  M_F_CPU0_SB_DQ<5>  DDR5_SB_DQ5  @S9S_MB_2U_LIB.S9S_MB_2U(SCH_1):M_F_CPU0_SB_DQ<5>
  DU29  M_F_CPU0_SB_DQ<4>  DDR5_SB_DQ4  @S9S_MB_2U_LIB.S9S_MB_2U(SCH_1):M_F_CPU0_SB_DQ<4>
  EA31  M_F_CPU0_SB_DQ<3>  DDR5_SB_DQ3  @S9S_MB_2U_LIB.S9S_MB_2U(SCH_1):M_F_CPU0_SB_DQ<3>
  DR17  M_F_CPU0_SB_DQ<31>  DDR5_SB_DQ31  @S9S_MB_2U_LIB.S9S_MB_2U(SCH_1):M_F_CPU0_SB_DQ<31>
  EC17  M_F_CPU0_SB_DQ<30>  DDR5_SB_DQ30  @S9S_MB_2U_LIB.S9S_MB_2U(SCH_1):M_F_CPU0_SB_DQ<30>
  DY32  M_F_CPU0_SB_DQ<2>  DDR5_SB_DQ2  @S9S_MB_2U_LIB.S9S_MB_2U(SCH_1):M_F_CPU0_SB_DQ<2>
  DU17  M_F_CPU0_SB_DQ<29>  DDR5_SB_DQ29  @S9S_MB_2U_LIB.S9S_MB_2U(SCH_1):M_F_CPU0_SB_DQ<29>
  EA17  M_F_CPU0_SB_DQ<28>  DDR5_SB_DQ28  @S9S_MB_2U_LIB.S9S_MB_2U(SCH_1):M_F_CPU0_SB_DQ<28>
  EA19  M_F_CPU0_SB_DQ<27>  DDR5_SB_DQ27  @S9S_MB_2U_LIB.S9S_MB_2U(SCH_1):M_F_CPU0_SB_DQ<27>
  DY20  M_F_CPU0_SB_DQ<26>  DDR5_SB_DQ26  @S9S_MB_2U_LIB.S9S_MB_2U(SCH_1):M_F_CPU0_SB_DQ<26>
  DU19  M_F_CPU0_SB_DQ<25>  DDR5_SB_DQ25  @S9S_MB_2U_LIB.S9S_MB_2U(SCH_1):M_F_CPU0_SB_DQ<25>
  DV20  M_F_CPU0_SB_DQ<24>  DDR5_SB_DQ24  @S9S_MB_2U_LIB.S9S_MB_2U(SCH_1):M_F_CPU0_SB_DQ<24>
  EP10  M_F_CPU0_SB_DQ<23>  DDR5_SB_DQ23  @S9S_MB_2U_LIB.S9S_MB_2U(SCH_1):M_F_CPU0_SB_DQ<23>
  ER11  M_F_CPU0_SB_DQ<22>  DDR5_SB_DQ22  @S9S_MB_2U_LIB.S9S_MB_2U(SCH_1):M_F_CPU0_SB_DQ<22>
  EM10  M_F_CPU0_SB_DQ<21>  DDR5_SB_DQ21  @S9S_MB_2U_LIB.S9S_MB_2U(SCH_1):M_F_CPU0_SB_DQ<21>
  EL11  M_F_CPU0_SB_DQ<20>  DDR5_SB_DQ20  @S9S_MB_2U_LIB.S9S_MB_2U(SCH_1):M_F_CPU0_SB_DQ<20>
  DU31  M_F_CPU0_SB_DQ<1>  DDR5_SB_DQ1  @S9S_MB_2U_LIB.S9S_MB_2U(SCH_1):M_F_CPU0_SB_DQ<1>
  ER13  M_F_CPU0_SB_DQ<19>  DDR5_SB_DQ19  @S9S_MB_2U_LIB.S9S_MB_2U(SCH_1):M_F_CPU0_SB_DQ<19>
  EP14  M_F_CPU0_SB_DQ<18>  DDR5_SB_DQ18  @S9S_MB_2U_LIB.S9S_MB_2U(SCH_1):M_F_CPU0_SB_DQ<18>
  EL13  M_F_CPU0_SB_DQ<17>  DDR5_SB_DQ17  @S9S_MB_2U_LIB.S9S_MB_2U(SCH_1):M_F_CPU0_SB_DQ<17>
  EM14  M_F_CPU0_SB_DQ<16>  DDR5_SB_DQ16  @S9S_MB_2U_LIB.S9S_MB_2U(SCH_1):M_F_CPU0_SB_DQ<16>
  EG19  M_F_CPU0_SB_DQ<15>  DDR5_SB_DQ15  @S9S_MB_2U_LIB.S9S_MB_2U(SCH_1):M_F_CPU0_SB_DQ<15>
  EH20  M_F_CPU0_SB_DQ<14>  DDR5_SB_DQ14  @S9S_MB_2U_LIB.S9S_MB_2U(SCH_1):M_F_CPU0_SB_DQ<14>
  EE19  M_F_CPU0_SB_DQ<13>  DDR5_SB_DQ13  @S9S_MB_2U_LIB.S9S_MB_2U(SCH_1):M_F_CPU0_SB_DQ<13>
  ED20  M_F_CPU0_SB_DQ<12>  DDR5_SB_DQ12  @S9S_MB_2U_LIB.S9S_MB_2U(SCH_1):M_F_CPU0_SB_DQ<12>
  EH22  M_F_CPU0_SB_DQ<11>  DDR5_SB_DQ11  @S9S_MB_2U_LIB.S9S_MB_2U(SCH_1):M_F_CPU0_SB_DQ<11>
  EG23  M_F_CPU0_SB_DQ<10>  DDR5_SB_DQ10  @S9S_MB_2U_LIB.S9S_MB_2U(SCH_1):M_F_CPU0_SB_DQ<10>
  DV32  M_F_CPU0_SB_DQ<0>  DDR5_SB_DQ0  @S9S_MB_2U_LIB.S9S_MB_2U(SCH_1):M_F_CPU0_SB_DQ<0>
  EE37  M_F_CPU0_SB_CS_N<3>  DDR5_SB_CS3_N  @S9S_MB_2U_LIB.S9S_MB_2U(SCH_1):M_F_CPU0_SB_CS_N<3>
  ED38  M_F_CPU0_SB_CS_N<2>  DDR5_SB_CS2_N  @S9S_MB_2U_LIB.S9S_MB_2U(SCH_1):M_F_CPU0_SB_CS_N<2>
  EG37  M_F_CPU0_SB_CS_N<1>  DDR5_SB_CS1_N  @S9S_MB_2U_LIB.S9S_MB_2U(SCH_1):M_F_CPU0_SB_CS_N<1>
  EH38  M_F_CPU0_SB_CS_N<0>  DDR5_SB_CS0_N  @S9S_MB_2U_LIB.S9S_MB_2U(SCH_1):M_F_CPU0_SB_CS_N<0>
  EH34  M_F_CPU0_SB_CB<7>  DDR5_SB_ECC7  @S9S_MB_2U_LIB.S9S_MB_2U(SCH_1):M_F_CPU0_SB_CB<7>
  EG35  M_F_CPU0_SB_CB<6>  DDR5_SB_ECC6  @S9S_MB_2U_LIB.S9S_MB_2U(SCH_1):M_F_CPU0_SB_CB<6>
  ED34  M_F_CPU0_SB_CB<5>  DDR5_SB_ECC5  @S9S_MB_2U_LIB.S9S_MB_2U(SCH_1):M_F_CPU0_SB_CB<5>
  EE35  M_F_CPU0_SB_CB<4>  DDR5_SB_ECC4  @S9S_MB_2U_LIB.S9S_MB_2U(SCH_1):M_F_CPU0_SB_CB<4>
  EG31  M_F_CPU0_SB_CB<3>  DDR5_SB_ECC3  @S9S_MB_2U_LIB.S9S_MB_2U(SCH_1):M_F_CPU0_SB_CB<3>
  EH32  M_F_CPU0_SB_CB<2>  DDR5_SB_ECC2  @S9S_MB_2U_LIB.S9S_MB_2U(SCH_1):M_F_CPU0_SB_CB<2>
  EE31  M_F_CPU0_SB_CB<1>  DDR5_SB_ECC1  @S9S_MB_2U_LIB.S9S_MB_2U(SCH_1):M_F_CPU0_SB_CB<1>
  ED32  M_F_CPU0_SB_CB<0>  DDR5_SB_ECC0  @S9S_MB_2U_LIB.S9S_MB_2U(SCH_1):M_F_CPU0_SB_CB<0>
  EC39  M_F_CPU0_SB_CA<6>  DDR5_SB_CA6  @S9S_MB_2U_LIB.S9S_MB_2U(SCH_1):M_F_CPU0_SB_CA<6>
  EH40  M_F_CPU0_SB_CA<5>  DDR5_SB_CA5  @S9S_MB_2U_LIB.S9S_MB_2U(SCH_1):M_F_CPU0_SB_CA<5>
  ED40  M_F_CPU0_SB_CA<4>  DDR5_SB_CA4  @S9S_MB_2U_LIB.S9S_MB_2U(SCH_1):M_F_CPU0_SB_CA<4>
  EG41  M_F_CPU0_SB_CA<3>  DDR5_SB_CA3  @S9S_MB_2U_LIB.S9S_MB_2U(SCH_1):M_F_CPU0_SB_CA<3>
  EE41  M_F_CPU0_SB_CA<2>  DDR5_SB_CA2  @S9S_MB_2U_LIB.S9S_MB_2U(SCH_1):M_F_CPU0_SB_CA<2>
  DU50  M_F_CPU0_SB_CA<1>  DDR5_SB_CA1  @S9S_MB_2U_LIB.S9S_MB_2U(SCH_1):M_F_CPU0_SB_CA<1>
  DV51  M_F_CPU0_SB_CA<0>  DDR5_SB_CA0  @S9S_MB_2U_LIB.S9S_MB_2U(SCH_1):M_F_CPU0_SB_CA<0>
  DP47  M_F_CPU0_SA_RSP<1>  DDR5_A_RSP1  @S9S_MB_2U_LIB.S9S_MB_2U(SCH_1):M_F_CPU0_SA_RSP<1>
  DN48  M_F_CPU0_SA_RSP<0>  DDR5_A_RSP0  @S9S_MB_2U_LIB.S9S_MB_2U(SCH_1):M_F_CPU0_SA_RSP<0>
  EA50  M_F_CPU0_SA_PAR  DDR5_SA_PAR  @S9S_MB_2U_LIB.S9S_MB_2U(SCH_1):M_F_CPU0_SA_PAR
  EG58  M_F_CPU0_SA_DQS_DP<9>  DDR5_SA_DQS_DP9  @S9S_MB_2U_LIB.S9S_MB_2U(SCH_1):M_F_CPU0_SA_DQS_DP<9>
  DY55  M_F_CPU0_SA_DQS_DP<8>  DDR5_SA_DQS_DP8  @S9S_MB_2U_LIB.S9S_MB_2U(SCH_1):M_F_CPU0_SA_DQS_DP<8>
  EG64  M_F_CPU0_SA_DQS_DP<7>  DDR5_SA_DQS_DP7  @S9S_MB_2U_LIB.S9S_MB_2U(SCH_1):M_F_CPU0_SA_DQS_DP<7>
  DY67  M_F_CPU0_SA_DQS_DP<6>  DDR5_SA_DQS_DP6  @S9S_MB_2U_LIB.S9S_MB_2U(SCH_1):M_F_CPU0_SA_DQS_DP<6>
  EG76  M_F_CPU0_SA_DQS_DP<5>  DDR5_SA_DQS_DP5  @S9S_MB_2U_LIB.S9S_MB_2U(SCH_1):M_F_CPU0_SA_DQS_DP<5>
  EC58  M_F_CPU0_SA_DQS_DP<4>  DDR5_SA_DQS_DP4  @S9S_MB_2U_LIB.S9S_MB_2U(SCH_1):M_F_CPU0_SA_DQS_DP<4>
  DT55  M_F_CPU0_SA_DQS_DP<3>  DDR5_SA_DQS_DP3  @S9S_MB_2U_LIB.S9S_MB_2U(SCH_1):M_F_CPU0_SA_DQS_DP<3>
  EE64  M_F_CPU0_SA_DQS_DP<2>  DDR5_SA_DQS_DP2  @S9S_MB_2U_LIB.S9S_MB_2U(SCH_1):M_F_CPU0_SA_DQS_DP<2>
  DV67  M_F_CPU0_SA_DQS_DP<1>  DDR5_SA_DQS_DP1  @S9S_MB_2U_LIB.S9S_MB_2U(SCH_1):M_F_CPU0_SA_DQS_DP<1>
  EC76  M_F_CPU0_SA_DQS_DP<0>  DDR5_SA_DQS_DP0  @S9S_MB_2U_LIB.S9S_MB_2U(SCH_1):M_F_CPU0_SA_DQS_DP<0>
  EJ58  M_F_CPU0_SA_DQS_DN<9>  DDR5_SA_DQS_DN9  @S9S_MB_2U_LIB.S9S_MB_2U(SCH_1):M_F_CPU0_SA_DQS_DN<9>
  EB55  M_F_CPU0_SA_DQS_DN<8>  DDR5_SA_DQS_DN8  @S9S_MB_2U_LIB.S9S_MB_2U(SCH_1):M_F_CPU0_SA_DQS_DN<8>
  EJ64  M_F_CPU0_SA_DQS_DN<7>  DDR5_SA_DQS_DN7  @S9S_MB_2U_LIB.S9S_MB_2U(SCH_1):M_F_CPU0_SA_DQS_DN<7>
  EB67  M_F_CPU0_SA_DQS_DN<6>  DDR5_SA_DQS_DN6  @S9S_MB_2U_LIB.S9S_MB_2U(SCH_1):M_F_CPU0_SA_DQS_DN<6>
  EJ76  M_F_CPU0_SA_DQS_DN<5>  DDR5_SA_DQS_DN5  @S9S_MB_2U_LIB.S9S_MB_2U(SCH_1):M_F_CPU0_SA_DQS_DN<5>
  EE58  M_F_CPU0_SA_DQS_DN<4>  DDR5_SA_DQS_DN4  @S9S_MB_2U_LIB.S9S_MB_2U(SCH_1):M_F_CPU0_SA_DQS_DN<4>
  DV55  M_F_CPU0_SA_DQS_DN<3>  DDR5_SA_DQS_DN3  @S9S_MB_2U_LIB.S9S_MB_2U(SCH_1):M_F_CPU0_SA_DQS_DN<3>
  EC64  M_F_CPU0_SA_DQS_DN<2>  DDR5_SA_DQS_DN2  @S9S_MB_2U_LIB.S9S_MB_2U(SCH_1):M_F_CPU0_SA_DQS_DN<2>
  DT67  M_F_CPU0_SA_DQS_DN<1>  DDR5_SA_DQS_DN1  @S9S_MB_2U_LIB.S9S_MB_2U(SCH_1):M_F_CPU0_SA_DQS_DN<1>
  EE76  M_F_CPU0_SA_DQS_DN<0>  DDR5_SA_DQS_DN0  @S9S_MB_2U_LIB.S9S_MB_2U(SCH_1):M_F_CPU0_SA_DQS_DN<0>
  DU68  M_F_CPU0_SA_DQ<9>  DDR5_SA_DQ9  @S9S_MB_2U_LIB.S9S_MB_2U(SCH_1):M_F_CPU0_SA_DQ<9>
  DV69  M_F_CPU0_SA_DQ<8>  DDR5_SA_DQ8  @S9S_MB_2U_LIB.S9S_MB_2U(SCH_1):M_F_CPU0_SA_DQ<8>
  EG74  M_F_CPU0_SA_DQ<7>  DDR5_SA_DQ7  @S9S_MB_2U_LIB.S9S_MB_2U(SCH_1):M_F_CPU0_SA_DQ<7>
  EH75  M_F_CPU0_SA_DQ<6>  DDR5_SA_DQ6  @S9S_MB_2U_LIB.S9S_MB_2U(SCH_1):M_F_CPU0_SA_DQ<6>
  EE74  M_F_CPU0_SA_DQ<5>  DDR5_SA_DQ5  @S9S_MB_2U_LIB.S9S_MB_2U(SCH_1):M_F_CPU0_SA_DQ<5>
  ED75  M_F_CPU0_SA_DQ<4>  DDR5_SA_DQ4  @S9S_MB_2U_LIB.S9S_MB_2U(SCH_1):M_F_CPU0_SA_DQ<4>
  EG78  M_F_CPU0_SA_DQ<3>  DDR5_SA_DQ3  @S9S_MB_2U_LIB.S9S_MB_2U(SCH_1):M_F_CPU0_SA_DQ<3>
  DY53  M_F_CPU0_SA_DQ<31>  DDR5_SA_DQ31  @S9S_MB_2U_LIB.S9S_MB_2U(SCH_1):M_F_CPU0_SA_DQ<31>
  EA54  M_F_CPU0_SA_DQ<30>  DDR5_SA_DQ30  @S9S_MB_2U_LIB.S9S_MB_2U(SCH_1):M_F_CPU0_SA_DQ<30>
  ED77  M_F_CPU0_SA_DQ<2>  DDR5_SA_DQ2  @S9S_MB_2U_LIB.S9S_MB_2U(SCH_1):M_F_CPU0_SA_DQ<2>
  DV53  M_F_CPU0_SA_DQ<29>  DDR5_SA_DQ29  @S9S_MB_2U_LIB.S9S_MB_2U(SCH_1):M_F_CPU0_SA_DQ<29>
  DU54  M_F_CPU0_SA_DQ<28>  DDR5_SA_DQ28  @S9S_MB_2U_LIB.S9S_MB_2U(SCH_1):M_F_CPU0_SA_DQ<28>
  EA56  M_F_CPU0_SA_DQ<27>  DDR5_SA_DQ27  @S9S_MB_2U_LIB.S9S_MB_2U(SCH_1):M_F_CPU0_SA_DQ<27>
  DY57  M_F_CPU0_SA_DQ<26>  DDR5_SA_DQ26  @S9S_MB_2U_LIB.S9S_MB_2U(SCH_1):M_F_CPU0_SA_DQ<26>
  DU56  M_F_CPU0_SA_DQ<25>  DDR5_SA_DQ25  @S9S_MB_2U_LIB.S9S_MB_2U(SCH_1):M_F_CPU0_SA_DQ<25>
  DV57  M_F_CPU0_SA_DQ<24>  DDR5_SA_DQ24  @S9S_MB_2U_LIB.S9S_MB_2U(SCH_1):M_F_CPU0_SA_DQ<24>
  EG62  M_F_CPU0_SA_DQ<23>  DDR5_SA_DQ23  @S9S_MB_2U_LIB.S9S_MB_2U(SCH_1):M_F_CPU0_SA_DQ<23>
  EH63  M_F_CPU0_SA_DQ<22>  DDR5_SA_DQ22  @S9S_MB_2U_LIB.S9S_MB_2U(SCH_1):M_F_CPU0_SA_DQ<22>
  EE62  M_F_CPU0_SA_DQ<21>  DDR5_SA_DQ21  @S9S_MB_2U_LIB.S9S_MB_2U(SCH_1):M_F_CPU0_SA_DQ<21>
  ED63  M_F_CPU0_SA_DQ<20>  DDR5_SA_DQ20  @S9S_MB_2U_LIB.S9S_MB_2U(SCH_1):M_F_CPU0_SA_DQ<20>
  EH77  M_F_CPU0_SA_DQ<1>  DDR5_SA_DQ1  @S9S_MB_2U_LIB.S9S_MB_2U(SCH_1):M_F_CPU0_SA_DQ<1>
  EH65  M_F_CPU0_SA_DQ<19>  DDR5_SA_DQ19  @S9S_MB_2U_LIB.S9S_MB_2U(SCH_1):M_F_CPU0_SA_DQ<19>
  EG66  M_F_CPU0_SA_DQ<18>  DDR5_SA_DQ18  @S9S_MB_2U_LIB.S9S_MB_2U(SCH_1):M_F_CPU0_SA_DQ<18>
  ED65  M_F_CPU0_SA_DQ<17>  DDR5_SA_DQ17  @S9S_MB_2U_LIB.S9S_MB_2U(SCH_1):M_F_CPU0_SA_DQ<17>
  EE66  M_F_CPU0_SA_DQ<16>  DDR5_SA_DQ16  @S9S_MB_2U_LIB.S9S_MB_2U(SCH_1):M_F_CPU0_SA_DQ<16>
  DY65  M_F_CPU0_SA_DQ<15>  DDR5_SA_DQ15  @S9S_MB_2U_LIB.S9S_MB_2U(SCH_1):M_F_CPU0_SA_DQ<15>
  EA66  M_F_CPU0_SA_DQ<14>  DDR5_SA_DQ14  @S9S_MB_2U_LIB.S9S_MB_2U(SCH_1):M_F_CPU0_SA_DQ<14>
  DV65  M_F_CPU0_SA_DQ<13>  DDR5_SA_DQ13  @S9S_MB_2U_LIB.S9S_MB_2U(SCH_1):M_F_CPU0_SA_DQ<13>
  DU66  M_F_CPU0_SA_DQ<12>  DDR5_SA_DQ12  @S9S_MB_2U_LIB.S9S_MB_2U(SCH_1):M_F_CPU0_SA_DQ<12>
  EA68  M_F_CPU0_SA_DQ<11>  DDR5_SA_DQ11  @S9S_MB_2U_LIB.S9S_MB_2U(SCH_1):M_F_CPU0_SA_DQ<11>
  DY69  M_F_CPU0_SA_DQ<10>  DDR5_SA_DQ10  @S9S_MB_2U_LIB.S9S_MB_2U(SCH_1):M_F_CPU0_SA_DQ<10>
  EB77  M_F_CPU0_SA_DQ<0>  DDR5_SA_DQ0  @S9S_MB_2U_LIB.S9S_MB_2U(SCH_1):M_F_CPU0_SA_DQ<0>
  ED53  M_F_CPU0_SA_CS_N<3>  DDR5_SA_CS3_N  @S9S_MB_2U_LIB.S9S_MB_2U(SCH_1):M_F_CPU0_SA_CS_N<3>
  EE54  M_F_CPU0_SA_CS_N<2>  DDR5_SA_CS2_N  @S9S_MB_2U_LIB.S9S_MB_2U(SCH_1):M_F_CPU0_SA_CS_N<2>
  EH53  M_F_CPU0_SA_CS_N<1>  DDR5_SA_CS1_N  @S9S_MB_2U_LIB.S9S_MB_2U(SCH_1):M_F_CPU0_SA_CS_N<1>
  EG54  M_F_CPU0_SA_CS_N<0>  DDR5_SA_CS0_N  @S9S_MB_2U_LIB.S9S_MB_2U(SCH_1):M_F_CPU0_SA_CS_N<0>
  EG56  M_F_CPU0_SA_CB<7>  DDR5_SA_ECC7  @S9S_MB_2U_LIB.S9S_MB_2U(SCH_1):M_F_CPU0_SA_CB<7>
  EH57  M_F_CPU0_SA_CB<6>  DDR5_SA_ECC6  @S9S_MB_2U_LIB.S9S_MB_2U(SCH_1):M_F_CPU0_SA_CB<6>
  EE56  M_F_CPU0_SA_CB<5>  DDR5_SA_ECC5  @S9S_MB_2U_LIB.S9S_MB_2U(SCH_1):M_F_CPU0_SA_CB<5>
  ED57  M_F_CPU0_SA_CB<4>  DDR5_SA_ECC4  @S9S_MB_2U_LIB.S9S_MB_2U(SCH_1):M_F_CPU0_SA_CB<4>
  EH59  M_F_CPU0_SA_CB<3>  DDR5_SA_ECC3  @S9S_MB_2U_LIB.S9S_MB_2U(SCH_1):M_F_CPU0_SA_CB<3>
  EG60  M_F_CPU0_SA_CB<2>  DDR5_SA_ECC2  @S9S_MB_2U_LIB.S9S_MB_2U(SCH_1):M_F_CPU0_SA_CB<2>
  ED59  M_F_CPU0_SA_CB<1>  DDR5_SA_ECC1  @S9S_MB_2U_LIB.S9S_MB_2U(SCH_1):M_F_CPU0_SA_CB<1>
  EE60  M_F_CPU0_SA_CB<0>  DDR5_SA_ECC0  @S9S_MB_2U_LIB.S9S_MB_2U(SCH_1):M_F_CPU0_SA_CB<0>
  DY51  M_F_CPU0_SA_CA<6>  DDR5_SA_CA6  @S9S_MB_2U_LIB.S9S_MB_2U(SCH_1):M_F_CPU0_SA_CA<6>
  EG50  M_F_CPU0_SA_CA<5>  DDR5_SA_CA5  @S9S_MB_2U_LIB.S9S_MB_2U(SCH_1):M_F_CPU0_SA_CA<5>
  EE50  M_F_CPU0_SA_CA<4>  DDR5_SA_CA4  @S9S_MB_2U_LIB.S9S_MB_2U(SCH_1):M_F_CPU0_SA_CA<4>
  EH51  M_F_CPU0_SA_CA<3>  DDR5_SA_CA3  @S9S_MB_2U_LIB.S9S_MB_2U(SCH_1):M_F_CPU0_SA_CA<3>
  ED51  M_F_CPU0_SA_CA<2>  DDR5_SA_CA2  @S9S_MB_2U_LIB.S9S_MB_2U(SCH_1):M_F_CPU0_SA_CA<2>
  EJ52  M_F_CPU0_SA_CA<1>  DDR5_SA_CA1  @S9S_MB_2U_LIB.S9S_MB_2U(SCH_1):M_F_CPU0_SA_CA<1>
  EC52  M_F_CPU0_SA_CA<0>  DDR5_SA_CA0  @S9S_MB_2U_LIB.S9S_MB_2U(SCH_1):M_F_CPU0_SA_CA<0>
  DT49  M_F_CPU0_CLK_DP<1>  DDR5_CLK_DP1  @S9S_MB_2U_LIB.S9S_MB_2U(SCH_1):M_F_CPU0_CLK_DP<1>
  EB49  M_F_CPU0_CLK_DP<0>  DDR5_CLK_DP0  @S9S_MB_2U_LIB.S9S_MB_2U(SCH_1):M_F_CPU0_CLK_DP<0>
  DV49  M_F_CPU0_CLK_DN<1>  DDR5_CLK_DN1  @S9S_MB_2U_LIB.S9S_MB_2U(SCH_1):M_F_CPU0_CLK_DN<1>
  DY49  M_F_CPU0_CLK_DN<0>  DDR5_CLK_DN0  @S9S_MB_2U_LIB.S9S_MB_2U(SCH_1):M_F_CPU0_CLK_DN<0>
  CW48  M_F_CPU0_ALERT_N  DDR5_ALERT_N  @S9S_MB_2U_LIB.S9S_MB_2U(SCH_1):M_F_CPU0_ALERT_N

SOCKET4677_AZIFS054P001C01  I169  U2     [SOCKET4677_AZIFS054P001C01-SOCA]
  DG43  M_E_CPU0_SB_RSP<1>  DDR4_B_RSP1  @S9S_MB_2U_LIB.S9S_MB_2U(SCH_1):M_E_CPU0_SB_RSP<1>
  DF44  M_E_CPU0_SB_RSP<0>  DDR4_B_RSP0  @S9S_MB_2U_LIB.S9S_MB_2U(SCH_1):M_E_CPU0_SB_RSP<0>
  EP42  M_E_CPU0_SB_PAR  DDR4_SB_PAR  @S9S_MB_2U_LIB.S9S_MB_2U(SCH_1):M_E_CPU0_SB_PAR
  EM36  M_E_CPU0_SB_DQS_DP<9>  DDR4_SB_DQS_DP9  @S9S_MB_2U_LIB.S9S_MB_2U(SCH_1):M_E_CPU0_SB_DQS_DP<9>
  EP18  M_E_CPU0_SB_DQS_DP<8>  DDR4_SB_DQS_DP8  @S9S_MB_2U_LIB.S9S_MB_2U(SCH_1):M_E_CPU0_SB_DQS_DP<8>
  EP24  M_E_CPU0_SB_DQS_DP<7>  DDR4_SB_DQS_DP7  @S9S_MB_2U_LIB.S9S_MB_2U(SCH_1):M_E_CPU0_SB_DQS_DP<7>
  EP30  M_E_CPU0_SB_DQS_DP<6>  DDR4_SB_DQS_DP6  @S9S_MB_2U_LIB.S9S_MB_2U(SCH_1):M_E_CPU0_SB_DQS_DP<6>
  EG27  M_E_CPU0_SB_DQS_DP<5>  DDR4_SB_DQS_DP5  @S9S_MB_2U_LIB.S9S_MB_2U(SCH_1):M_E_CPU0_SB_DQS_DP<5>
  EP36  M_E_CPU0_SB_DQS_DP<4>  DDR4_SB_DQS_DP4  @S9S_MB_2U_LIB.S9S_MB_2U(SCH_1):M_E_CPU0_SB_DQS_DP<4>
  EM18  M_E_CPU0_SB_DQS_DP<3>  DDR4_SB_DQS_DP3  @S9S_MB_2U_LIB.S9S_MB_2U(SCH_1):M_E_CPU0_SB_DQS_DP<3>
  EM24  M_E_CPU0_SB_DQS_DP<2>  DDR4_SB_DQS_DP2  @S9S_MB_2U_LIB.S9S_MB_2U(SCH_1):M_E_CPU0_SB_DQS_DP<2>
  EM30  M_E_CPU0_SB_DQS_DP<1>  DDR4_SB_DQS_DP1  @S9S_MB_2U_LIB.S9S_MB_2U(SCH_1):M_E_CPU0_SB_DQS_DP<1>
  EC27  M_E_CPU0_SB_DQS_DP<0>  DDR4_SB_DQS_DP0  @S9S_MB_2U_LIB.S9S_MB_2U(SCH_1):M_E_CPU0_SB_DQS_DP<0>
  EK36  M_E_CPU0_SB_DQS_DN<9>  DDR4_SB_DQS_DN9  @S9S_MB_2U_LIB.S9S_MB_2U(SCH_1):M_E_CPU0_SB_DQS_DN<9>
  ET18  M_E_CPU0_SB_DQS_DN<8>  DDR4_SB_DQS_DN8  @S9S_MB_2U_LIB.S9S_MB_2U(SCH_1):M_E_CPU0_SB_DQS_DN<8>
  ET24  M_E_CPU0_SB_DQS_DN<7>  DDR4_SB_DQS_DN7  @S9S_MB_2U_LIB.S9S_MB_2U(SCH_1):M_E_CPU0_SB_DQS_DN<7>
  ET30  M_E_CPU0_SB_DQS_DN<6>  DDR4_SB_DQS_DN6  @S9S_MB_2U_LIB.S9S_MB_2U(SCH_1):M_E_CPU0_SB_DQS_DN<6>
  EJ27  M_E_CPU0_SB_DQS_DN<5>  DDR4_SB_DQS_DN5  @S9S_MB_2U_LIB.S9S_MB_2U(SCH_1):M_E_CPU0_SB_DQS_DN<5>
  ET36  M_E_CPU0_SB_DQS_DN<4>  DDR4_SB_DQS_DN4  @S9S_MB_2U_LIB.S9S_MB_2U(SCH_1):M_E_CPU0_SB_DQS_DN<4>
  EK18  M_E_CPU0_SB_DQS_DN<3>  DDR4_SB_DQS_DN3  @S9S_MB_2U_LIB.S9S_MB_2U(SCH_1):M_E_CPU0_SB_DQS_DN<3>
  EK24  M_E_CPU0_SB_DQS_DN<2>  DDR4_SB_DQS_DN2  @S9S_MB_2U_LIB.S9S_MB_2U(SCH_1):M_E_CPU0_SB_DQS_DN<2>
  EK30  M_E_CPU0_SB_DQS_DN<1>  DDR4_SB_DQS_DN1  @S9S_MB_2U_LIB.S9S_MB_2U(SCH_1):M_E_CPU0_SB_DQS_DN<1>
  EE27  M_E_CPU0_SB_DQS_DN<0>  DDR4_SB_DQS_DN0  @S9S_MB_2U_LIB.S9S_MB_2U(SCH_1):M_E_CPU0_SB_DQS_DN<0>
  EL31  M_E_CPU0_SB_DQ<9>  DDR4_SB_DQ9  @S9S_MB_2U_LIB.S9S_MB_2U(SCH_1):M_E_CPU0_SB_DQ<9>
  EM32  M_E_CPU0_SB_DQ<8>  DDR4_SB_DQ8  @S9S_MB_2U_LIB.S9S_MB_2U(SCH_1):M_E_CPU0_SB_DQ<8>
  EG25  M_E_CPU0_SB_DQ<7>  DDR4_SB_DQ7  @S9S_MB_2U_LIB.S9S_MB_2U(SCH_1):M_E_CPU0_SB_DQ<7>
  EH26  M_E_CPU0_SB_DQ<6>  DDR4_SB_DQ6  @S9S_MB_2U_LIB.S9S_MB_2U(SCH_1):M_E_CPU0_SB_DQ<6>
  EE25  M_E_CPU0_SB_DQ<5>  DDR4_SB_DQ5  @S9S_MB_2U_LIB.S9S_MB_2U(SCH_1):M_E_CPU0_SB_DQ<5>
  ED26  M_E_CPU0_SB_DQ<4>  DDR4_SB_DQ4  @S9S_MB_2U_LIB.S9S_MB_2U(SCH_1):M_E_CPU0_SB_DQ<4>
  EH28  M_E_CPU0_SB_DQ<3>  DDR4_SB_DQ3  @S9S_MB_2U_LIB.S9S_MB_2U(SCH_1):M_E_CPU0_SB_DQ<3>
  EP16  M_E_CPU0_SB_DQ<31>  DDR4_SB_DQ31  @S9S_MB_2U_LIB.S9S_MB_2U(SCH_1):M_E_CPU0_SB_DQ<31>
  ER17  M_E_CPU0_SB_DQ<30>  DDR4_SB_DQ30  @S9S_MB_2U_LIB.S9S_MB_2U(SCH_1):M_E_CPU0_SB_DQ<30>
  EG29  M_E_CPU0_SB_DQ<2>  DDR4_SB_DQ2  @S9S_MB_2U_LIB.S9S_MB_2U(SCH_1):M_E_CPU0_SB_DQ<2>
  EM16  M_E_CPU0_SB_DQ<29>  DDR4_SB_DQ29  @S9S_MB_2U_LIB.S9S_MB_2U(SCH_1):M_E_CPU0_SB_DQ<29>
  EL17  M_E_CPU0_SB_DQ<28>  DDR4_SB_DQ28  @S9S_MB_2U_LIB.S9S_MB_2U(SCH_1):M_E_CPU0_SB_DQ<28>
  ER19  M_E_CPU0_SB_DQ<27>  DDR4_SB_DQ27  @S9S_MB_2U_LIB.S9S_MB_2U(SCH_1):M_E_CPU0_SB_DQ<27>
  EP20  M_E_CPU0_SB_DQ<26>  DDR4_SB_DQ26  @S9S_MB_2U_LIB.S9S_MB_2U(SCH_1):M_E_CPU0_SB_DQ<26>
  EL19  M_E_CPU0_SB_DQ<25>  DDR4_SB_DQ25  @S9S_MB_2U_LIB.S9S_MB_2U(SCH_1):M_E_CPU0_SB_DQ<25>
  EM20  M_E_CPU0_SB_DQ<24>  DDR4_SB_DQ24  @S9S_MB_2U_LIB.S9S_MB_2U(SCH_1):M_E_CPU0_SB_DQ<24>
  EP22  M_E_CPU0_SB_DQ<23>  DDR4_SB_DQ23  @S9S_MB_2U_LIB.S9S_MB_2U(SCH_1):M_E_CPU0_SB_DQ<23>
  ER23  M_E_CPU0_SB_DQ<22>  DDR4_SB_DQ22  @S9S_MB_2U_LIB.S9S_MB_2U(SCH_1):M_E_CPU0_SB_DQ<22>
  EM22  M_E_CPU0_SB_DQ<21>  DDR4_SB_DQ21  @S9S_MB_2U_LIB.S9S_MB_2U(SCH_1):M_E_CPU0_SB_DQ<21>
  EL23  M_E_CPU0_SB_DQ<20>  DDR4_SB_DQ20  @S9S_MB_2U_LIB.S9S_MB_2U(SCH_1):M_E_CPU0_SB_DQ<20>
  ED28  M_E_CPU0_SB_DQ<1>  DDR4_SB_DQ1  @S9S_MB_2U_LIB.S9S_MB_2U(SCH_1):M_E_CPU0_SB_DQ<1>
  ER25  M_E_CPU0_SB_DQ<19>  DDR4_SB_DQ19  @S9S_MB_2U_LIB.S9S_MB_2U(SCH_1):M_E_CPU0_SB_DQ<19>
  EP26  M_E_CPU0_SB_DQ<18>  DDR4_SB_DQ18  @S9S_MB_2U_LIB.S9S_MB_2U(SCH_1):M_E_CPU0_SB_DQ<18>
  EL25  M_E_CPU0_SB_DQ<17>  DDR4_SB_DQ17  @S9S_MB_2U_LIB.S9S_MB_2U(SCH_1):M_E_CPU0_SB_DQ<17>
  EM26  M_E_CPU0_SB_DQ<16>  DDR4_SB_DQ16  @S9S_MB_2U_LIB.S9S_MB_2U(SCH_1):M_E_CPU0_SB_DQ<16>
  EP28  M_E_CPU0_SB_DQ<15>  DDR4_SB_DQ15  @S9S_MB_2U_LIB.S9S_MB_2U(SCH_1):M_E_CPU0_SB_DQ<15>
  ER29  M_E_CPU0_SB_DQ<14>  DDR4_SB_DQ14  @S9S_MB_2U_LIB.S9S_MB_2U(SCH_1):M_E_CPU0_SB_DQ<14>
  EM28  M_E_CPU0_SB_DQ<13>  DDR4_SB_DQ13  @S9S_MB_2U_LIB.S9S_MB_2U(SCH_1):M_E_CPU0_SB_DQ<13>
  EL29  M_E_CPU0_SB_DQ<12>  DDR4_SB_DQ12  @S9S_MB_2U_LIB.S9S_MB_2U(SCH_1):M_E_CPU0_SB_DQ<12>
  ER31  M_E_CPU0_SB_DQ<11>  DDR4_SB_DQ11  @S9S_MB_2U_LIB.S9S_MB_2U(SCH_1):M_E_CPU0_SB_DQ<11>
  EP32  M_E_CPU0_SB_DQ<10>  DDR4_SB_DQ10  @S9S_MB_2U_LIB.S9S_MB_2U(SCH_1):M_E_CPU0_SB_DQ<10>
  EE29  M_E_CPU0_SB_DQ<0>  DDR4_SB_DQ0  @S9S_MB_2U_LIB.S9S_MB_2U(SCH_1):M_E_CPU0_SB_DQ<0>
  EL41  M_E_CPU0_SB_CS_N<3>  DDR4_SB_CS3_N  @S9S_MB_2U_LIB.S9S_MB_2U(SCH_1):M_E_CPU0_SB_CS_N<3>
  EM40  M_E_CPU0_SB_CS_N<2>  DDR4_SB_CS2_N  @S9S_MB_2U_LIB.S9S_MB_2U(SCH_1):M_E_CPU0_SB_CS_N<2>
  ET40  M_E_CPU0_SB_CS_N<1>  DDR4_SB_CS1_N  @S9S_MB_2U_LIB.S9S_MB_2U(SCH_1):M_E_CPU0_SB_CS_N<1>
  EP40  M_E_CPU0_SB_CS_N<0>  DDR4_SB_CS0_N  @S9S_MB_2U_LIB.S9S_MB_2U(SCH_1):M_E_CPU0_SB_CS_N<0>
  ER37  M_E_CPU0_SB_CB<7>  DDR4_SB_ECC7  @S9S_MB_2U_LIB.S9S_MB_2U(SCH_1):M_E_CPU0_SB_CB<7>
  EP38  M_E_CPU0_SB_CB<6>  DDR4_SB_ECC6  @S9S_MB_2U_LIB.S9S_MB_2U(SCH_1):M_E_CPU0_SB_CB<6>
  EL37  M_E_CPU0_SB_CB<5>  DDR4_SB_ECC5  @S9S_MB_2U_LIB.S9S_MB_2U(SCH_1):M_E_CPU0_SB_CB<5>
  EM38  M_E_CPU0_SB_CB<4>  DDR4_SB_ECC4  @S9S_MB_2U_LIB.S9S_MB_2U(SCH_1):M_E_CPU0_SB_CB<4>
  EP34  M_E_CPU0_SB_CB<3>  DDR4_SB_ECC3  @S9S_MB_2U_LIB.S9S_MB_2U(SCH_1):M_E_CPU0_SB_CB<3>
  ER35  M_E_CPU0_SB_CB<2>  DDR4_SB_ECC2  @S9S_MB_2U_LIB.S9S_MB_2U(SCH_1):M_E_CPU0_SB_CB<2>
  EM34  M_E_CPU0_SB_CB<1>  DDR4_SB_ECC1  @S9S_MB_2U_LIB.S9S_MB_2U(SCH_1):M_E_CPU0_SB_CB<1>
  EL35  M_E_CPU0_SB_CB<0>  DDR4_SB_ECC0  @S9S_MB_2U_LIB.S9S_MB_2U(SCH_1):M_E_CPU0_SB_CB<0>
  EK42  M_E_CPU0_SB_CA<6>  DDR4_SB_CA6  @S9S_MB_2U_LIB.S9S_MB_2U(SCH_1):M_E_CPU0_SB_CA<6>
  ET42  M_E_CPU0_SB_CA<5>  DDR4_SB_CA5  @S9S_MB_2U_LIB.S9S_MB_2U(SCH_1):M_E_CPU0_SB_CA<5>
  EL43  M_E_CPU0_SB_CA<4>  DDR4_SB_CA4  @S9S_MB_2U_LIB.S9S_MB_2U(SCH_1):M_E_CPU0_SB_CA<4>
  EP44  M_E_CPU0_SB_CA<3>  DDR4_SB_CA3  @S9S_MB_2U_LIB.S9S_MB_2U(SCH_1):M_E_CPU0_SB_CA<3>
  EM44  M_E_CPU0_SB_CA<2>  DDR4_SB_CA2  @S9S_MB_2U_LIB.S9S_MB_2U(SCH_1):M_E_CPU0_SB_CA<2>
  EH44  M_E_CPU0_SB_CA<1>  DDR4_SB_CA1  @S9S_MB_2U_LIB.S9S_MB_2U(SCH_1):M_E_CPU0_SB_CA<1>
  EG43  M_E_CPU0_SB_CA<0>  DDR4_SB_CA0  @S9S_MB_2U_LIB.S9S_MB_2U(SCH_1):M_E_CPU0_SB_CA<0>
  DC43  M_E_CPU0_SA_RSP<1>  DDR4_A_RSP1  @S9S_MB_2U_LIB.S9S_MB_2U(SCH_1):M_E_CPU0_SA_RSP<1>
  DD44  M_E_CPU0_SA_RSP<0>  DDR4_A_RSP0  @S9S_MB_2U_LIB.S9S_MB_2U(SCH_1):M_E_CPU0_SA_RSP<0>
  EE43  M_E_CPU0_SA_PAR  DDR4_SA_PAR  @S9S_MB_2U_LIB.S9S_MB_2U(SCH_1):M_E_CPU0_SA_PAR
  EP55  M_E_CPU0_SA_DQS_DP<9>  DDR4_SA_DQS_DP9  @S9S_MB_2U_LIB.S9S_MB_2U(SCH_1):M_E_CPU0_SA_DQS_DP<9>
  EP61  M_E_CPU0_SA_DQS_DP<8>  DDR4_SA_DQS_DP8  @S9S_MB_2U_LIB.S9S_MB_2U(SCH_1):M_E_CPU0_SA_DQS_DP<8>
  EM67  M_E_CPU0_SA_DQS_DP<7>  DDR4_SA_DQS_DP7  @S9S_MB_2U_LIB.S9S_MB_2U(SCH_1):M_E_CPU0_SA_DQS_DP<7>
  EG70  M_E_CPU0_SA_DQS_DP<6>  DDR4_SA_DQS_DP6  @S9S_MB_2U_LIB.S9S_MB_2U(SCH_1):M_E_CPU0_SA_DQS_DP<6>
  EN74  M_E_CPU0_SA_DQS_DP<5>  DDR4_SA_DQS_DP5  @S9S_MB_2U_LIB.S9S_MB_2U(SCH_1):M_E_CPU0_SA_DQS_DP<5>
  EK55  M_E_CPU0_SA_DQS_DP<4>  DDR4_SA_DQS_DP4  @S9S_MB_2U_LIB.S9S_MB_2U(SCH_1):M_E_CPU0_SA_DQS_DP<4>
  EM61  M_E_CPU0_SA_DQS_DP<3>  DDR4_SA_DQS_DP3  @S9S_MB_2U_LIB.S9S_MB_2U(SCH_1):M_E_CPU0_SA_DQS_DP<3>
  EL68  M_E_CPU0_SA_DQS_DP<2>  DDR4_SA_DQS_DP2  @S9S_MB_2U_LIB.S9S_MB_2U(SCH_1):M_E_CPU0_SA_DQS_DP<2>
  EE70  M_E_CPU0_SA_DQS_DP<1>  DDR4_SA_DQS_DP1  @S9S_MB_2U_LIB.S9S_MB_2U(SCH_1):M_E_CPU0_SA_DQS_DP<1>
  EN76  M_E_CPU0_SA_DQS_DP<0>  DDR4_SA_DQS_DP0  @S9S_MB_2U_LIB.S9S_MB_2U(SCH_1):M_E_CPU0_SA_DQS_DP<0>
  ET55  M_E_CPU0_SA_DQS_DN<9>  DDR4_SA_DQS_DN9  @S9S_MB_2U_LIB.S9S_MB_2U(SCH_1):M_E_CPU0_SA_DQS_DN<9>
  ET61  M_E_CPU0_SA_DQS_DN<8>  DDR4_SA_DQS_DN8  @S9S_MB_2U_LIB.S9S_MB_2U(SCH_1):M_E_CPU0_SA_DQS_DN<8>
  EN68  M_E_CPU0_SA_DQS_DN<7>  DDR4_SA_DQS_DN7  @S9S_MB_2U_LIB.S9S_MB_2U(SCH_1):M_E_CPU0_SA_DQS_DN<7>
  EJ70  M_E_CPU0_SA_DQS_DN<6>  DDR4_SA_DQS_DN6  @S9S_MB_2U_LIB.S9S_MB_2U(SCH_1):M_E_CPU0_SA_DQS_DN<6>
  EM75  M_E_CPU0_SA_DQS_DN<5>  DDR4_SA_DQS_DN5  @S9S_MB_2U_LIB.S9S_MB_2U(SCH_1):M_E_CPU0_SA_DQS_DN<5>
  EM55  M_E_CPU0_SA_DQS_DN<4>  DDR4_SA_DQS_DN4  @S9S_MB_2U_LIB.S9S_MB_2U(SCH_1):M_E_CPU0_SA_DQS_DN<4>
  EK61  M_E_CPU0_SA_DQS_DN<3>  DDR4_SA_DQS_DN3  @S9S_MB_2U_LIB.S9S_MB_2U(SCH_1):M_E_CPU0_SA_DQS_DN<3>
  EK67  M_E_CPU0_SA_DQS_DN<2>  DDR4_SA_DQS_DN2  @S9S_MB_2U_LIB.S9S_MB_2U(SCH_1):M_E_CPU0_SA_DQS_DN<2>
  EC70  M_E_CPU0_SA_DQS_DN<1>  DDR4_SA_DQS_DN1  @S9S_MB_2U_LIB.S9S_MB_2U(SCH_1):M_E_CPU0_SA_DQS_DN<1>
  EP75  M_E_CPU0_SA_DQS_DN<0>  DDR4_SA_DQS_DN0  @S9S_MB_2U_LIB.S9S_MB_2U(SCH_1):M_E_CPU0_SA_DQS_DN<0>
  ED71  M_E_CPU0_SA_DQ<9>  DDR4_SA_DQ9  @S9S_MB_2U_LIB.S9S_MB_2U(SCH_1):M_E_CPU0_SA_DQ<9>
  EE72  M_E_CPU0_SA_DQ<8>  DDR4_SA_DQ8  @S9S_MB_2U_LIB.S9S_MB_2U(SCH_1):M_E_CPU0_SA_DQ<8>
  ER72  M_E_CPU0_SA_DQ<7>  DDR4_SA_DQ7  @S9S_MB_2U_LIB.S9S_MB_2U(SCH_1):M_E_CPU0_SA_DQ<7>
  EP73  M_E_CPU0_SA_DQ<6>  DDR4_SA_DQ6  @S9S_MB_2U_LIB.S9S_MB_2U(SCH_1):M_E_CPU0_SA_DQ<6>
  EK73  M_E_CPU0_SA_DQ<5>  DDR4_SA_DQ5  @S9S_MB_2U_LIB.S9S_MB_2U(SCH_1):M_E_CPU0_SA_DQ<5>
  EL74  M_E_CPU0_SA_DQ<4>  DDR4_SA_DQ4  @S9S_MB_2U_LIB.S9S_MB_2U(SCH_1):M_E_CPU0_SA_DQ<4>
  ER76  M_E_CPU0_SA_DQ<3>  DDR4_SA_DQ3  @S9S_MB_2U_LIB.S9S_MB_2U(SCH_1):M_E_CPU0_SA_DQ<3>
  EP59  M_E_CPU0_SA_DQ<31>  DDR4_SA_DQ31  @S9S_MB_2U_LIB.S9S_MB_2U(SCH_1):M_E_CPU0_SA_DQ<31>
  ER60  M_E_CPU0_SA_DQ<30>  DDR4_SA_DQ30  @S9S_MB_2U_LIB.S9S_MB_2U(SCH_1):M_E_CPU0_SA_DQ<30>
  EP79  M_E_CPU0_SA_DQ<2>  DDR4_SA_DQ2  @S9S_MB_2U_LIB.S9S_MB_2U(SCH_1):M_E_CPU0_SA_DQ<2>
  EM59  M_E_CPU0_SA_DQ<29>  DDR4_SA_DQ29  @S9S_MB_2U_LIB.S9S_MB_2U(SCH_1):M_E_CPU0_SA_DQ<29>
  EL60  M_E_CPU0_SA_DQ<28>  DDR4_SA_DQ28  @S9S_MB_2U_LIB.S9S_MB_2U(SCH_1):M_E_CPU0_SA_DQ<28>
  ER62  M_E_CPU0_SA_DQ<27>  DDR4_SA_DQ27  @S9S_MB_2U_LIB.S9S_MB_2U(SCH_1):M_E_CPU0_SA_DQ<27>
  EP63  M_E_CPU0_SA_DQ<26>  DDR4_SA_DQ26  @S9S_MB_2U_LIB.S9S_MB_2U(SCH_1):M_E_CPU0_SA_DQ<26>
  EL62  M_E_CPU0_SA_DQ<25>  DDR4_SA_DQ25  @S9S_MB_2U_LIB.S9S_MB_2U(SCH_1):M_E_CPU0_SA_DQ<25>
  EM63  M_E_CPU0_SA_DQ<24>  DDR4_SA_DQ24  @S9S_MB_2U_LIB.S9S_MB_2U(SCH_1):M_E_CPU0_SA_DQ<24>
  EP65  M_E_CPU0_SA_DQ<23>  DDR4_SA_DQ23  @S9S_MB_2U_LIB.S9S_MB_2U(SCH_1):M_E_CPU0_SA_DQ<23>
  EL66  M_E_CPU0_SA_DQ<22>  DDR4_SA_DQ22  @S9S_MB_2U_LIB.S9S_MB_2U(SCH_1):M_E_CPU0_SA_DQ<22>
  EM65  M_E_CPU0_SA_DQ<21>  DDR4_SA_DQ21  @S9S_MB_2U_LIB.S9S_MB_2U(SCH_1):M_E_CPU0_SA_DQ<21>
  ER66  M_E_CPU0_SA_DQ<20>  DDR4_SA_DQ20  @S9S_MB_2U_LIB.S9S_MB_2U(SCH_1):M_E_CPU0_SA_DQ<20>
  EM77  M_E_CPU0_SA_DQ<1>  DDR4_SA_DQ1  @S9S_MB_2U_LIB.S9S_MB_2U(SCH_1):M_E_CPU0_SA_DQ<1>
  ER68  M_E_CPU0_SA_DQ<19>  DDR4_SA_DQ19  @S9S_MB_2U_LIB.S9S_MB_2U(SCH_1):M_E_CPU0_SA_DQ<19>
  EN70  M_E_CPU0_SA_DQ<18>  DDR4_SA_DQ18  @S9S_MB_2U_LIB.S9S_MB_2U(SCH_1):M_E_CPU0_SA_DQ<18>
  EM69  M_E_CPU0_SA_DQ<17>  DDR4_SA_DQ17  @S9S_MB_2U_LIB.S9S_MB_2U(SCH_1):M_E_CPU0_SA_DQ<17>
  EM71  M_E_CPU0_SA_DQ<16>  DDR4_SA_DQ16  @S9S_MB_2U_LIB.S9S_MB_2U(SCH_1):M_E_CPU0_SA_DQ<16>
  EG68  M_E_CPU0_SA_DQ<15>  DDR4_SA_DQ15  @S9S_MB_2U_LIB.S9S_MB_2U(SCH_1):M_E_CPU0_SA_DQ<15>
  EH69  M_E_CPU0_SA_DQ<14>  DDR4_SA_DQ14  @S9S_MB_2U_LIB.S9S_MB_2U(SCH_1):M_E_CPU0_SA_DQ<14>
  EE68  M_E_CPU0_SA_DQ<13>  DDR4_SA_DQ13  @S9S_MB_2U_LIB.S9S_MB_2U(SCH_1):M_E_CPU0_SA_DQ<13>
  ED69  M_E_CPU0_SA_DQ<12>  DDR4_SA_DQ12  @S9S_MB_2U_LIB.S9S_MB_2U(SCH_1):M_E_CPU0_SA_DQ<12>
  EH71  M_E_CPU0_SA_DQ<11>  DDR4_SA_DQ11  @S9S_MB_2U_LIB.S9S_MB_2U(SCH_1):M_E_CPU0_SA_DQ<11>
  EG72  M_E_CPU0_SA_DQ<10>  DDR4_SA_DQ10  @S9S_MB_2U_LIB.S9S_MB_2U(SCH_1):M_E_CPU0_SA_DQ<10>
  EL78  M_E_CPU0_SA_DQ<0>  DDR4_SA_DQ0  @S9S_MB_2U_LIB.S9S_MB_2U(SCH_1):M_E_CPU0_SA_DQ<0>
  EL50  M_E_CPU0_SA_CS_N<3>  DDR4_SA_CS3_N  @S9S_MB_2U_LIB.S9S_MB_2U(SCH_1):M_E_CPU0_SA_CS_N<3>
  EM51  M_E_CPU0_SA_CS_N<2>  DDR4_SA_CS2_N  @S9S_MB_2U_LIB.S9S_MB_2U(SCH_1):M_E_CPU0_SA_CS_N<2>
  ET51  M_E_CPU0_SA_CS_N<1>  DDR4_SA_CS1_N  @S9S_MB_2U_LIB.S9S_MB_2U(SCH_1):M_E_CPU0_SA_CS_N<1>
  EP51  M_E_CPU0_SA_CS_N<0>  DDR4_SA_CS0_N  @S9S_MB_2U_LIB.S9S_MB_2U(SCH_1):M_E_CPU0_SA_CS_N<0>
  EP53  M_E_CPU0_SA_CB<7>  DDR4_SA_ECC7  @S9S_MB_2U_LIB.S9S_MB_2U(SCH_1):M_E_CPU0_SA_CB<7>
  ER54  M_E_CPU0_SA_CB<6>  DDR4_SA_ECC6  @S9S_MB_2U_LIB.S9S_MB_2U(SCH_1):M_E_CPU0_SA_CB<6>
  EM53  M_E_CPU0_SA_CB<5>  DDR4_SA_ECC5  @S9S_MB_2U_LIB.S9S_MB_2U(SCH_1):M_E_CPU0_SA_CB<5>
  EL54  M_E_CPU0_SA_CB<4>  DDR4_SA_ECC4  @S9S_MB_2U_LIB.S9S_MB_2U(SCH_1):M_E_CPU0_SA_CB<4>
  ER56  M_E_CPU0_SA_CB<3>  DDR4_SA_ECC3  @S9S_MB_2U_LIB.S9S_MB_2U(SCH_1):M_E_CPU0_SA_CB<3>
  EP57  M_E_CPU0_SA_CB<2>  DDR4_SA_ECC2  @S9S_MB_2U_LIB.S9S_MB_2U(SCH_1):M_E_CPU0_SA_CB<2>
  EL56  M_E_CPU0_SA_CB<1>  DDR4_SA_ECC1  @S9S_MB_2U_LIB.S9S_MB_2U(SCH_1):M_E_CPU0_SA_CB<1>
  EM57  M_E_CPU0_SA_CB<0>  DDR4_SA_ECC0  @S9S_MB_2U_LIB.S9S_MB_2U(SCH_1):M_E_CPU0_SA_CB<0>
  ED44  M_E_CPU0_SA_CA<6>  DDR4_SA_CA6  @S9S_MB_2U_LIB.S9S_MB_2U(SCH_1):M_E_CPU0_SA_CA<6>
  EP47  M_E_CPU0_SA_CA<5>  DDR4_SA_CA5  @S9S_MB_2U_LIB.S9S_MB_2U(SCH_1):M_E_CPU0_SA_CA<5>
  EM47  M_E_CPU0_SA_CA<4>  DDR4_SA_CA4  @S9S_MB_2U_LIB.S9S_MB_2U(SCH_1):M_E_CPU0_SA_CA<4>
  EL48  M_E_CPU0_SA_CA<3>  DDR4_SA_CA3  @S9S_MB_2U_LIB.S9S_MB_2U(SCH_1):M_E_CPU0_SA_CA<3>
  EK49  M_E_CPU0_SA_CA<2>  DDR4_SA_CA2  @S9S_MB_2U_LIB.S9S_MB_2U(SCH_1):M_E_CPU0_SA_CA<2>
  ET49  M_E_CPU0_SA_CA<1>  DDR4_SA_CA1  @S9S_MB_2U_LIB.S9S_MB_2U(SCH_1):M_E_CPU0_SA_CA<1>
  EP49  M_E_CPU0_SA_CA<0>  DDR4_SA_CA0  @S9S_MB_2U_LIB.S9S_MB_2U(SCH_1):M_E_CPU0_SA_CA<0>
  EC45  M_E_CPU0_CLK_DP<1>  DDR4_CLK_DP1  @S9S_MB_2U_LIB.S9S_MB_2U(SCH_1):M_E_CPU0_CLK_DP<1>
  EG45  M_E_CPU0_CLK_DP<0>  DDR4_CLK_DP0  @S9S_MB_2U_LIB.S9S_MB_2U(SCH_1):M_E_CPU0_CLK_DP<0>
  EE45  M_E_CPU0_CLK_DN<1>  DDR4_CLK_DN1  @S9S_MB_2U_LIB.S9S_MB_2U(SCH_1):M_E_CPU0_CLK_DN<1>
  EJ45  M_E_CPU0_CLK_DN<0>  DDR4_CLK_DN0  @S9S_MB_2U_LIB.S9S_MB_2U(SCH_1):M_E_CPU0_CLK_DN<0>
  CY47  M_E_CPU0_ALERT_N  DDR4_ALERT_N  @S9S_MB_2U_LIB.S9S_MB_2U(SCH_1):M_E_CPU0_ALERT_N

SOCKET4677_AZIFS054P001C01  I169  U2     [SOCKET4677_AZIFS054P001C01-SOCA]
  AG50  M_D_CPU0_SB_RSP<1>  DDR3_B_RSP1  @S9S_MB_2U_LIB.S9S_MB_2U(SCH_1):M_D_CPU0_SB_RSP<1>
  AF51  M_D_CPU0_SB_RSP<0>  DDR3_B_RSP0  @S9S_MB_2U_LIB.S9S_MB_2U(SCH_1):M_D_CPU0_SB_RSP<0>
  AH42  M_D_CPU0_SB_PAR  DDR3_SB_PAR  @S9S_MB_2U_LIB.S9S_MB_2U(SCH_1):M_D_CPU0_SB_PAR
  AL39  M_D_CPU0_SB_DQS_DP<9>  DDR3_SB_DQS_DP9  @S9S_MB_2U_LIB.S9S_MB_2U(SCH_1):M_D_CPU0_SB_DQS_DP<9>
  AR21  M_D_CPU0_SB_DQS_DP<8>  DDR3_SB_DQS_DP8  @S9S_MB_2U_LIB.S9S_MB_2U(SCH_1):M_D_CPU0_SB_DQS_DP<8>
  AH24  M_D_CPU0_SB_DQS_DP<7>  DDR3_SB_DQS_DP7  @S9S_MB_2U_LIB.S9S_MB_2U(SCH_1):M_D_CPU0_SB_DQS_DP<7>
  AR27  M_D_CPU0_SB_DQS_DP<6>  DDR3_SB_DQS_DP6  @S9S_MB_2U_LIB.S9S_MB_2U(SCH_1):M_D_CPU0_SB_DQS_DP<6>
  AR33  M_D_CPU0_SB_DQS_DP<5>  DDR3_SB_DQS_DP5  @S9S_MB_2U_LIB.S9S_MB_2U(SCH_1):M_D_CPU0_SB_DQS_DP<5>
  AN39  M_D_CPU0_SB_DQS_DP<4>  DDR3_SB_DQS_DP4  @S9S_MB_2U_LIB.S9S_MB_2U(SCH_1):M_D_CPU0_SB_DQS_DP<4>
  AL21  M_D_CPU0_SB_DQS_DP<3>  DDR3_SB_DQS_DP3  @S9S_MB_2U_LIB.S9S_MB_2U(SCH_1):M_D_CPU0_SB_DQS_DP<3>
  AD24  M_D_CPU0_SB_DQS_DP<2>  DDR3_SB_DQS_DP2  @S9S_MB_2U_LIB.S9S_MB_2U(SCH_1):M_D_CPU0_SB_DQS_DP<2>
  AL27  M_D_CPU0_SB_DQS_DP<1>  DDR3_SB_DQS_DP1  @S9S_MB_2U_LIB.S9S_MB_2U(SCH_1):M_D_CPU0_SB_DQS_DP<1>
  AL33  M_D_CPU0_SB_DQS_DP<0>  DDR3_SB_DQS_DP0  @S9S_MB_2U_LIB.S9S_MB_2U(SCH_1):M_D_CPU0_SB_DQS_DP<0>
  AJ39  M_D_CPU0_SB_DQS_DN<9>  DDR3_SB_DQS_DN9  @S9S_MB_2U_LIB.S9S_MB_2U(SCH_1):M_D_CPU0_SB_DQS_DN<9>
  AN21  M_D_CPU0_SB_DQS_DN<8>  DDR3_SB_DQS_DN8  @S9S_MB_2U_LIB.S9S_MB_2U(SCH_1):M_D_CPU0_SB_DQS_DN<8>
  AF24  M_D_CPU0_SB_DQS_DN<7>  DDR3_SB_DQS_DN7  @S9S_MB_2U_LIB.S9S_MB_2U(SCH_1):M_D_CPU0_SB_DQS_DN<7>
  AN27  M_D_CPU0_SB_DQS_DN<6>  DDR3_SB_DQS_DN6  @S9S_MB_2U_LIB.S9S_MB_2U(SCH_1):M_D_CPU0_SB_DQS_DN<6>
  AN33  M_D_CPU0_SB_DQS_DN<5>  DDR3_SB_DQS_DN5  @S9S_MB_2U_LIB.S9S_MB_2U(SCH_1):M_D_CPU0_SB_DQS_DN<5>
  AR39  M_D_CPU0_SB_DQS_DN<4>  DDR3_SB_DQS_DN4  @S9S_MB_2U_LIB.S9S_MB_2U(SCH_1):M_D_CPU0_SB_DQS_DN<4>
  AJ21  M_D_CPU0_SB_DQS_DN<3>  DDR3_SB_DQS_DN3  @S9S_MB_2U_LIB.S9S_MB_2U(SCH_1):M_D_CPU0_SB_DQS_DN<3>
  AB24  M_D_CPU0_SB_DQS_DN<2>  DDR3_SB_DQS_DN2  @S9S_MB_2U_LIB.S9S_MB_2U(SCH_1):M_D_CPU0_SB_DQS_DN<2>
  AJ27  M_D_CPU0_SB_DQS_DN<1>  DDR3_SB_DQS_DN1  @S9S_MB_2U_LIB.S9S_MB_2U(SCH_1):M_D_CPU0_SB_DQS_DN<1>
  AJ33  M_D_CPU0_SB_DQS_DN<0>  DDR3_SB_DQS_DN0  @S9S_MB_2U_LIB.S9S_MB_2U(SCH_1):M_D_CPU0_SB_DQS_DN<0>
  AK28  M_D_CPU0_SB_DQ<9>  DDR3_SB_DQ9  @S9S_MB_2U_LIB.S9S_MB_2U(SCH_1):M_D_CPU0_SB_DQ<9>
  AL29  M_D_CPU0_SB_DQ<8>  DDR3_SB_DQ8  @S9S_MB_2U_LIB.S9S_MB_2U(SCH_1):M_D_CPU0_SB_DQ<8>
  AN31  M_D_CPU0_SB_DQ<7>  DDR3_SB_DQ7  @S9S_MB_2U_LIB.S9S_MB_2U(SCH_1):M_D_CPU0_SB_DQ<7>
  AP32  M_D_CPU0_SB_DQ<6>  DDR3_SB_DQ6  @S9S_MB_2U_LIB.S9S_MB_2U(SCH_1):M_D_CPU0_SB_DQ<6>
  AL31  M_D_CPU0_SB_DQ<5>  DDR3_SB_DQ5  @S9S_MB_2U_LIB.S9S_MB_2U(SCH_1):M_D_CPU0_SB_DQ<5>
  AK32  M_D_CPU0_SB_DQ<4>  DDR3_SB_DQ4  @S9S_MB_2U_LIB.S9S_MB_2U(SCH_1):M_D_CPU0_SB_DQ<4>
  AP34  M_D_CPU0_SB_DQ<3>  DDR3_SB_DQ3  @S9S_MB_2U_LIB.S9S_MB_2U(SCH_1):M_D_CPU0_SB_DQ<3>
  AN19  M_D_CPU0_SB_DQ<31>  DDR3_SB_DQ31  @S9S_MB_2U_LIB.S9S_MB_2U(SCH_1):M_D_CPU0_SB_DQ<31>
  AP20  M_D_CPU0_SB_DQ<30>  DDR3_SB_DQ30  @S9S_MB_2U_LIB.S9S_MB_2U(SCH_1):M_D_CPU0_SB_DQ<30>
  AN35  M_D_CPU0_SB_DQ<2>  DDR3_SB_DQ2  @S9S_MB_2U_LIB.S9S_MB_2U(SCH_1):M_D_CPU0_SB_DQ<2>
  AL19  M_D_CPU0_SB_DQ<29>  DDR3_SB_DQ29  @S9S_MB_2U_LIB.S9S_MB_2U(SCH_1):M_D_CPU0_SB_DQ<29>
  AK20  M_D_CPU0_SB_DQ<28>  DDR3_SB_DQ28  @S9S_MB_2U_LIB.S9S_MB_2U(SCH_1):M_D_CPU0_SB_DQ<28>
  AP22  M_D_CPU0_SB_DQ<27>  DDR3_SB_DQ27  @S9S_MB_2U_LIB.S9S_MB_2U(SCH_1):M_D_CPU0_SB_DQ<27>
  AN23  M_D_CPU0_SB_DQ<26>  DDR3_SB_DQ26  @S9S_MB_2U_LIB.S9S_MB_2U(SCH_1):M_D_CPU0_SB_DQ<26>
  AK22  M_D_CPU0_SB_DQ<25>  DDR3_SB_DQ25  @S9S_MB_2U_LIB.S9S_MB_2U(SCH_1):M_D_CPU0_SB_DQ<25>
  AL23  M_D_CPU0_SB_DQ<24>  DDR3_SB_DQ24  @S9S_MB_2U_LIB.S9S_MB_2U(SCH_1):M_D_CPU0_SB_DQ<24>
  AF22  M_D_CPU0_SB_DQ<23>  DDR3_SB_DQ23  @S9S_MB_2U_LIB.S9S_MB_2U(SCH_1):M_D_CPU0_SB_DQ<23>
  AG23  M_D_CPU0_SB_DQ<22>  DDR3_SB_DQ22  @S9S_MB_2U_LIB.S9S_MB_2U(SCH_1):M_D_CPU0_SB_DQ<22>
  AD22  M_D_CPU0_SB_DQ<21>  DDR3_SB_DQ21  @S9S_MB_2U_LIB.S9S_MB_2U(SCH_1):M_D_CPU0_SB_DQ<21>
  AC23  M_D_CPU0_SB_DQ<20>  DDR3_SB_DQ20  @S9S_MB_2U_LIB.S9S_MB_2U(SCH_1):M_D_CPU0_SB_DQ<20>
  AK34  M_D_CPU0_SB_DQ<1>  DDR3_SB_DQ1  @S9S_MB_2U_LIB.S9S_MB_2U(SCH_1):M_D_CPU0_SB_DQ<1>
  AG25  M_D_CPU0_SB_DQ<19>  DDR3_SB_DQ19  @S9S_MB_2U_LIB.S9S_MB_2U(SCH_1):M_D_CPU0_SB_DQ<19>
  AF26  M_D_CPU0_SB_DQ<18>  DDR3_SB_DQ18  @S9S_MB_2U_LIB.S9S_MB_2U(SCH_1):M_D_CPU0_SB_DQ<18>
  AC25  M_D_CPU0_SB_DQ<17>  DDR3_SB_DQ17  @S9S_MB_2U_LIB.S9S_MB_2U(SCH_1):M_D_CPU0_SB_DQ<17>
  AD26  M_D_CPU0_SB_DQ<16>  DDR3_SB_DQ16  @S9S_MB_2U_LIB.S9S_MB_2U(SCH_1):M_D_CPU0_SB_DQ<16>
  AN25  M_D_CPU0_SB_DQ<15>  DDR3_SB_DQ15  @S9S_MB_2U_LIB.S9S_MB_2U(SCH_1):M_D_CPU0_SB_DQ<15>
  AP26  M_D_CPU0_SB_DQ<14>  DDR3_SB_DQ14  @S9S_MB_2U_LIB.S9S_MB_2U(SCH_1):M_D_CPU0_SB_DQ<14>
  AL25  M_D_CPU0_SB_DQ<13>  DDR3_SB_DQ13  @S9S_MB_2U_LIB.S9S_MB_2U(SCH_1):M_D_CPU0_SB_DQ<13>
  AK26  M_D_CPU0_SB_DQ<12>  DDR3_SB_DQ12  @S9S_MB_2U_LIB.S9S_MB_2U(SCH_1):M_D_CPU0_SB_DQ<12>
  AP28  M_D_CPU0_SB_DQ<11>  DDR3_SB_DQ11  @S9S_MB_2U_LIB.S9S_MB_2U(SCH_1):M_D_CPU0_SB_DQ<11>
  AN29  M_D_CPU0_SB_DQ<10>  DDR3_SB_DQ10  @S9S_MB_2U_LIB.S9S_MB_2U(SCH_1):M_D_CPU0_SB_DQ<10>
  AL35  M_D_CPU0_SB_DQ<0>  DDR3_SB_DQ0  @S9S_MB_2U_LIB.S9S_MB_2U(SCH_1):M_D_CPU0_SB_DQ<0>
  AD40  M_D_CPU0_SB_CS_N<3>  DDR3_SB_CS3_N  @S9S_MB_2U_LIB.S9S_MB_2U(SCH_1):M_D_CPU0_SB_CS_N<3>
  AF40  M_D_CPU0_SB_CS_N<2>  DDR3_SB_CS2_N  @S9S_MB_2U_LIB.S9S_MB_2U(SCH_1):M_D_CPU0_SB_CS_N<2>
  AG41  M_D_CPU0_SB_CS_N<1>  DDR3_SB_CS1_N  @S9S_MB_2U_LIB.S9S_MB_2U(SCH_1):M_D_CPU0_SB_CS_N<1>
  AC41  M_D_CPU0_SB_CS_N<0>  DDR3_SB_CS0_N  @S9S_MB_2U_LIB.S9S_MB_2U(SCH_1):M_D_CPU0_SB_CS_N<0>
  AP40  M_D_CPU0_SB_CB<7>  DDR3_SB_ECC7  @S9S_MB_2U_LIB.S9S_MB_2U(SCH_1):M_D_CPU0_SB_CB<7>
  AN41  M_D_CPU0_SB_CB<6>  DDR3_SB_ECC6  @S9S_MB_2U_LIB.S9S_MB_2U(SCH_1):M_D_CPU0_SB_CB<6>
  AK40  M_D_CPU0_SB_CB<5>  DDR3_SB_ECC5  @S9S_MB_2U_LIB.S9S_MB_2U(SCH_1):M_D_CPU0_SB_CB<5>
  AL41  M_D_CPU0_SB_CB<4>  DDR3_SB_ECC4  @S9S_MB_2U_LIB.S9S_MB_2U(SCH_1):M_D_CPU0_SB_CB<4>
  AN37  M_D_CPU0_SB_CB<3>  DDR3_SB_ECC3  @S9S_MB_2U_LIB.S9S_MB_2U(SCH_1):M_D_CPU0_SB_CB<3>
  AP38  M_D_CPU0_SB_CB<2>  DDR3_SB_ECC2  @S9S_MB_2U_LIB.S9S_MB_2U(SCH_1):M_D_CPU0_SB_CB<2>
  AL37  M_D_CPU0_SB_CB<1>  DDR3_SB_ECC1  @S9S_MB_2U_LIB.S9S_MB_2U(SCH_1):M_D_CPU0_SB_CB<1>
  AK38  M_D_CPU0_SB_CB<0>  DDR3_SB_ECC0  @S9S_MB_2U_LIB.S9S_MB_2U(SCH_1):M_D_CPU0_SB_CB<0>
  AB42  M_D_CPU0_SB_CA<6>  DDR3_SB_CA6  @S9S_MB_2U_LIB.S9S_MB_2U(SCH_1):M_D_CPU0_SB_CA<6>
  AG43  M_D_CPU0_SB_CA<5>  DDR3_SB_CA5  @S9S_MB_2U_LIB.S9S_MB_2U(SCH_1):M_D_CPU0_SB_CA<5>
  AC43  M_D_CPU0_SB_CA<4>  DDR3_SB_CA4  @S9S_MB_2U_LIB.S9S_MB_2U(SCH_1):M_D_CPU0_SB_CA<4>
  AF44  M_D_CPU0_SB_CA<3>  DDR3_SB_CA3  @S9S_MB_2U_LIB.S9S_MB_2U(SCH_1):M_D_CPU0_SB_CA<3>
  AD44  M_D_CPU0_SB_CA<2>  DDR3_SB_CA2  @S9S_MB_2U_LIB.S9S_MB_2U(SCH_1):M_D_CPU0_SB_CA<2>
  AL43  M_D_CPU0_SB_CA<1>  DDR3_SB_CA1  @S9S_MB_2U_LIB.S9S_MB_2U(SCH_1):M_D_CPU0_SB_CA<1>
  AK44  M_D_CPU0_SB_CA<0>  DDR3_SB_CA0  @S9S_MB_2U_LIB.S9S_MB_2U(SCH_1):M_D_CPU0_SB_CA<0>
  AC50  M_D_CPU0_SA_RSP<1>  DDR3_A_RSP1  @S9S_MB_2U_LIB.S9S_MB_2U(SCH_1):M_D_CPU0_SA_RSP<1>
  AD51  M_D_CPU0_SA_RSP<0>  DDR3_A_RSP0  @S9S_MB_2U_LIB.S9S_MB_2U(SCH_1):M_D_CPU0_SA_RSP<0>
  AP44  M_D_CPU0_SA_PAR  DDR3_SA_PAR  @S9S_MB_2U_LIB.S9S_MB_2U(SCH_1):M_D_CPU0_SA_PAR
  AR58  M_D_CPU0_SA_DQS_DP<9>  DDR3_SA_DQS_DP9  @S9S_MB_2U_LIB.S9S_MB_2U(SCH_1):M_D_CPU0_SA_DQS_DP<9>
  AR64  M_D_CPU0_SA_DQS_DP<8>  DDR3_SA_DQS_DP8  @S9S_MB_2U_LIB.S9S_MB_2U(SCH_1):M_D_CPU0_SA_DQS_DP<8>
  AR70  M_D_CPU0_SA_DQS_DP<7>  DDR3_SA_DQS_DP7  @S9S_MB_2U_LIB.S9S_MB_2U(SCH_1):M_D_CPU0_SA_DQS_DP<7>
  AR76  M_D_CPU0_SA_DQS_DP<6>  DDR3_SA_DQS_DP6  @S9S_MB_2U_LIB.S9S_MB_2U(SCH_1):M_D_CPU0_SA_DQS_DP<6>
  AF73  M_D_CPU0_SA_DQS_DP<5>  DDR3_SA_DQS_DP5  @S9S_MB_2U_LIB.S9S_MB_2U(SCH_1):M_D_CPU0_SA_DQS_DP<5>
  AL58  M_D_CPU0_SA_DQS_DP<4>  DDR3_SA_DQS_DP4  @S9S_MB_2U_LIB.S9S_MB_2U(SCH_1):M_D_CPU0_SA_DQS_DP<4>
  AL64  M_D_CPU0_SA_DQS_DP<3>  DDR3_SA_DQS_DP3  @S9S_MB_2U_LIB.S9S_MB_2U(SCH_1):M_D_CPU0_SA_DQS_DP<3>
  AL70  M_D_CPU0_SA_DQS_DP<2>  DDR3_SA_DQS_DP2  @S9S_MB_2U_LIB.S9S_MB_2U(SCH_1):M_D_CPU0_SA_DQS_DP<2>
  AL76  M_D_CPU0_SA_DQS_DP<1>  DDR3_SA_DQS_DP1  @S9S_MB_2U_LIB.S9S_MB_2U(SCH_1):M_D_CPU0_SA_DQS_DP<1>
  AD73  M_D_CPU0_SA_DQS_DP<0>  DDR3_SA_DQS_DP0  @S9S_MB_2U_LIB.S9S_MB_2U(SCH_1):M_D_CPU0_SA_DQS_DP<0>
  AN58  M_D_CPU0_SA_DQS_DN<9>  DDR3_SA_DQS_DN9  @S9S_MB_2U_LIB.S9S_MB_2U(SCH_1):M_D_CPU0_SA_DQS_DN<9>
  AN64  M_D_CPU0_SA_DQS_DN<8>  DDR3_SA_DQS_DN8  @S9S_MB_2U_LIB.S9S_MB_2U(SCH_1):M_D_CPU0_SA_DQS_DN<8>
  AN70  M_D_CPU0_SA_DQS_DN<7>  DDR3_SA_DQS_DN7  @S9S_MB_2U_LIB.S9S_MB_2U(SCH_1):M_D_CPU0_SA_DQS_DN<7>
  AN76  M_D_CPU0_SA_DQS_DN<6>  DDR3_SA_DQS_DN6  @S9S_MB_2U_LIB.S9S_MB_2U(SCH_1):M_D_CPU0_SA_DQS_DN<6>
  AH73  M_D_CPU0_SA_DQS_DN<5>  DDR3_SA_DQS_DN5  @S9S_MB_2U_LIB.S9S_MB_2U(SCH_1):M_D_CPU0_SA_DQS_DN<5>
  AJ58  M_D_CPU0_SA_DQS_DN<4>  DDR3_SA_DQS_DN4  @S9S_MB_2U_LIB.S9S_MB_2U(SCH_1):M_D_CPU0_SA_DQS_DN<4>
  AJ64  M_D_CPU0_SA_DQS_DN<3>  DDR3_SA_DQS_DN3  @S9S_MB_2U_LIB.S9S_MB_2U(SCH_1):M_D_CPU0_SA_DQS_DN<3>
  AJ70  M_D_CPU0_SA_DQS_DN<2>  DDR3_SA_DQS_DN2  @S9S_MB_2U_LIB.S9S_MB_2U(SCH_1):M_D_CPU0_SA_DQS_DN<2>
  AJ76  M_D_CPU0_SA_DQS_DN<1>  DDR3_SA_DQS_DN1  @S9S_MB_2U_LIB.S9S_MB_2U(SCH_1):M_D_CPU0_SA_DQS_DN<1>
  AB73  M_D_CPU0_SA_DQS_DN<0>  DDR3_SA_DQS_DN0  @S9S_MB_2U_LIB.S9S_MB_2U(SCH_1):M_D_CPU0_SA_DQS_DN<0>
  AK77  M_D_CPU0_SA_DQ<9>  DDR3_SA_DQ9  @S9S_MB_2U_LIB.S9S_MB_2U(SCH_1):M_D_CPU0_SA_DQ<9>
  AL78  M_D_CPU0_SA_DQ<8>  DDR3_SA_DQ8  @S9S_MB_2U_LIB.S9S_MB_2U(SCH_1):M_D_CPU0_SA_DQ<8>
  AF71  M_D_CPU0_SA_DQ<7>  DDR3_SA_DQ7  @S9S_MB_2U_LIB.S9S_MB_2U(SCH_1):M_D_CPU0_SA_DQ<7>
  AG72  M_D_CPU0_SA_DQ<6>  DDR3_SA_DQ6  @S9S_MB_2U_LIB.S9S_MB_2U(SCH_1):M_D_CPU0_SA_DQ<6>
  AD71  M_D_CPU0_SA_DQ<5>  DDR3_SA_DQ5  @S9S_MB_2U_LIB.S9S_MB_2U(SCH_1):M_D_CPU0_SA_DQ<5>
  AC72  M_D_CPU0_SA_DQ<4>  DDR3_SA_DQ4  @S9S_MB_2U_LIB.S9S_MB_2U(SCH_1):M_D_CPU0_SA_DQ<4>
  AG74  M_D_CPU0_SA_DQ<3>  DDR3_SA_DQ3  @S9S_MB_2U_LIB.S9S_MB_2U(SCH_1):M_D_CPU0_SA_DQ<3>
  AN62  M_D_CPU0_SA_DQ<31>  DDR3_SA_DQ31  @S9S_MB_2U_LIB.S9S_MB_2U(SCH_1):M_D_CPU0_SA_DQ<31>
  AP63  M_D_CPU0_SA_DQ<30>  DDR3_SA_DQ30  @S9S_MB_2U_LIB.S9S_MB_2U(SCH_1):M_D_CPU0_SA_DQ<30>
  AF75  M_D_CPU0_SA_DQ<2>  DDR3_SA_DQ2  @S9S_MB_2U_LIB.S9S_MB_2U(SCH_1):M_D_CPU0_SA_DQ<2>
  AL62  M_D_CPU0_SA_DQ<29>  DDR3_SA_DQ29  @S9S_MB_2U_LIB.S9S_MB_2U(SCH_1):M_D_CPU0_SA_DQ<29>
  AK63  M_D_CPU0_SA_DQ<28>  DDR3_SA_DQ28  @S9S_MB_2U_LIB.S9S_MB_2U(SCH_1):M_D_CPU0_SA_DQ<28>
  AP65  M_D_CPU0_SA_DQ<27>  DDR3_SA_DQ27  @S9S_MB_2U_LIB.S9S_MB_2U(SCH_1):M_D_CPU0_SA_DQ<27>
  AN66  M_D_CPU0_SA_DQ<26>  DDR3_SA_DQ26  @S9S_MB_2U_LIB.S9S_MB_2U(SCH_1):M_D_CPU0_SA_DQ<26>
  AK65  M_D_CPU0_SA_DQ<25>  DDR3_SA_DQ25  @S9S_MB_2U_LIB.S9S_MB_2U(SCH_1):M_D_CPU0_SA_DQ<25>
  AL66  M_D_CPU0_SA_DQ<24>  DDR3_SA_DQ24  @S9S_MB_2U_LIB.S9S_MB_2U(SCH_1):M_D_CPU0_SA_DQ<24>
  AN68  M_D_CPU0_SA_DQ<23>  DDR3_SA_DQ23  @S9S_MB_2U_LIB.S9S_MB_2U(SCH_1):M_D_CPU0_SA_DQ<23>
  AP69  M_D_CPU0_SA_DQ<22>  DDR3_SA_DQ22  @S9S_MB_2U_LIB.S9S_MB_2U(SCH_1):M_D_CPU0_SA_DQ<22>
  AL68  M_D_CPU0_SA_DQ<21>  DDR3_SA_DQ21  @S9S_MB_2U_LIB.S9S_MB_2U(SCH_1):M_D_CPU0_SA_DQ<21>
  AK69  M_D_CPU0_SA_DQ<20>  DDR3_SA_DQ20  @S9S_MB_2U_LIB.S9S_MB_2U(SCH_1):M_D_CPU0_SA_DQ<20>
  AC74  M_D_CPU0_SA_DQ<1>  DDR3_SA_DQ1  @S9S_MB_2U_LIB.S9S_MB_2U(SCH_1):M_D_CPU0_SA_DQ<1>
  AP71  M_D_CPU0_SA_DQ<19>  DDR3_SA_DQ19  @S9S_MB_2U_LIB.S9S_MB_2U(SCH_1):M_D_CPU0_SA_DQ<19>
  AN72  M_D_CPU0_SA_DQ<18>  DDR3_SA_DQ18  @S9S_MB_2U_LIB.S9S_MB_2U(SCH_1):M_D_CPU0_SA_DQ<18>
  AK71  M_D_CPU0_SA_DQ<17>  DDR3_SA_DQ17  @S9S_MB_2U_LIB.S9S_MB_2U(SCH_1):M_D_CPU0_SA_DQ<17>
  AL72  M_D_CPU0_SA_DQ<16>  DDR3_SA_DQ16  @S9S_MB_2U_LIB.S9S_MB_2U(SCH_1):M_D_CPU0_SA_DQ<16>
  AN74  M_D_CPU0_SA_DQ<15>  DDR3_SA_DQ15  @S9S_MB_2U_LIB.S9S_MB_2U(SCH_1):M_D_CPU0_SA_DQ<15>
  AP75  M_D_CPU0_SA_DQ<14>  DDR3_SA_DQ14  @S9S_MB_2U_LIB.S9S_MB_2U(SCH_1):M_D_CPU0_SA_DQ<14>
  AL74  M_D_CPU0_SA_DQ<13>  DDR3_SA_DQ13  @S9S_MB_2U_LIB.S9S_MB_2U(SCH_1):M_D_CPU0_SA_DQ<13>
  AK75  M_D_CPU0_SA_DQ<12>  DDR3_SA_DQ12  @S9S_MB_2U_LIB.S9S_MB_2U(SCH_1):M_D_CPU0_SA_DQ<12>
  AP77  M_D_CPU0_SA_DQ<11>  DDR3_SA_DQ11  @S9S_MB_2U_LIB.S9S_MB_2U(SCH_1):M_D_CPU0_SA_DQ<11>
  AN78  M_D_CPU0_SA_DQ<10>  DDR3_SA_DQ10  @S9S_MB_2U_LIB.S9S_MB_2U(SCH_1):M_D_CPU0_SA_DQ<10>
  AD75  M_D_CPU0_SA_DQ<0>  DDR3_SA_DQ0  @S9S_MB_2U_LIB.S9S_MB_2U(SCH_1):M_D_CPU0_SA_DQ<0>
  AP53  M_D_CPU0_SA_CS_N<3>  DDR3_SA_CS3_N  @S9S_MB_2U_LIB.S9S_MB_2U(SCH_1):M_D_CPU0_SA_CS_N<3>
  AN54  M_D_CPU0_SA_CS_N<2>  DDR3_SA_CS2_N  @S9S_MB_2U_LIB.S9S_MB_2U(SCH_1):M_D_CPU0_SA_CS_N<2>
  AK53  M_D_CPU0_SA_CS_N<1>  DDR3_SA_CS1_N  @S9S_MB_2U_LIB.S9S_MB_2U(SCH_1):M_D_CPU0_SA_CS_N<1>
  AL54  M_D_CPU0_SA_CS_N<0>  DDR3_SA_CS0_N  @S9S_MB_2U_LIB.S9S_MB_2U(SCH_1):M_D_CPU0_SA_CS_N<0>
  AN56  M_D_CPU0_SA_CB<7>  DDR3_SA_ECC7  @S9S_MB_2U_LIB.S9S_MB_2U(SCH_1):M_D_CPU0_SA_CB<7>
  AP57  M_D_CPU0_SA_CB<6>  DDR3_SA_ECC6  @S9S_MB_2U_LIB.S9S_MB_2U(SCH_1):M_D_CPU0_SA_CB<6>
  AL56  M_D_CPU0_SA_CB<5>  DDR3_SA_ECC5  @S9S_MB_2U_LIB.S9S_MB_2U(SCH_1):M_D_CPU0_SA_CB<5>
  AK57  M_D_CPU0_SA_CB<4>  DDR3_SA_ECC4  @S9S_MB_2U_LIB.S9S_MB_2U(SCH_1):M_D_CPU0_SA_CB<4>
  AP59  M_D_CPU0_SA_CB<3>  DDR3_SA_ECC3  @S9S_MB_2U_LIB.S9S_MB_2U(SCH_1):M_D_CPU0_SA_CB<3>
  AN60  M_D_CPU0_SA_CB<2>  DDR3_SA_ECC2  @S9S_MB_2U_LIB.S9S_MB_2U(SCH_1):M_D_CPU0_SA_CB<2>
  AK59  M_D_CPU0_SA_CB<1>  DDR3_SA_ECC1  @S9S_MB_2U_LIB.S9S_MB_2U(SCH_1):M_D_CPU0_SA_CB<1>
  AL60  M_D_CPU0_SA_CB<0>  DDR3_SA_ECC0  @S9S_MB_2U_LIB.S9S_MB_2U(SCH_1):M_D_CPU0_SA_CB<0>
  AN43  M_D_CPU0_SA_CA<6>  DDR3_SA_CA6  @S9S_MB_2U_LIB.S9S_MB_2U(SCH_1):M_D_CPU0_SA_CA<6>
  AN50  M_D_CPU0_SA_CA<5>  DDR3_SA_CA5  @S9S_MB_2U_LIB.S9S_MB_2U(SCH_1):M_D_CPU0_SA_CA<5>
  AL50  M_D_CPU0_SA_CA<4>  DDR3_SA_CA4  @S9S_MB_2U_LIB.S9S_MB_2U(SCH_1):M_D_CPU0_SA_CA<4>
  AP51  M_D_CPU0_SA_CA<3>  DDR3_SA_CA3  @S9S_MB_2U_LIB.S9S_MB_2U(SCH_1):M_D_CPU0_SA_CA<3>
  AK51  M_D_CPU0_SA_CA<2>  DDR3_SA_CA2  @S9S_MB_2U_LIB.S9S_MB_2U(SCH_1):M_D_CPU0_SA_CA<2>
  AR52  M_D_CPU0_SA_CA<1>  DDR3_SA_CA1  @S9S_MB_2U_LIB.S9S_MB_2U(SCH_1):M_D_CPU0_SA_CA<1>
  AJ52  M_D_CPU0_SA_CA<0>  DDR3_SA_CA0  @S9S_MB_2U_LIB.S9S_MB_2U(SCH_1):M_D_CPU0_SA_CA<0>
  AR45  M_D_CPU0_CLK_DP<1>  DDR3_CLK_DP1  @S9S_MB_2U_LIB.S9S_MB_2U(SCH_1):M_D_CPU0_CLK_DP<1>
  AL45  M_D_CPU0_CLK_DP<0>  DDR3_CLK_DP0  @S9S_MB_2U_LIB.S9S_MB_2U(SCH_1):M_D_CPU0_CLK_DP<0>
  AN45  M_D_CPU0_CLK_DN<1>  DDR3_CLK_DN1  @S9S_MB_2U_LIB.S9S_MB_2U(SCH_1):M_D_CPU0_CLK_DN<1>
  AJ45  M_D_CPU0_CLK_DN<0>  DDR3_CLK_DN0  @S9S_MB_2U_LIB.S9S_MB_2U(SCH_1):M_D_CPU0_CLK_DN<0>
  AV47  M_D_CPU0_ALERT_N  DDR3_ALERT_N  @S9S_MB_2U_LIB.S9S_MB_2U(SCH_1):M_D_CPU0_ALERT_N

SOCKET4677_AZIFS054P001C01  I169  U2     [SOCKET4677_AZIFS054P001C01-SOCA]
  AF47  M_C_CPU0_SB_RSP<1>  DDR2_B_RSP1  @S9S_MB_2U_LIB.S9S_MB_2U(SCH_1):M_C_CPU0_SB_RSP<1>
  AG48  M_C_CPU0_SB_RSP<0>  DDR2_B_RSP0  @S9S_MB_2U_LIB.S9S_MB_2U(SCH_1):M_C_CPU0_SB_RSP<0>
  AA39  M_C_CPU0_SB_PAR  DDR2_SB_PAR  @S9S_MB_2U_LIB.S9S_MB_2U(SCH_1):M_C_CPU0_SB_PAR
  U33  M_C_CPU0_SB_DQS_DP<9>  DDR2_SB_DQS_DP9  @S9S_MB_2U_LIB.S9S_MB_2U(SCH_1):M_C_CPU0_SB_DQS_DP<9>
  AH18  M_C_CPU0_SB_DQS_DP<8>  DDR2_SB_DQS_DP8  @S9S_MB_2U_LIB.S9S_MB_2U(SCH_1):M_C_CPU0_SB_DQS_DP<8>
  AA21  M_C_CPU0_SB_DQS_DP<7>  DDR2_SB_DQS_DP7  @S9S_MB_2U_LIB.S9S_MB_2U(SCH_1):M_C_CPU0_SB_DQS_DP<7>
  AH30  M_C_CPU0_SB_DQS_DP<6>  DDR2_SB_DQS_DP6  @S9S_MB_2U_LIB.S9S_MB_2U(SCH_1):M_C_CPU0_SB_DQS_DP<6>
  AH36  M_C_CPU0_SB_DQS_DP<5>  DDR2_SB_DQS_DP5  @S9S_MB_2U_LIB.S9S_MB_2U(SCH_1):M_C_CPU0_SB_DQS_DP<5>
  AA33  M_C_CPU0_SB_DQS_DP<4>  DDR2_SB_DQS_DP4  @S9S_MB_2U_LIB.S9S_MB_2U(SCH_1):M_C_CPU0_SB_DQS_DP<4>
  AD18  M_C_CPU0_SB_DQS_DP<3>  DDR2_SB_DQS_DP3  @S9S_MB_2U_LIB.S9S_MB_2U(SCH_1):M_C_CPU0_SB_DQS_DP<3>
  U21  M_C_CPU0_SB_DQS_DP<2>  DDR2_SB_DQS_DP2  @S9S_MB_2U_LIB.S9S_MB_2U(SCH_1):M_C_CPU0_SB_DQS_DP<2>
  AD30  M_C_CPU0_SB_DQS_DP<1>  DDR2_SB_DQS_DP1  @S9S_MB_2U_LIB.S9S_MB_2U(SCH_1):M_C_CPU0_SB_DQS_DP<1>
  AD36  M_C_CPU0_SB_DQS_DP<0>  DDR2_SB_DQS_DP0  @S9S_MB_2U_LIB.S9S_MB_2U(SCH_1):M_C_CPU0_SB_DQS_DP<0>
  R33  M_C_CPU0_SB_DQS_DN<9>  DDR2_SB_DQS_DN9  @S9S_MB_2U_LIB.S9S_MB_2U(SCH_1):M_C_CPU0_SB_DQS_DN<9>
  AF18  M_C_CPU0_SB_DQS_DN<8>  DDR2_SB_DQS_DN8  @S9S_MB_2U_LIB.S9S_MB_2U(SCH_1):M_C_CPU0_SB_DQS_DN<8>
  W21  M_C_CPU0_SB_DQS_DN<7>  DDR2_SB_DQS_DN7  @S9S_MB_2U_LIB.S9S_MB_2U(SCH_1):M_C_CPU0_SB_DQS_DN<7>
  AF30  M_C_CPU0_SB_DQS_DN<6>  DDR2_SB_DQS_DN6  @S9S_MB_2U_LIB.S9S_MB_2U(SCH_1):M_C_CPU0_SB_DQS_DN<6>
  AF36  M_C_CPU0_SB_DQS_DN<5>  DDR2_SB_DQS_DN5  @S9S_MB_2U_LIB.S9S_MB_2U(SCH_1):M_C_CPU0_SB_DQS_DN<5>
  W33  M_C_CPU0_SB_DQS_DN<4>  DDR2_SB_DQS_DN4  @S9S_MB_2U_LIB.S9S_MB_2U(SCH_1):M_C_CPU0_SB_DQS_DN<4>
  AB18  M_C_CPU0_SB_DQS_DN<3>  DDR2_SB_DQS_DN3  @S9S_MB_2U_LIB.S9S_MB_2U(SCH_1):M_C_CPU0_SB_DQS_DN<3>
  R21  M_C_CPU0_SB_DQS_DN<2>  DDR2_SB_DQS_DN2  @S9S_MB_2U_LIB.S9S_MB_2U(SCH_1):M_C_CPU0_SB_DQS_DN<2>
  AB30  M_C_CPU0_SB_DQS_DN<1>  DDR2_SB_DQS_DN1  @S9S_MB_2U_LIB.S9S_MB_2U(SCH_1):M_C_CPU0_SB_DQS_DN<1>
  AB36  M_C_CPU0_SB_DQS_DN<0>  DDR2_SB_DQS_DN0  @S9S_MB_2U_LIB.S9S_MB_2U(SCH_1):M_C_CPU0_SB_DQS_DN<0>
  AC31  M_C_CPU0_SB_DQ<9>  DDR2_SB_DQ9  @S9S_MB_2U_LIB.S9S_MB_2U(SCH_1):M_C_CPU0_SB_DQ<9>
  AD32  M_C_CPU0_SB_DQ<8>  DDR2_SB_DQ8  @S9S_MB_2U_LIB.S9S_MB_2U(SCH_1):M_C_CPU0_SB_DQ<8>
  AF34  M_C_CPU0_SB_DQ<7>  DDR2_SB_DQ7  @S9S_MB_2U_LIB.S9S_MB_2U(SCH_1):M_C_CPU0_SB_DQ<7>
  AG35  M_C_CPU0_SB_DQ<6>  DDR2_SB_DQ6  @S9S_MB_2U_LIB.S9S_MB_2U(SCH_1):M_C_CPU0_SB_DQ<6>
  AD34  M_C_CPU0_SB_DQ<5>  DDR2_SB_DQ5  @S9S_MB_2U_LIB.S9S_MB_2U(SCH_1):M_C_CPU0_SB_DQ<5>
  AC35  M_C_CPU0_SB_DQ<4>  DDR2_SB_DQ4  @S9S_MB_2U_LIB.S9S_MB_2U(SCH_1):M_C_CPU0_SB_DQ<4>
  AG37  M_C_CPU0_SB_DQ<3>  DDR2_SB_DQ3  @S9S_MB_2U_LIB.S9S_MB_2U(SCH_1):M_C_CPU0_SB_DQ<3>
  AJ17  M_C_CPU0_SB_DQ<31>  DDR2_SB_DQ31  @S9S_MB_2U_LIB.S9S_MB_2U(SCH_1):M_C_CPU0_SB_DQ<31>
  AC17  M_C_CPU0_SB_DQ<30>  DDR2_SB_DQ30  @S9S_MB_2U_LIB.S9S_MB_2U(SCH_1):M_C_CPU0_SB_DQ<30>
  AF38  M_C_CPU0_SB_DQ<2>  DDR2_SB_DQ2  @S9S_MB_2U_LIB.S9S_MB_2U(SCH_1):M_C_CPU0_SB_DQ<2>
  AG17  M_C_CPU0_SB_DQ<29>  DDR2_SB_DQ29  @S9S_MB_2U_LIB.S9S_MB_2U(SCH_1):M_C_CPU0_SB_DQ<29>
  AA17  M_C_CPU0_SB_DQ<28>  DDR2_SB_DQ28  @S9S_MB_2U_LIB.S9S_MB_2U(SCH_1):M_C_CPU0_SB_DQ<28>
  AG19  M_C_CPU0_SB_DQ<27>  DDR2_SB_DQ27  @S9S_MB_2U_LIB.S9S_MB_2U(SCH_1):M_C_CPU0_SB_DQ<27>
  AF20  M_C_CPU0_SB_DQ<26>  DDR2_SB_DQ26  @S9S_MB_2U_LIB.S9S_MB_2U(SCH_1):M_C_CPU0_SB_DQ<26>
  AC19  M_C_CPU0_SB_DQ<25>  DDR2_SB_DQ25  @S9S_MB_2U_LIB.S9S_MB_2U(SCH_1):M_C_CPU0_SB_DQ<25>
  AD20  M_C_CPU0_SB_DQ<24>  DDR2_SB_DQ24  @S9S_MB_2U_LIB.S9S_MB_2U(SCH_1):M_C_CPU0_SB_DQ<24>
  W19  M_C_CPU0_SB_DQ<23>  DDR2_SB_DQ23  @S9S_MB_2U_LIB.S9S_MB_2U(SCH_1):M_C_CPU0_SB_DQ<23>
  Y20  M_C_CPU0_SB_DQ<22>  DDR2_SB_DQ22  @S9S_MB_2U_LIB.S9S_MB_2U(SCH_1):M_C_CPU0_SB_DQ<22>
  U19  M_C_CPU0_SB_DQ<21>  DDR2_SB_DQ21  @S9S_MB_2U_LIB.S9S_MB_2U(SCH_1):M_C_CPU0_SB_DQ<21>
  T20  M_C_CPU0_SB_DQ<20>  DDR2_SB_DQ20  @S9S_MB_2U_LIB.S9S_MB_2U(SCH_1):M_C_CPU0_SB_DQ<20>
  AC37  M_C_CPU0_SB_DQ<1>  DDR2_SB_DQ1  @S9S_MB_2U_LIB.S9S_MB_2U(SCH_1):M_C_CPU0_SB_DQ<1>
  Y22  M_C_CPU0_SB_DQ<19>  DDR2_SB_DQ19  @S9S_MB_2U_LIB.S9S_MB_2U(SCH_1):M_C_CPU0_SB_DQ<19>
  W23  M_C_CPU0_SB_DQ<18>  DDR2_SB_DQ18  @S9S_MB_2U_LIB.S9S_MB_2U(SCH_1):M_C_CPU0_SB_DQ<18>
  T22  M_C_CPU0_SB_DQ<17>  DDR2_SB_DQ17  @S9S_MB_2U_LIB.S9S_MB_2U(SCH_1):M_C_CPU0_SB_DQ<17>
  U23  M_C_CPU0_SB_DQ<16>  DDR2_SB_DQ16  @S9S_MB_2U_LIB.S9S_MB_2U(SCH_1):M_C_CPU0_SB_DQ<16>
  AF28  M_C_CPU0_SB_DQ<15>  DDR2_SB_DQ15  @S9S_MB_2U_LIB.S9S_MB_2U(SCH_1):M_C_CPU0_SB_DQ<15>
  AG29  M_C_CPU0_SB_DQ<14>  DDR2_SB_DQ14  @S9S_MB_2U_LIB.S9S_MB_2U(SCH_1):M_C_CPU0_SB_DQ<14>
  AD28  M_C_CPU0_SB_DQ<13>  DDR2_SB_DQ13  @S9S_MB_2U_LIB.S9S_MB_2U(SCH_1):M_C_CPU0_SB_DQ<13>
  AC29  M_C_CPU0_SB_DQ<12>  DDR2_SB_DQ12  @S9S_MB_2U_LIB.S9S_MB_2U(SCH_1):M_C_CPU0_SB_DQ<12>
  AG31  M_C_CPU0_SB_DQ<11>  DDR2_SB_DQ11  @S9S_MB_2U_LIB.S9S_MB_2U(SCH_1):M_C_CPU0_SB_DQ<11>
  AF32  M_C_CPU0_SB_DQ<10>  DDR2_SB_DQ10  @S9S_MB_2U_LIB.S9S_MB_2U(SCH_1):M_C_CPU0_SB_DQ<10>
  AD38  M_C_CPU0_SB_DQ<0>  DDR2_SB_DQ0  @S9S_MB_2U_LIB.S9S_MB_2U(SCH_1):M_C_CPU0_SB_DQ<0>
  W37  M_C_CPU0_SB_CS_N<3>  DDR2_SB_CS3_N  @S9S_MB_2U_LIB.S9S_MB_2U(SCH_1):M_C_CPU0_SB_CS_N<3>
  Y38  M_C_CPU0_SB_CS_N<2>  DDR2_SB_CS2_N  @S9S_MB_2U_LIB.S9S_MB_2U(SCH_1):M_C_CPU0_SB_CS_N<2>
  U37  M_C_CPU0_SB_CS_N<1>  DDR2_SB_CS1_N  @S9S_MB_2U_LIB.S9S_MB_2U(SCH_1):M_C_CPU0_SB_CS_N<1>
  T38  M_C_CPU0_SB_CS_N<0>  DDR2_SB_CS0_N  @S9S_MB_2U_LIB.S9S_MB_2U(SCH_1):M_C_CPU0_SB_CS_N<0>
  Y34  M_C_CPU0_SB_CB<7>  DDR2_SB_ECC7  @S9S_MB_2U_LIB.S9S_MB_2U(SCH_1):M_C_CPU0_SB_CB<7>
  W35  M_C_CPU0_SB_CB<6>  DDR2_SB_ECC6  @S9S_MB_2U_LIB.S9S_MB_2U(SCH_1):M_C_CPU0_SB_CB<6>
  T34  M_C_CPU0_SB_CB<5>  DDR2_SB_ECC5  @S9S_MB_2U_LIB.S9S_MB_2U(SCH_1):M_C_CPU0_SB_CB<5>
  U35  M_C_CPU0_SB_CB<4>  DDR2_SB_ECC4  @S9S_MB_2U_LIB.S9S_MB_2U(SCH_1):M_C_CPU0_SB_CB<4>
  W31  M_C_CPU0_SB_CB<3>  DDR2_SB_ECC3  @S9S_MB_2U_LIB.S9S_MB_2U(SCH_1):M_C_CPU0_SB_CB<3>
  Y32  M_C_CPU0_SB_CB<2>  DDR2_SB_ECC2  @S9S_MB_2U_LIB.S9S_MB_2U(SCH_1):M_C_CPU0_SB_CB<2>
  U31  M_C_CPU0_SB_CB<1>  DDR2_SB_ECC1  @S9S_MB_2U_LIB.S9S_MB_2U(SCH_1):M_C_CPU0_SB_CB<1>
  T32  M_C_CPU0_SB_CB<0>  DDR2_SB_ECC0  @S9S_MB_2U_LIB.S9S_MB_2U(SCH_1):M_C_CPU0_SB_CB<0>
  R39  M_C_CPU0_SB_CA<6>  DDR2_SB_CA6  @S9S_MB_2U_LIB.S9S_MB_2U(SCH_1):M_C_CPU0_SB_CA<6>
  Y40  M_C_CPU0_SB_CA<5>  DDR2_SB_CA5  @S9S_MB_2U_LIB.S9S_MB_2U(SCH_1):M_C_CPU0_SB_CA<5>
  T40  M_C_CPU0_SB_CA<4>  DDR2_SB_CA4  @S9S_MB_2U_LIB.S9S_MB_2U(SCH_1):M_C_CPU0_SB_CA<4>
  W41  M_C_CPU0_SB_CA<3>  DDR2_SB_CA3  @S9S_MB_2U_LIB.S9S_MB_2U(SCH_1):M_C_CPU0_SB_CA<3>
  U41  M_C_CPU0_SB_CA<2>  DDR2_SB_CA2  @S9S_MB_2U_LIB.S9S_MB_2U(SCH_1):M_C_CPU0_SB_CA<2>
  Y47  M_C_CPU0_SB_CA<1>  DDR2_SB_CA1  @S9S_MB_2U_LIB.S9S_MB_2U(SCH_1):M_C_CPU0_SB_CA<1>
  W48  M_C_CPU0_SB_CA<0>  DDR2_SB_CA0  @S9S_MB_2U_LIB.S9S_MB_2U(SCH_1):M_C_CPU0_SB_CA<0>
  AD47  M_C_CPU0_SA_RSP<1>  DDR2_A_RSP1  @S9S_MB_2U_LIB.S9S_MB_2U(SCH_1):M_C_CPU0_SA_RSP<1>
  AC48  M_C_CPU0_SA_RSP<0>  DDR2_A_RSP0  @S9S_MB_2U_LIB.S9S_MB_2U(SCH_1):M_C_CPU0_SA_RSP<0>
  T47  M_C_CPU0_SA_PAR  DDR2_SA_PAR  @S9S_MB_2U_LIB.S9S_MB_2U(SCH_1):M_C_CPU0_SA_PAR
  AF55  M_C_CPU0_SA_DQS_DP<9>  DDR2_SA_DQS_DP9  @S9S_MB_2U_LIB.S9S_MB_2U(SCH_1):M_C_CPU0_SA_DQS_DP<9>
  AH61  M_C_CPU0_SA_DQS_DP<8>  DDR2_SA_DQS_DP8  @S9S_MB_2U_LIB.S9S_MB_2U(SCH_1):M_C_CPU0_SA_DQS_DP<8>
  W64  M_C_CPU0_SA_DQS_DP<7>  DDR2_SA_DQS_DP7  @S9S_MB_2U_LIB.S9S_MB_2U(SCH_1):M_C_CPU0_SA_DQS_DP<7>
  AF67  M_C_CPU0_SA_DQS_DP<6>  DDR2_SA_DQS_DP6  @S9S_MB_2U_LIB.S9S_MB_2U(SCH_1):M_C_CPU0_SA_DQS_DP<6>
  AA76  M_C_CPU0_SA_DQS_DP<5>  DDR2_SA_DQS_DP5  @S9S_MB_2U_LIB.S9S_MB_2U(SCH_1):M_C_CPU0_SA_DQS_DP<5>
  AB55  M_C_CPU0_SA_DQS_DP<4>  DDR2_SA_DQS_DP4  @S9S_MB_2U_LIB.S9S_MB_2U(SCH_1):M_C_CPU0_SA_DQS_DP<4>
  AD61  M_C_CPU0_SA_DQS_DP<3>  DDR2_SA_DQS_DP3  @S9S_MB_2U_LIB.S9S_MB_2U(SCH_1):M_C_CPU0_SA_DQS_DP<3>
  U64  M_C_CPU0_SA_DQS_DP<2>  DDR2_SA_DQS_DP2  @S9S_MB_2U_LIB.S9S_MB_2U(SCH_1):M_C_CPU0_SA_DQS_DP<2>
  AD67  M_C_CPU0_SA_DQS_DP<1>  DDR2_SA_DQS_DP1  @S9S_MB_2U_LIB.S9S_MB_2U(SCH_1):M_C_CPU0_SA_DQS_DP<1>
  U76  M_C_CPU0_SA_DQS_DP<0>  DDR2_SA_DQS_DP0  @S9S_MB_2U_LIB.S9S_MB_2U(SCH_1):M_C_CPU0_SA_DQS_DP<0>
  AH55  M_C_CPU0_SA_DQS_DN<9>  DDR2_SA_DQS_DN9  @S9S_MB_2U_LIB.S9S_MB_2U(SCH_1):M_C_CPU0_SA_DQS_DN<9>
  AF61  M_C_CPU0_SA_DQS_DN<8>  DDR2_SA_DQS_DN8  @S9S_MB_2U_LIB.S9S_MB_2U(SCH_1):M_C_CPU0_SA_DQS_DN<8>
  AA64  M_C_CPU0_SA_DQS_DN<7>  DDR2_SA_DQS_DN7  @S9S_MB_2U_LIB.S9S_MB_2U(SCH_1):M_C_CPU0_SA_DQS_DN<7>
  AH67  M_C_CPU0_SA_DQS_DN<6>  DDR2_SA_DQS_DN6  @S9S_MB_2U_LIB.S9S_MB_2U(SCH_1):M_C_CPU0_SA_DQS_DN<6>
  W76  M_C_CPU0_SA_DQS_DN<5>  DDR2_SA_DQS_DN5  @S9S_MB_2U_LIB.S9S_MB_2U(SCH_1):M_C_CPU0_SA_DQS_DN<5>
  AD55  M_C_CPU0_SA_DQS_DN<4>  DDR2_SA_DQS_DN4  @S9S_MB_2U_LIB.S9S_MB_2U(SCH_1):M_C_CPU0_SA_DQS_DN<4>
  AB61  M_C_CPU0_SA_DQS_DN<3>  DDR2_SA_DQS_DN3  @S9S_MB_2U_LIB.S9S_MB_2U(SCH_1):M_C_CPU0_SA_DQS_DN<3>
  R64  M_C_CPU0_SA_DQS_DN<2>  DDR2_SA_DQS_DN2  @S9S_MB_2U_LIB.S9S_MB_2U(SCH_1):M_C_CPU0_SA_DQS_DN<2>
  AB67  M_C_CPU0_SA_DQS_DN<1>  DDR2_SA_DQS_DN1  @S9S_MB_2U_LIB.S9S_MB_2U(SCH_1):M_C_CPU0_SA_DQS_DN<1>
  R76  M_C_CPU0_SA_DQS_DN<0>  DDR2_SA_DQS_DN0  @S9S_MB_2U_LIB.S9S_MB_2U(SCH_1):M_C_CPU0_SA_DQS_DN<0>
  AC68  M_C_CPU0_SA_DQ<9>  DDR2_SA_DQ9  @S9S_MB_2U_LIB.S9S_MB_2U(SCH_1):M_C_CPU0_SA_DQ<9>
  AD69  M_C_CPU0_SA_DQ<8>  DDR2_SA_DQ8  @S9S_MB_2U_LIB.S9S_MB_2U(SCH_1):M_C_CPU0_SA_DQ<8>
  W74  M_C_CPU0_SA_DQ<7>  DDR2_SA_DQ7  @S9S_MB_2U_LIB.S9S_MB_2U(SCH_1):M_C_CPU0_SA_DQ<7>
  Y75  M_C_CPU0_SA_DQ<6>  DDR2_SA_DQ6  @S9S_MB_2U_LIB.S9S_MB_2U(SCH_1):M_C_CPU0_SA_DQ<6>
  U74  M_C_CPU0_SA_DQ<5>  DDR2_SA_DQ5  @S9S_MB_2U_LIB.S9S_MB_2U(SCH_1):M_C_CPU0_SA_DQ<5>
  T75  M_C_CPU0_SA_DQ<4>  DDR2_SA_DQ4  @S9S_MB_2U_LIB.S9S_MB_2U(SCH_1):M_C_CPU0_SA_DQ<4>
  Y77  M_C_CPU0_SA_DQ<3>  DDR2_SA_DQ3  @S9S_MB_2U_LIB.S9S_MB_2U(SCH_1):M_C_CPU0_SA_DQ<3>
  AF59  M_C_CPU0_SA_DQ<31>  DDR2_SA_DQ31  @S9S_MB_2U_LIB.S9S_MB_2U(SCH_1):M_C_CPU0_SA_DQ<31>
  AG60  M_C_CPU0_SA_DQ<30>  DDR2_SA_DQ30  @S9S_MB_2U_LIB.S9S_MB_2U(SCH_1):M_C_CPU0_SA_DQ<30>
  W78  M_C_CPU0_SA_DQ<2>  DDR2_SA_DQ2  @S9S_MB_2U_LIB.S9S_MB_2U(SCH_1):M_C_CPU0_SA_DQ<2>
  AD59  M_C_CPU0_SA_DQ<29>  DDR2_SA_DQ29  @S9S_MB_2U_LIB.S9S_MB_2U(SCH_1):M_C_CPU0_SA_DQ<29>
  AC60  M_C_CPU0_SA_DQ<28>  DDR2_SA_DQ28  @S9S_MB_2U_LIB.S9S_MB_2U(SCH_1):M_C_CPU0_SA_DQ<28>
  AG62  M_C_CPU0_SA_DQ<27>  DDR2_SA_DQ27  @S9S_MB_2U_LIB.S9S_MB_2U(SCH_1):M_C_CPU0_SA_DQ<27>
  AF63  M_C_CPU0_SA_DQ<26>  DDR2_SA_DQ26  @S9S_MB_2U_LIB.S9S_MB_2U(SCH_1):M_C_CPU0_SA_DQ<26>
  AC62  M_C_CPU0_SA_DQ<25>  DDR2_SA_DQ25  @S9S_MB_2U_LIB.S9S_MB_2U(SCH_1):M_C_CPU0_SA_DQ<25>
  AD63  M_C_CPU0_SA_DQ<24>  DDR2_SA_DQ24  @S9S_MB_2U_LIB.S9S_MB_2U(SCH_1):M_C_CPU0_SA_DQ<24>
  W62  M_C_CPU0_SA_DQ<23>  DDR2_SA_DQ23  @S9S_MB_2U_LIB.S9S_MB_2U(SCH_1):M_C_CPU0_SA_DQ<23>
  Y63  M_C_CPU0_SA_DQ<22>  DDR2_SA_DQ22  @S9S_MB_2U_LIB.S9S_MB_2U(SCH_1):M_C_CPU0_SA_DQ<22>
  U62  M_C_CPU0_SA_DQ<21>  DDR2_SA_DQ21  @S9S_MB_2U_LIB.S9S_MB_2U(SCH_1):M_C_CPU0_SA_DQ<21>
  T63  M_C_CPU0_SA_DQ<20>  DDR2_SA_DQ20  @S9S_MB_2U_LIB.S9S_MB_2U(SCH_1):M_C_CPU0_SA_DQ<20>
  T77  M_C_CPU0_SA_DQ<1>  DDR2_SA_DQ1  @S9S_MB_2U_LIB.S9S_MB_2U(SCH_1):M_C_CPU0_SA_DQ<1>
  Y65  M_C_CPU0_SA_DQ<19>  DDR2_SA_DQ19  @S9S_MB_2U_LIB.S9S_MB_2U(SCH_1):M_C_CPU0_SA_DQ<19>
  W66  M_C_CPU0_SA_DQ<18>  DDR2_SA_DQ18  @S9S_MB_2U_LIB.S9S_MB_2U(SCH_1):M_C_CPU0_SA_DQ<18>
  T65  M_C_CPU0_SA_DQ<17>  DDR2_SA_DQ17  @S9S_MB_2U_LIB.S9S_MB_2U(SCH_1):M_C_CPU0_SA_DQ<17>
  U66  M_C_CPU0_SA_DQ<16>  DDR2_SA_DQ16  @S9S_MB_2U_LIB.S9S_MB_2U(SCH_1):M_C_CPU0_SA_DQ<16>
  AF65  M_C_CPU0_SA_DQ<15>  DDR2_SA_DQ15  @S9S_MB_2U_LIB.S9S_MB_2U(SCH_1):M_C_CPU0_SA_DQ<15>
  AG66  M_C_CPU0_SA_DQ<14>  DDR2_SA_DQ14  @S9S_MB_2U_LIB.S9S_MB_2U(SCH_1):M_C_CPU0_SA_DQ<14>
  AD65  M_C_CPU0_SA_DQ<13>  DDR2_SA_DQ13  @S9S_MB_2U_LIB.S9S_MB_2U(SCH_1):M_C_CPU0_SA_DQ<13>
  AC66  M_C_CPU0_SA_DQ<12>  DDR2_SA_DQ12  @S9S_MB_2U_LIB.S9S_MB_2U(SCH_1):M_C_CPU0_SA_DQ<12>
  AG68  M_C_CPU0_SA_DQ<11>  DDR2_SA_DQ11  @S9S_MB_2U_LIB.S9S_MB_2U(SCH_1):M_C_CPU0_SA_DQ<11>
  AF69  M_C_CPU0_SA_DQ<10>  DDR2_SA_DQ10  @S9S_MB_2U_LIB.S9S_MB_2U(SCH_1):M_C_CPU0_SA_DQ<10>
  U78  M_C_CPU0_SA_DQ<0>  DDR2_SA_DQ0  @S9S_MB_2U_LIB.S9S_MB_2U(SCH_1):M_C_CPU0_SA_DQ<0>
  Y53  M_C_CPU0_SA_CS_N<3>  DDR2_SA_CS3_N  @S9S_MB_2U_LIB.S9S_MB_2U(SCH_1):M_C_CPU0_SA_CS_N<3>
  W54  M_C_CPU0_SA_CS_N<2>  DDR2_SA_CS2_N  @S9S_MB_2U_LIB.S9S_MB_2U(SCH_1):M_C_CPU0_SA_CS_N<2>
  T53  M_C_CPU0_SA_CS_N<1>  DDR2_SA_CS1_N  @S9S_MB_2U_LIB.S9S_MB_2U(SCH_1):M_C_CPU0_SA_CS_N<1>
  U54  M_C_CPU0_SA_CS_N<0>  DDR2_SA_CS0_N  @S9S_MB_2U_LIB.S9S_MB_2U(SCH_1):M_C_CPU0_SA_CS_N<0>
  AF53  M_C_CPU0_SA_CB<7>  DDR2_SA_ECC7  @S9S_MB_2U_LIB.S9S_MB_2U(SCH_1):M_C_CPU0_SA_CB<7>
  AG54  M_C_CPU0_SA_CB<6>  DDR2_SA_ECC6  @S9S_MB_2U_LIB.S9S_MB_2U(SCH_1):M_C_CPU0_SA_CB<6>
  AD53  M_C_CPU0_SA_CB<5>  DDR2_SA_ECC5  @S9S_MB_2U_LIB.S9S_MB_2U(SCH_1):M_C_CPU0_SA_CB<5>
  AC54  M_C_CPU0_SA_CB<4>  DDR2_SA_ECC4  @S9S_MB_2U_LIB.S9S_MB_2U(SCH_1):M_C_CPU0_SA_CB<4>
  AG56  M_C_CPU0_SA_CB<3>  DDR2_SA_ECC3  @S9S_MB_2U_LIB.S9S_MB_2U(SCH_1):M_C_CPU0_SA_CB<3>
  AF57  M_C_CPU0_SA_CB<2>  DDR2_SA_ECC2  @S9S_MB_2U_LIB.S9S_MB_2U(SCH_1):M_C_CPU0_SA_CB<2>
  AC56  M_C_CPU0_SA_CB<1>  DDR2_SA_ECC1  @S9S_MB_2U_LIB.S9S_MB_2U(SCH_1):M_C_CPU0_SA_CB<1>
  AD57  M_C_CPU0_SA_CB<0>  DDR2_SA_ECC0  @S9S_MB_2U_LIB.S9S_MB_2U(SCH_1):M_C_CPU0_SA_CB<0>
  U48  M_C_CPU0_SA_CA<6>  DDR2_SA_CA6  @S9S_MB_2U_LIB.S9S_MB_2U(SCH_1):M_C_CPU0_SA_CA<6>
  W50  M_C_CPU0_SA_CA<5>  DDR2_SA_CA5  @S9S_MB_2U_LIB.S9S_MB_2U(SCH_1):M_C_CPU0_SA_CA<5>
  U50  M_C_CPU0_SA_CA<4>  DDR2_SA_CA4  @S9S_MB_2U_LIB.S9S_MB_2U(SCH_1):M_C_CPU0_SA_CA<4>
  Y51  M_C_CPU0_SA_CA<3>  DDR2_SA_CA3  @S9S_MB_2U_LIB.S9S_MB_2U(SCH_1):M_C_CPU0_SA_CA<3>
  T51  M_C_CPU0_SA_CA<2>  DDR2_SA_CA2  @S9S_MB_2U_LIB.S9S_MB_2U(SCH_1):M_C_CPU0_SA_CA<2>
  AA52  M_C_CPU0_SA_CA<1>  DDR2_SA_CA1  @S9S_MB_2U_LIB.S9S_MB_2U(SCH_1):M_C_CPU0_SA_CA<1>
  R52  M_C_CPU0_SA_CA<0>  DDR2_SA_CA0  @S9S_MB_2U_LIB.S9S_MB_2U(SCH_1):M_C_CPU0_SA_CA<0>
  AH49  M_C_CPU0_CLK_DP<1>  DDR2_CLK_DP1  @S9S_MB_2U_LIB.S9S_MB_2U(SCH_1):M_C_CPU0_CLK_DP<1>
  AD49  M_C_CPU0_CLK_DP<0>  DDR2_CLK_DP0  @S9S_MB_2U_LIB.S9S_MB_2U(SCH_1):M_C_CPU0_CLK_DP<0>
  AF49  M_C_CPU0_CLK_DN<1>  DDR2_CLK_DN1  @S9S_MB_2U_LIB.S9S_MB_2U(SCH_1):M_C_CPU0_CLK_DN<1>
  AB49  M_C_CPU0_CLK_DN<0>  DDR2_CLK_DN0  @S9S_MB_2U_LIB.S9S_MB_2U(SCH_1):M_C_CPU0_CLK_DN<0>
  AT47  M_C_CPU0_ALERT_N  DDR2_ALERT_N  @S9S_MB_2U_LIB.S9S_MB_2U(SCH_1):M_C_CPU0_ALERT_N

SOCKET4677_AZIFS054P001C01  I169  U2     [SOCKET4677_AZIFS054P001C01-SOCA]
  AP47  M_B_CPU0_SB_RSP<1>  DDR1_B_RSP1  @S9S_MB_2U_LIB.S9S_MB_2U(SCH_1):M_B_CPU0_SB_RSP<1>
  AN48  M_B_CPU0_SB_RSP<0>  DDR1_B_RSP0  @S9S_MB_2U_LIB.S9S_MB_2U(SCH_1):M_B_CPU0_SB_RSP<0>
  P42  M_B_CPU0_SB_PAR  DDR1_SB_PAR  @S9S_MB_2U_LIB.S9S_MB_2U(SCH_1):M_B_CPU0_SB_PAR
  H36  M_B_CPU0_SB_DQS_DP<9>  DDR1_SB_DQS_DP9  @S9S_MB_2U_LIB.S9S_MB_2U(SCH_1):M_B_CPU0_SB_DQS_DP<9>
  G15  M_B_CPU0_SB_DQS_DP<8>  DDR1_SB_DQS_DP8  @S9S_MB_2U_LIB.S9S_MB_2U(SCH_1):M_B_CPU0_SB_DQS_DP<8>
  P18  M_B_CPU0_SB_DQS_DP<7>  DDR1_SB_DQS_DP7  @S9S_MB_2U_LIB.S9S_MB_2U(SCH_1):M_B_CPU0_SB_DQS_DP<7>
  P24  M_B_CPU0_SB_DQS_DP<6>  DDR1_SB_DQS_DP6  @S9S_MB_2U_LIB.S9S_MB_2U(SCH_1):M_B_CPU0_SB_DQS_DP<6>
  AA27  M_B_CPU0_SB_DQS_DP<5>  DDR1_SB_DQS_DP5  @S9S_MB_2U_LIB.S9S_MB_2U(SCH_1):M_B_CPU0_SB_DQS_DP<5>
  M36  M_B_CPU0_SB_DQS_DP<4>  DDR1_SB_DQS_DP4  @S9S_MB_2U_LIB.S9S_MB_2U(SCH_1):M_B_CPU0_SB_DQS_DP<4>
  C15  M_B_CPU0_SB_DQS_DP<3>  DDR1_SB_DQS_DP3  @S9S_MB_2U_LIB.S9S_MB_2U(SCH_1):M_B_CPU0_SB_DQS_DP<3>
  K18  M_B_CPU0_SB_DQS_DP<2>  DDR1_SB_DQS_DP2  @S9S_MB_2U_LIB.S9S_MB_2U(SCH_1):M_B_CPU0_SB_DQS_DP<2>
  K24  M_B_CPU0_SB_DQS_DP<1>  DDR1_SB_DQS_DP1  @S9S_MB_2U_LIB.S9S_MB_2U(SCH_1):M_B_CPU0_SB_DQS_DP<1>
  U27  M_B_CPU0_SB_DQS_DP<0>  DDR1_SB_DQS_DP0  @S9S_MB_2U_LIB.S9S_MB_2U(SCH_1):M_B_CPU0_SB_DQS_DP<0>
  K36  M_B_CPU0_SB_DQS_DN<9>  DDR1_SB_DQS_DN9  @S9S_MB_2U_LIB.S9S_MB_2U(SCH_1):M_B_CPU0_SB_DQS_DN<9>
  E15  M_B_CPU0_SB_DQS_DN<8>  DDR1_SB_DQS_DN8  @S9S_MB_2U_LIB.S9S_MB_2U(SCH_1):M_B_CPU0_SB_DQS_DN<8>
  M18  M_B_CPU0_SB_DQS_DN<7>  DDR1_SB_DQS_DN7  @S9S_MB_2U_LIB.S9S_MB_2U(SCH_1):M_B_CPU0_SB_DQS_DN<7>
  M24  M_B_CPU0_SB_DQS_DN<6>  DDR1_SB_DQS_DN6  @S9S_MB_2U_LIB.S9S_MB_2U(SCH_1):M_B_CPU0_SB_DQS_DN<6>
  W27  M_B_CPU0_SB_DQS_DN<5>  DDR1_SB_DQS_DN5  @S9S_MB_2U_LIB.S9S_MB_2U(SCH_1):M_B_CPU0_SB_DQS_DN<5>
  P36  M_B_CPU0_SB_DQS_DN<4>  DDR1_SB_DQS_DN4  @S9S_MB_2U_LIB.S9S_MB_2U(SCH_1):M_B_CPU0_SB_DQS_DN<4>
  A15  M_B_CPU0_SB_DQS_DN<3>  DDR1_SB_DQS_DN3  @S9S_MB_2U_LIB.S9S_MB_2U(SCH_1):M_B_CPU0_SB_DQS_DN<3>
  H18  M_B_CPU0_SB_DQS_DN<2>  DDR1_SB_DQS_DN2  @S9S_MB_2U_LIB.S9S_MB_2U(SCH_1):M_B_CPU0_SB_DQS_DN<2>
  H24  M_B_CPU0_SB_DQS_DN<1>  DDR1_SB_DQS_DN1  @S9S_MB_2U_LIB.S9S_MB_2U(SCH_1):M_B_CPU0_SB_DQS_DN<1>
  R27  M_B_CPU0_SB_DQS_DN<0>  DDR1_SB_DQS_DN0  @S9S_MB_2U_LIB.S9S_MB_2U(SCH_1):M_B_CPU0_SB_DQS_DN<0>
  J25  M_B_CPU0_SB_DQ<9>  DDR1_SB_DQ9  @S9S_MB_2U_LIB.S9S_MB_2U(SCH_1):M_B_CPU0_SB_DQ<9>
  K26  M_B_CPU0_SB_DQ<8>  DDR1_SB_DQ8  @S9S_MB_2U_LIB.S9S_MB_2U(SCH_1):M_B_CPU0_SB_DQ<8>
  W25  M_B_CPU0_SB_DQ<7>  DDR1_SB_DQ7  @S9S_MB_2U_LIB.S9S_MB_2U(SCH_1):M_B_CPU0_SB_DQ<7>
  Y26  M_B_CPU0_SB_DQ<6>  DDR1_SB_DQ6  @S9S_MB_2U_LIB.S9S_MB_2U(SCH_1):M_B_CPU0_SB_DQ<6>
  U25  M_B_CPU0_SB_DQ<5>  DDR1_SB_DQ5  @S9S_MB_2U_LIB.S9S_MB_2U(SCH_1):M_B_CPU0_SB_DQ<5>
  T26  M_B_CPU0_SB_DQ<4>  DDR1_SB_DQ4  @S9S_MB_2U_LIB.S9S_MB_2U(SCH_1):M_B_CPU0_SB_DQ<4>
  Y28  M_B_CPU0_SB_DQ<3>  DDR1_SB_DQ3  @S9S_MB_2U_LIB.S9S_MB_2U(SCH_1):M_B_CPU0_SB_DQ<3>
  F14  M_B_CPU0_SB_DQ<31>  DDR1_SB_DQ31  @S9S_MB_2U_LIB.S9S_MB_2U(SCH_1):M_B_CPU0_SB_DQ<31>
  B14  M_B_CPU0_SB_DQ<30>  DDR1_SB_DQ30  @S9S_MB_2U_LIB.S9S_MB_2U(SCH_1):M_B_CPU0_SB_DQ<30>
  W29  M_B_CPU0_SB_DQ<2>  DDR1_SB_DQ2  @S9S_MB_2U_LIB.S9S_MB_2U(SCH_1):M_B_CPU0_SB_DQ<2>
  E13  M_B_CPU0_SB_DQ<29>  DDR1_SB_DQ29  @S9S_MB_2U_LIB.S9S_MB_2U(SCH_1):M_B_CPU0_SB_DQ<29>
  C13  M_B_CPU0_SB_DQ<28>  DDR1_SB_DQ28  @S9S_MB_2U_LIB.S9S_MB_2U(SCH_1):M_B_CPU0_SB_DQ<28>
  F16  M_B_CPU0_SB_DQ<27>  DDR1_SB_DQ27  @S9S_MB_2U_LIB.S9S_MB_2U(SCH_1):M_B_CPU0_SB_DQ<27>
  E17  M_B_CPU0_SB_DQ<26>  DDR1_SB_DQ26  @S9S_MB_2U_LIB.S9S_MB_2U(SCH_1):M_B_CPU0_SB_DQ<26>
  B16  M_B_CPU0_SB_DQ<25>  DDR1_SB_DQ25  @S9S_MB_2U_LIB.S9S_MB_2U(SCH_1):M_B_CPU0_SB_DQ<25>
  C17  M_B_CPU0_SB_DQ<24>  DDR1_SB_DQ24  @S9S_MB_2U_LIB.S9S_MB_2U(SCH_1):M_B_CPU0_SB_DQ<24>
  M16  M_B_CPU0_SB_DQ<23>  DDR1_SB_DQ23  @S9S_MB_2U_LIB.S9S_MB_2U(SCH_1):M_B_CPU0_SB_DQ<23>
  N17  M_B_CPU0_SB_DQ<22>  DDR1_SB_DQ22  @S9S_MB_2U_LIB.S9S_MB_2U(SCH_1):M_B_CPU0_SB_DQ<22>
  K16  M_B_CPU0_SB_DQ<21>  DDR1_SB_DQ21  @S9S_MB_2U_LIB.S9S_MB_2U(SCH_1):M_B_CPU0_SB_DQ<21>
  J17  M_B_CPU0_SB_DQ<20>  DDR1_SB_DQ20  @S9S_MB_2U_LIB.S9S_MB_2U(SCH_1):M_B_CPU0_SB_DQ<20>
  T28  M_B_CPU0_SB_DQ<1>  DDR1_SB_DQ1  @S9S_MB_2U_LIB.S9S_MB_2U(SCH_1):M_B_CPU0_SB_DQ<1>
  N19  M_B_CPU0_SB_DQ<19>  DDR1_SB_DQ19  @S9S_MB_2U_LIB.S9S_MB_2U(SCH_1):M_B_CPU0_SB_DQ<19>
  M20  M_B_CPU0_SB_DQ<18>  DDR1_SB_DQ18  @S9S_MB_2U_LIB.S9S_MB_2U(SCH_1):M_B_CPU0_SB_DQ<18>
  J19  M_B_CPU0_SB_DQ<17>  DDR1_SB_DQ17  @S9S_MB_2U_LIB.S9S_MB_2U(SCH_1):M_B_CPU0_SB_DQ<17>
  K20  M_B_CPU0_SB_DQ<16>  DDR1_SB_DQ16  @S9S_MB_2U_LIB.S9S_MB_2U(SCH_1):M_B_CPU0_SB_DQ<16>
  M22  M_B_CPU0_SB_DQ<15>  DDR1_SB_DQ15  @S9S_MB_2U_LIB.S9S_MB_2U(SCH_1):M_B_CPU0_SB_DQ<15>
  N23  M_B_CPU0_SB_DQ<14>  DDR1_SB_DQ14  @S9S_MB_2U_LIB.S9S_MB_2U(SCH_1):M_B_CPU0_SB_DQ<14>
  K22  M_B_CPU0_SB_DQ<13>  DDR1_SB_DQ13  @S9S_MB_2U_LIB.S9S_MB_2U(SCH_1):M_B_CPU0_SB_DQ<13>
  J23  M_B_CPU0_SB_DQ<12>  DDR1_SB_DQ12  @S9S_MB_2U_LIB.S9S_MB_2U(SCH_1):M_B_CPU0_SB_DQ<12>
  N25  M_B_CPU0_SB_DQ<11>  DDR1_SB_DQ11  @S9S_MB_2U_LIB.S9S_MB_2U(SCH_1):M_B_CPU0_SB_DQ<11>
  M26  M_B_CPU0_SB_DQ<10>  DDR1_SB_DQ10  @S9S_MB_2U_LIB.S9S_MB_2U(SCH_1):M_B_CPU0_SB_DQ<10>
  U29  M_B_CPU0_SB_DQ<0>  DDR1_SB_DQ0  @S9S_MB_2U_LIB.S9S_MB_2U(SCH_1):M_B_CPU0_SB_DQ<0>
  M40  M_B_CPU0_SB_CS_N<3>  DDR1_SB_CS3_N  @S9S_MB_2U_LIB.S9S_MB_2U(SCH_1):M_B_CPU0_SB_CS_N<3>
  N41  M_B_CPU0_SB_CS_N<2>  DDR1_SB_CS2_N  @S9S_MB_2U_LIB.S9S_MB_2U(SCH_1):M_B_CPU0_SB_CS_N<2>
  K40  M_B_CPU0_SB_CS_N<1>  DDR1_SB_CS1_N  @S9S_MB_2U_LIB.S9S_MB_2U(SCH_1):M_B_CPU0_SB_CS_N<1>
  J41  M_B_CPU0_SB_CS_N<0>  DDR1_SB_CS0_N  @S9S_MB_2U_LIB.S9S_MB_2U(SCH_1):M_B_CPU0_SB_CS_N<0>
  N37  M_B_CPU0_SB_CB<7>  DDR1_SB_ECC7  @S9S_MB_2U_LIB.S9S_MB_2U(SCH_1):M_B_CPU0_SB_CB<7>
  M38  M_B_CPU0_SB_CB<6>  DDR1_SB_ECC6  @S9S_MB_2U_LIB.S9S_MB_2U(SCH_1):M_B_CPU0_SB_CB<6>
  J37  M_B_CPU0_SB_CB<5>  DDR1_SB_ECC5  @S9S_MB_2U_LIB.S9S_MB_2U(SCH_1):M_B_CPU0_SB_CB<5>
  K38  M_B_CPU0_SB_CB<4>  DDR1_SB_ECC4  @S9S_MB_2U_LIB.S9S_MB_2U(SCH_1):M_B_CPU0_SB_CB<4>
  M34  M_B_CPU0_SB_CB<3>  DDR1_SB_ECC3  @S9S_MB_2U_LIB.S9S_MB_2U(SCH_1):M_B_CPU0_SB_CB<3>
  N35  M_B_CPU0_SB_CB<2>  DDR1_SB_ECC2  @S9S_MB_2U_LIB.S9S_MB_2U(SCH_1):M_B_CPU0_SB_CB<2>
  K34  M_B_CPU0_SB_CB<1>  DDR1_SB_ECC1  @S9S_MB_2U_LIB.S9S_MB_2U(SCH_1):M_B_CPU0_SB_CB<1>
  J35  M_B_CPU0_SB_CB<0>  DDR1_SB_ECC0  @S9S_MB_2U_LIB.S9S_MB_2U(SCH_1):M_B_CPU0_SB_CB<0>
  H42  M_B_CPU0_SB_CA<6>  DDR1_SB_CA6  @S9S_MB_2U_LIB.S9S_MB_2U(SCH_1):M_B_CPU0_SB_CA<6>
  N43  M_B_CPU0_SB_CA<5>  DDR1_SB_CA5  @S9S_MB_2U_LIB.S9S_MB_2U(SCH_1):M_B_CPU0_SB_CA<5>
  J43  M_B_CPU0_SB_CA<4>  DDR1_SB_CA4  @S9S_MB_2U_LIB.S9S_MB_2U(SCH_1):M_B_CPU0_SB_CA<4>
  M44  M_B_CPU0_SB_CA<3>  DDR1_SB_CA3  @S9S_MB_2U_LIB.S9S_MB_2U(SCH_1):M_B_CPU0_SB_CA<3>
  K44  M_B_CPU0_SB_CA<2>  DDR1_SB_CA2  @S9S_MB_2U_LIB.S9S_MB_2U(SCH_1):M_B_CPU0_SB_CA<2>
  U43  M_B_CPU0_SB_CA<1>  DDR1_SB_CA1  @S9S_MB_2U_LIB.S9S_MB_2U(SCH_1):M_B_CPU0_SB_CA<1>
  T44  M_B_CPU0_SB_CA<0>  DDR1_SB_CA0  @S9S_MB_2U_LIB.S9S_MB_2U(SCH_1):M_B_CPU0_SB_CA<0>
  AK47  M_B_CPU0_SA_RSP<1>  DDR1_A_RSP1  @S9S_MB_2U_LIB.S9S_MB_2U(SCH_1):M_B_CPU0_SA_RSP<1>
  AL48  M_B_CPU0_SA_RSP<0>  DDR1_A_RSP0  @S9S_MB_2U_LIB.S9S_MB_2U(SCH_1):M_B_CPU0_SA_RSP<0>
  W43  M_B_CPU0_SA_PAR  DDR1_SA_PAR  @S9S_MB_2U_LIB.S9S_MB_2U(SCH_1):M_B_CPU0_SA_PAR
  P55  M_B_CPU0_SA_DQS_DP<9>  DDR1_SA_DQS_DP9  @S9S_MB_2U_LIB.S9S_MB_2U(SCH_1):M_B_CPU0_SA_DQS_DP<9>
  W58  M_B_CPU0_SA_DQS_DP<8>  DDR1_SA_DQS_DP8  @S9S_MB_2U_LIB.S9S_MB_2U(SCH_1):M_B_CPU0_SA_DQS_DP<8>
  P61  M_B_CPU0_SA_DQS_DP<7>  DDR1_SA_DQS_DP7  @S9S_MB_2U_LIB.S9S_MB_2U(SCH_1):M_B_CPU0_SA_DQS_DP<7>
  W70  M_B_CPU0_SA_DQS_DP<6>  DDR1_SA_DQS_DP6  @S9S_MB_2U_LIB.S9S_MB_2U(SCH_1):M_B_CPU0_SA_DQS_DP<6>
  P73  M_B_CPU0_SA_DQS_DP<5>  DDR1_SA_DQS_DP5  @S9S_MB_2U_LIB.S9S_MB_2U(SCH_1):M_B_CPU0_SA_DQS_DP<5>
  K55  M_B_CPU0_SA_DQS_DP<4>  DDR1_SA_DQS_DP4  @S9S_MB_2U_LIB.S9S_MB_2U(SCH_1):M_B_CPU0_SA_DQS_DP<4>
  U58  M_B_CPU0_SA_DQS_DP<3>  DDR1_SA_DQS_DP3  @S9S_MB_2U_LIB.S9S_MB_2U(SCH_1):M_B_CPU0_SA_DQS_DP<3>
  K61  M_B_CPU0_SA_DQS_DP<2>  DDR1_SA_DQS_DP2  @S9S_MB_2U_LIB.S9S_MB_2U(SCH_1):M_B_CPU0_SA_DQS_DP<2>
  U70  M_B_CPU0_SA_DQS_DP<1>  DDR1_SA_DQS_DP1  @S9S_MB_2U_LIB.S9S_MB_2U(SCH_1):M_B_CPU0_SA_DQS_DP<1>
  K73  M_B_CPU0_SA_DQS_DP<0>  DDR1_SA_DQS_DP0  @S9S_MB_2U_LIB.S9S_MB_2U(SCH_1):M_B_CPU0_SA_DQS_DP<0>
  M55  M_B_CPU0_SA_DQS_DN<9>  DDR1_SA_DQS_DN9  @S9S_MB_2U_LIB.S9S_MB_2U(SCH_1):M_B_CPU0_SA_DQS_DN<9>
  AA58  M_B_CPU0_SA_DQS_DN<8>  DDR1_SA_DQS_DN8  @S9S_MB_2U_LIB.S9S_MB_2U(SCH_1):M_B_CPU0_SA_DQS_DN<8>
  M61  M_B_CPU0_SA_DQS_DN<7>  DDR1_SA_DQS_DN7  @S9S_MB_2U_LIB.S9S_MB_2U(SCH_1):M_B_CPU0_SA_DQS_DN<7>
  AA70  M_B_CPU0_SA_DQS_DN<6>  DDR1_SA_DQS_DN6  @S9S_MB_2U_LIB.S9S_MB_2U(SCH_1):M_B_CPU0_SA_DQS_DN<6>
  M73  M_B_CPU0_SA_DQS_DN<5>  DDR1_SA_DQS_DN5  @S9S_MB_2U_LIB.S9S_MB_2U(SCH_1):M_B_CPU0_SA_DQS_DN<5>
  H55  M_B_CPU0_SA_DQS_DN<4>  DDR1_SA_DQS_DN4  @S9S_MB_2U_LIB.S9S_MB_2U(SCH_1):M_B_CPU0_SA_DQS_DN<4>
  R58  M_B_CPU0_SA_DQS_DN<3>  DDR1_SA_DQS_DN3  @S9S_MB_2U_LIB.S9S_MB_2U(SCH_1):M_B_CPU0_SA_DQS_DN<3>
  H61  M_B_CPU0_SA_DQS_DN<2>  DDR1_SA_DQS_DN2  @S9S_MB_2U_LIB.S9S_MB_2U(SCH_1):M_B_CPU0_SA_DQS_DN<2>
  R70  M_B_CPU0_SA_DQS_DN<1>  DDR1_SA_DQS_DN1  @S9S_MB_2U_LIB.S9S_MB_2U(SCH_1):M_B_CPU0_SA_DQS_DN<1>
  H73  M_B_CPU0_SA_DQS_DN<0>  DDR1_SA_DQS_DN0  @S9S_MB_2U_LIB.S9S_MB_2U(SCH_1):M_B_CPU0_SA_DQS_DN<0>
  T71  M_B_CPU0_SA_DQ<9>  DDR1_SA_DQ9  @S9S_MB_2U_LIB.S9S_MB_2U(SCH_1):M_B_CPU0_SA_DQ<9>
  U72  M_B_CPU0_SA_DQ<8>  DDR1_SA_DQ8  @S9S_MB_2U_LIB.S9S_MB_2U(SCH_1):M_B_CPU0_SA_DQ<8>
  M71  M_B_CPU0_SA_DQ<7>  DDR1_SA_DQ7  @S9S_MB_2U_LIB.S9S_MB_2U(SCH_1):M_B_CPU0_SA_DQ<7>
  N72  M_B_CPU0_SA_DQ<6>  DDR1_SA_DQ6  @S9S_MB_2U_LIB.S9S_MB_2U(SCH_1):M_B_CPU0_SA_DQ<6>
  K71  M_B_CPU0_SA_DQ<5>  DDR1_SA_DQ5  @S9S_MB_2U_LIB.S9S_MB_2U(SCH_1):M_B_CPU0_SA_DQ<5>
  J72  M_B_CPU0_SA_DQ<4>  DDR1_SA_DQ4  @S9S_MB_2U_LIB.S9S_MB_2U(SCH_1):M_B_CPU0_SA_DQ<4>
  N74  M_B_CPU0_SA_DQ<3>  DDR1_SA_DQ3  @S9S_MB_2U_LIB.S9S_MB_2U(SCH_1):M_B_CPU0_SA_DQ<3>
  W56  M_B_CPU0_SA_DQ<31>  DDR1_SA_DQ31  @S9S_MB_2U_LIB.S9S_MB_2U(SCH_1):M_B_CPU0_SA_DQ<31>
  Y57  M_B_CPU0_SA_DQ<30>  DDR1_SA_DQ30  @S9S_MB_2U_LIB.S9S_MB_2U(SCH_1):M_B_CPU0_SA_DQ<30>
  M75  M_B_CPU0_SA_DQ<2>  DDR1_SA_DQ2  @S9S_MB_2U_LIB.S9S_MB_2U(SCH_1):M_B_CPU0_SA_DQ<2>
  U56  M_B_CPU0_SA_DQ<29>  DDR1_SA_DQ29  @S9S_MB_2U_LIB.S9S_MB_2U(SCH_1):M_B_CPU0_SA_DQ<29>
  T57  M_B_CPU0_SA_DQ<28>  DDR1_SA_DQ28  @S9S_MB_2U_LIB.S9S_MB_2U(SCH_1):M_B_CPU0_SA_DQ<28>
  Y59  M_B_CPU0_SA_DQ<27>  DDR1_SA_DQ27  @S9S_MB_2U_LIB.S9S_MB_2U(SCH_1):M_B_CPU0_SA_DQ<27>
  W60  M_B_CPU0_SA_DQ<26>  DDR1_SA_DQ26  @S9S_MB_2U_LIB.S9S_MB_2U(SCH_1):M_B_CPU0_SA_DQ<26>
  T59  M_B_CPU0_SA_DQ<25>  DDR1_SA_DQ25  @S9S_MB_2U_LIB.S9S_MB_2U(SCH_1):M_B_CPU0_SA_DQ<25>
  U60  M_B_CPU0_SA_DQ<24>  DDR1_SA_DQ24  @S9S_MB_2U_LIB.S9S_MB_2U(SCH_1):M_B_CPU0_SA_DQ<24>
  M59  M_B_CPU0_SA_DQ<23>  DDR1_SA_DQ23  @S9S_MB_2U_LIB.S9S_MB_2U(SCH_1):M_B_CPU0_SA_DQ<23>
  N60  M_B_CPU0_SA_DQ<22>  DDR1_SA_DQ22  @S9S_MB_2U_LIB.S9S_MB_2U(SCH_1):M_B_CPU0_SA_DQ<22>
  K59  M_B_CPU0_SA_DQ<21>  DDR1_SA_DQ21  @S9S_MB_2U_LIB.S9S_MB_2U(SCH_1):M_B_CPU0_SA_DQ<21>
  J60  M_B_CPU0_SA_DQ<20>  DDR1_SA_DQ20  @S9S_MB_2U_LIB.S9S_MB_2U(SCH_1):M_B_CPU0_SA_DQ<20>
  J74  M_B_CPU0_SA_DQ<1>  DDR1_SA_DQ1  @S9S_MB_2U_LIB.S9S_MB_2U(SCH_1):M_B_CPU0_SA_DQ<1>
  N62  M_B_CPU0_SA_DQ<19>  DDR1_SA_DQ19  @S9S_MB_2U_LIB.S9S_MB_2U(SCH_1):M_B_CPU0_SA_DQ<19>
  M63  M_B_CPU0_SA_DQ<18>  DDR1_SA_DQ18  @S9S_MB_2U_LIB.S9S_MB_2U(SCH_1):M_B_CPU0_SA_DQ<18>
  J62  M_B_CPU0_SA_DQ<17>  DDR1_SA_DQ17  @S9S_MB_2U_LIB.S9S_MB_2U(SCH_1):M_B_CPU0_SA_DQ<17>
  K63  M_B_CPU0_SA_DQ<16>  DDR1_SA_DQ16  @S9S_MB_2U_LIB.S9S_MB_2U(SCH_1):M_B_CPU0_SA_DQ<16>
  W68  M_B_CPU0_SA_DQ<15>  DDR1_SA_DQ15  @S9S_MB_2U_LIB.S9S_MB_2U(SCH_1):M_B_CPU0_SA_DQ<15>
  Y69  M_B_CPU0_SA_DQ<14>  DDR1_SA_DQ14  @S9S_MB_2U_LIB.S9S_MB_2U(SCH_1):M_B_CPU0_SA_DQ<14>
  U68  M_B_CPU0_SA_DQ<13>  DDR1_SA_DQ13  @S9S_MB_2U_LIB.S9S_MB_2U(SCH_1):M_B_CPU0_SA_DQ<13>
  T69  M_B_CPU0_SA_DQ<12>  DDR1_SA_DQ12  @S9S_MB_2U_LIB.S9S_MB_2U(SCH_1):M_B_CPU0_SA_DQ<12>
  Y71  M_B_CPU0_SA_DQ<11>  DDR1_SA_DQ11  @S9S_MB_2U_LIB.S9S_MB_2U(SCH_1):M_B_CPU0_SA_DQ<11>
  W72  M_B_CPU0_SA_DQ<10>  DDR1_SA_DQ10  @S9S_MB_2U_LIB.S9S_MB_2U(SCH_1):M_B_CPU0_SA_DQ<10>
  K75  M_B_CPU0_SA_DQ<0>  DDR1_SA_DQ0  @S9S_MB_2U_LIB.S9S_MB_2U(SCH_1):M_B_CPU0_SA_DQ<0>
  N50  M_B_CPU0_SA_CS_N<3>  DDR1_SA_CS3_N  @S9S_MB_2U_LIB.S9S_MB_2U(SCH_1):M_B_CPU0_SA_CS_N<3>
  M51  M_B_CPU0_SA_CS_N<2>  DDR1_SA_CS2_N  @S9S_MB_2U_LIB.S9S_MB_2U(SCH_1):M_B_CPU0_SA_CS_N<2>
  J50  M_B_CPU0_SA_CS_N<1>  DDR1_SA_CS1_N  @S9S_MB_2U_LIB.S9S_MB_2U(SCH_1):M_B_CPU0_SA_CS_N<1>
  K51  M_B_CPU0_SA_CS_N<0>  DDR1_SA_CS0_N  @S9S_MB_2U_LIB.S9S_MB_2U(SCH_1):M_B_CPU0_SA_CS_N<0>
  M53  M_B_CPU0_SA_CB<7>  DDR1_SA_ECC7  @S9S_MB_2U_LIB.S9S_MB_2U(SCH_1):M_B_CPU0_SA_CB<7>
  N54  M_B_CPU0_SA_CB<6>  DDR1_SA_ECC6  @S9S_MB_2U_LIB.S9S_MB_2U(SCH_1):M_B_CPU0_SA_CB<6>
  K53  M_B_CPU0_SA_CB<5>  DDR1_SA_ECC5  @S9S_MB_2U_LIB.S9S_MB_2U(SCH_1):M_B_CPU0_SA_CB<5>
  J54  M_B_CPU0_SA_CB<4>  DDR1_SA_ECC4  @S9S_MB_2U_LIB.S9S_MB_2U(SCH_1):M_B_CPU0_SA_CB<4>
  N56  M_B_CPU0_SA_CB<3>  DDR1_SA_ECC3  @S9S_MB_2U_LIB.S9S_MB_2U(SCH_1):M_B_CPU0_SA_CB<3>
  M57  M_B_CPU0_SA_CB<2>  DDR1_SA_ECC2  @S9S_MB_2U_LIB.S9S_MB_2U(SCH_1):M_B_CPU0_SA_CB<2>
  J56  M_B_CPU0_SA_CB<1>  DDR1_SA_ECC1  @S9S_MB_2U_LIB.S9S_MB_2U(SCH_1):M_B_CPU0_SA_CB<1>
  K57  M_B_CPU0_SA_CB<0>  DDR1_SA_ECC0  @S9S_MB_2U_LIB.S9S_MB_2U(SCH_1):M_B_CPU0_SA_CB<0>
  Y44  M_B_CPU0_SA_CA<6>  DDR1_SA_CA6  @S9S_MB_2U_LIB.S9S_MB_2U(SCH_1):M_B_CPU0_SA_CA<6>
  M47  M_B_CPU0_SA_CA<5>  DDR1_SA_CA5  @S9S_MB_2U_LIB.S9S_MB_2U(SCH_1):M_B_CPU0_SA_CA<5>
  K47  M_B_CPU0_SA_CA<4>  DDR1_SA_CA4  @S9S_MB_2U_LIB.S9S_MB_2U(SCH_1):M_B_CPU0_SA_CA<4>
  N48  M_B_CPU0_SA_CA<3>  DDR1_SA_CA3  @S9S_MB_2U_LIB.S9S_MB_2U(SCH_1):M_B_CPU0_SA_CA<3>
  J48  M_B_CPU0_SA_CA<2>  DDR1_SA_CA2  @S9S_MB_2U_LIB.S9S_MB_2U(SCH_1):M_B_CPU0_SA_CA<2>
  P49  M_B_CPU0_SA_CA<1>  DDR1_SA_CA1  @S9S_MB_2U_LIB.S9S_MB_2U(SCH_1):M_B_CPU0_SA_CA<1>
  H49  M_B_CPU0_SA_CA<0>  DDR1_SA_CA0  @S9S_MB_2U_LIB.S9S_MB_2U(SCH_1):M_B_CPU0_SA_CA<0>
  AA45  M_B_CPU0_CLK_DP<1>  DDR1_CLK_DP1  @S9S_MB_2U_LIB.S9S_MB_2U(SCH_1):M_B_CPU0_CLK_DP<1>
  U45  M_B_CPU0_CLK_DP<0>  DDR1_CLK_DP0  @S9S_MB_2U_LIB.S9S_MB_2U(SCH_1):M_B_CPU0_CLK_DP<0>
  W45  M_B_CPU0_CLK_DN<1>  DDR1_CLK_DN1  @S9S_MB_2U_LIB.S9S_MB_2U(SCH_1):M_B_CPU0_CLK_DN<1>
  R45  M_B_CPU0_CLK_DN<0>  DDR1_CLK_DN0  @S9S_MB_2U_LIB.S9S_MB_2U(SCH_1):M_B_CPU0_CLK_DN<0>
  AV49  M_B_CPU0_ALERT_N  DDR1_ALERT_N  @S9S_MB_2U_LIB.S9S_MB_2U(SCH_1):M_B_CPU0_ALERT_N

SOCKET4677_AZIFS054P001C01  I1   U2     [SOCKET4677_AZIFS054P001C01-SOCA]
  AV42  M_A_CPU0_SB_RSP<1>  DDR0_B_RSP1  @S9S_MB_2U_LIB.S9S_MB_2U(SCH_1):M_A_CPU0_SB_RSP<1>
  AV44  M_A_CPU0_SB_RSP<0>  DDR0_B_RSP0  @S9S_MB_2U_LIB.S9S_MB_2U(SCH_1):M_A_CPU0_SB_RSP<0>
  G39  M_A_CPU0_SB_PAR  DDR0_SB_PAR  @S9S_MB_2U_LIB.S9S_MB_2U(SCH_1):M_A_CPU0_SB_PAR
  C33  M_A_CPU0_SB_DQS_DP<9>  DDR0_SB_DQS_DP9  @S9S_MB_2U_LIB.S9S_MB_2U(SCH_1):M_A_CPU0_SB_DQS_DP<9>
   E9  M_A_CPU0_SB_DQS_DP<8>  DDR0_SB_DQS_DP8  @S9S_MB_2U_LIB.S9S_MB_2U(SCH_1):M_A_CPU0_SB_DQS_DP<8>
  E21  M_A_CPU0_SB_DQS_DP<7>  DDR0_SB_DQS_DP7  @S9S_MB_2U_LIB.S9S_MB_2U(SCH_1):M_A_CPU0_SB_DQS_DP<7>
  E27  M_A_CPU0_SB_DQS_DP<6>  DDR0_SB_DQS_DP6  @S9S_MB_2U_LIB.S9S_MB_2U(SCH_1):M_A_CPU0_SB_DQS_DP<6>
  P30  M_A_CPU0_SB_DQS_DP<5>  DDR0_SB_DQS_DP5  @S9S_MB_2U_LIB.S9S_MB_2U(SCH_1):M_A_CPU0_SB_DQS_DP<5>
  E33  M_A_CPU0_SB_DQS_DP<4>  DDR0_SB_DQS_DP4  @S9S_MB_2U_LIB.S9S_MB_2U(SCH_1):M_A_CPU0_SB_DQS_DP<4>
   C9  M_A_CPU0_SB_DQS_DP<3>  DDR0_SB_DQS_DP3  @S9S_MB_2U_LIB.S9S_MB_2U(SCH_1):M_A_CPU0_SB_DQS_DP<3>
  C21  M_A_CPU0_SB_DQS_DP<2>  DDR0_SB_DQS_DP2  @S9S_MB_2U_LIB.S9S_MB_2U(SCH_1):M_A_CPU0_SB_DQS_DP<2>
  C27  M_A_CPU0_SB_DQS_DP<1>  DDR0_SB_DQS_DP1  @S9S_MB_2U_LIB.S9S_MB_2U(SCH_1):M_A_CPU0_SB_DQS_DP<1>
  K30  M_A_CPU0_SB_DQS_DP<0>  DDR0_SB_DQS_DP0  @S9S_MB_2U_LIB.S9S_MB_2U(SCH_1):M_A_CPU0_SB_DQS_DP<0>
  A33  M_A_CPU0_SB_DQS_DN<9>  DDR0_SB_DQS_DN9  @S9S_MB_2U_LIB.S9S_MB_2U(SCH_1):M_A_CPU0_SB_DQS_DN<9>
   G9  M_A_CPU0_SB_DQS_DN<8>  DDR0_SB_DQS_DN8  @S9S_MB_2U_LIB.S9S_MB_2U(SCH_1):M_A_CPU0_SB_DQS_DN<8>
  G21  M_A_CPU0_SB_DQS_DN<7>  DDR0_SB_DQS_DN7  @S9S_MB_2U_LIB.S9S_MB_2U(SCH_1):M_A_CPU0_SB_DQS_DN<7>
  G27  M_A_CPU0_SB_DQS_DN<6>  DDR0_SB_DQS_DN6  @S9S_MB_2U_LIB.S9S_MB_2U(SCH_1):M_A_CPU0_SB_DQS_DN<6>
  M30  M_A_CPU0_SB_DQS_DN<5>  DDR0_SB_DQS_DN5  @S9S_MB_2U_LIB.S9S_MB_2U(SCH_1):M_A_CPU0_SB_DQS_DN<5>
  G33  M_A_CPU0_SB_DQS_DN<4>  DDR0_SB_DQS_DN4  @S9S_MB_2U_LIB.S9S_MB_2U(SCH_1):M_A_CPU0_SB_DQS_DN<4>
   A9  M_A_CPU0_SB_DQS_DN<3>  DDR0_SB_DQS_DN3  @S9S_MB_2U_LIB.S9S_MB_2U(SCH_1):M_A_CPU0_SB_DQS_DN<3>
  A21  M_A_CPU0_SB_DQS_DN<2>  DDR0_SB_DQS_DN2  @S9S_MB_2U_LIB.S9S_MB_2U(SCH_1):M_A_CPU0_SB_DQS_DN<2>
  A27  M_A_CPU0_SB_DQS_DN<1>  DDR0_SB_DQS_DN1  @S9S_MB_2U_LIB.S9S_MB_2U(SCH_1):M_A_CPU0_SB_DQS_DN<1>
  H30  M_A_CPU0_SB_DQS_DN<0>  DDR0_SB_DQS_DN0  @S9S_MB_2U_LIB.S9S_MB_2U(SCH_1):M_A_CPU0_SB_DQS_DN<0>
  B28  M_A_CPU0_SB_DQ<9>  DDR0_SB_DQ9  @S9S_MB_2U_LIB.S9S_MB_2U(SCH_1):M_A_CPU0_SB_DQ<9>
  C29  M_A_CPU0_SB_DQ<8>  DDR0_SB_DQ8  @S9S_MB_2U_LIB.S9S_MB_2U(SCH_1):M_A_CPU0_SB_DQ<8>
  M28  M_A_CPU0_SB_DQ<7>  DDR0_SB_DQ7  @S9S_MB_2U_LIB.S9S_MB_2U(SCH_1):M_A_CPU0_SB_DQ<7>
  N29  M_A_CPU0_SB_DQ<6>  DDR0_SB_DQ6  @S9S_MB_2U_LIB.S9S_MB_2U(SCH_1):M_A_CPU0_SB_DQ<6>
  K28  M_A_CPU0_SB_DQ<5>  DDR0_SB_DQ5  @S9S_MB_2U_LIB.S9S_MB_2U(SCH_1):M_A_CPU0_SB_DQ<5>
  J29  M_A_CPU0_SB_DQ<4>  DDR0_SB_DQ4  @S9S_MB_2U_LIB.S9S_MB_2U(SCH_1):M_A_CPU0_SB_DQ<4>
  N31  M_A_CPU0_SB_DQ<3>  DDR0_SB_DQ3  @S9S_MB_2U_LIB.S9S_MB_2U(SCH_1):M_A_CPU0_SB_DQ<3>
   E7  M_A_CPU0_SB_DQ<31>  DDR0_SB_DQ31  @S9S_MB_2U_LIB.S9S_MB_2U(SCH_1):M_A_CPU0_SB_DQ<31>
   F8  M_A_CPU0_SB_DQ<30>  DDR0_SB_DQ30  @S9S_MB_2U_LIB.S9S_MB_2U(SCH_1):M_A_CPU0_SB_DQ<30>
  M32  M_A_CPU0_SB_DQ<2>  DDR0_SB_DQ2  @S9S_MB_2U_LIB.S9S_MB_2U(SCH_1):M_A_CPU0_SB_DQ<2>
   C7  M_A_CPU0_SB_DQ<29>  DDR0_SB_DQ29  @S9S_MB_2U_LIB.S9S_MB_2U(SCH_1):M_A_CPU0_SB_DQ<29>
   B8  M_A_CPU0_SB_DQ<28>  DDR0_SB_DQ28  @S9S_MB_2U_LIB.S9S_MB_2U(SCH_1):M_A_CPU0_SB_DQ<28>
  F10  M_A_CPU0_SB_DQ<27>  DDR0_SB_DQ27  @S9S_MB_2U_LIB.S9S_MB_2U(SCH_1):M_A_CPU0_SB_DQ<27>
  E11  M_A_CPU0_SB_DQ<26>  DDR0_SB_DQ26  @S9S_MB_2U_LIB.S9S_MB_2U(SCH_1):M_A_CPU0_SB_DQ<26>
  B10  M_A_CPU0_SB_DQ<25>  DDR0_SB_DQ25  @S9S_MB_2U_LIB.S9S_MB_2U(SCH_1):M_A_CPU0_SB_DQ<25>
  C11  M_A_CPU0_SB_DQ<24>  DDR0_SB_DQ24  @S9S_MB_2U_LIB.S9S_MB_2U(SCH_1):M_A_CPU0_SB_DQ<24>
  E19  M_A_CPU0_SB_DQ<23>  DDR0_SB_DQ23  @S9S_MB_2U_LIB.S9S_MB_2U(SCH_1):M_A_CPU0_SB_DQ<23>
  F20  M_A_CPU0_SB_DQ<22>  DDR0_SB_DQ22  @S9S_MB_2U_LIB.S9S_MB_2U(SCH_1):M_A_CPU0_SB_DQ<22>
  C19  M_A_CPU0_SB_DQ<21>  DDR0_SB_DQ21  @S9S_MB_2U_LIB.S9S_MB_2U(SCH_1):M_A_CPU0_SB_DQ<21>
  B20  M_A_CPU0_SB_DQ<20>  DDR0_SB_DQ20  @S9S_MB_2U_LIB.S9S_MB_2U(SCH_1):M_A_CPU0_SB_DQ<20>
  J31  M_A_CPU0_SB_DQ<1>  DDR0_SB_DQ1  @S9S_MB_2U_LIB.S9S_MB_2U(SCH_1):M_A_CPU0_SB_DQ<1>
  F22  M_A_CPU0_SB_DQ<19>  DDR0_SB_DQ19  @S9S_MB_2U_LIB.S9S_MB_2U(SCH_1):M_A_CPU0_SB_DQ<19>
  E23  M_A_CPU0_SB_DQ<18>  DDR0_SB_DQ18  @S9S_MB_2U_LIB.S9S_MB_2U(SCH_1):M_A_CPU0_SB_DQ<18>
  B22  M_A_CPU0_SB_DQ<17>  DDR0_SB_DQ17  @S9S_MB_2U_LIB.S9S_MB_2U(SCH_1):M_A_CPU0_SB_DQ<17>
  C23  M_A_CPU0_SB_DQ<16>  DDR0_SB_DQ16  @S9S_MB_2U_LIB.S9S_MB_2U(SCH_1):M_A_CPU0_SB_DQ<16>
  E25  M_A_CPU0_SB_DQ<15>  DDR0_SB_DQ15  @S9S_MB_2U_LIB.S9S_MB_2U(SCH_1):M_A_CPU0_SB_DQ<15>
  F26  M_A_CPU0_SB_DQ<14>  DDR0_SB_DQ14  @S9S_MB_2U_LIB.S9S_MB_2U(SCH_1):M_A_CPU0_SB_DQ<14>
  C25  M_A_CPU0_SB_DQ<13>  DDR0_SB_DQ13  @S9S_MB_2U_LIB.S9S_MB_2U(SCH_1):M_A_CPU0_SB_DQ<13>
  B26  M_A_CPU0_SB_DQ<12>  DDR0_SB_DQ12  @S9S_MB_2U_LIB.S9S_MB_2U(SCH_1):M_A_CPU0_SB_DQ<12>
  F28  M_A_CPU0_SB_DQ<11>  DDR0_SB_DQ11  @S9S_MB_2U_LIB.S9S_MB_2U(SCH_1):M_A_CPU0_SB_DQ<11>
  E29  M_A_CPU0_SB_DQ<10>  DDR0_SB_DQ10  @S9S_MB_2U_LIB.S9S_MB_2U(SCH_1):M_A_CPU0_SB_DQ<10>
  K32  M_A_CPU0_SB_DQ<0>  DDR0_SB_DQ0  @S9S_MB_2U_LIB.S9S_MB_2U(SCH_1):M_A_CPU0_SB_DQ<0>
  E37  M_A_CPU0_SB_CS_N<3>  DDR0_SB_CS3_N  @S9S_MB_2U_LIB.S9S_MB_2U(SCH_1):M_A_CPU0_SB_CS_N<3>
  F38  M_A_CPU0_SB_CS_N<2>  DDR0_SB_CS2_N  @S9S_MB_2U_LIB.S9S_MB_2U(SCH_1):M_A_CPU0_SB_CS_N<2>
  C37  M_A_CPU0_SB_CS_N<1>  DDR0_SB_CS1_N  @S9S_MB_2U_LIB.S9S_MB_2U(SCH_1):M_A_CPU0_SB_CS_N<1>
  B38  M_A_CPU0_SB_CS_N<0>  DDR0_SB_CS0_N  @S9S_MB_2U_LIB.S9S_MB_2U(SCH_1):M_A_CPU0_SB_CS_N<0>
  F34  M_A_CPU0_SB_CB<7>  DDR0_SB_ECC7  @S9S_MB_2U_LIB.S9S_MB_2U(SCH_1):M_A_CPU0_SB_CB<7>
  E35  M_A_CPU0_SB_CB<6>  DDR0_SB_ECC6  @S9S_MB_2U_LIB.S9S_MB_2U(SCH_1):M_A_CPU0_SB_CB<6>
  B34  M_A_CPU0_SB_CB<5>  DDR0_SB_ECC5  @S9S_MB_2U_LIB.S9S_MB_2U(SCH_1):M_A_CPU0_SB_CB<5>
  C35  M_A_CPU0_SB_CB<4>  DDR0_SB_ECC4  @S9S_MB_2U_LIB.S9S_MB_2U(SCH_1):M_A_CPU0_SB_CB<4>
  E31  M_A_CPU0_SB_CB<3>  DDR0_SB_ECC3  @S9S_MB_2U_LIB.S9S_MB_2U(SCH_1):M_A_CPU0_SB_CB<3>
  F32  M_A_CPU0_SB_CB<2>  DDR0_SB_ECC2  @S9S_MB_2U_LIB.S9S_MB_2U(SCH_1):M_A_CPU0_SB_CB<2>
  C31  M_A_CPU0_SB_CB<1>  DDR0_SB_ECC1  @S9S_MB_2U_LIB.S9S_MB_2U(SCH_1):M_A_CPU0_SB_CB<1>
  B32  M_A_CPU0_SB_CB<0>  DDR0_SB_ECC0  @S9S_MB_2U_LIB.S9S_MB_2U(SCH_1):M_A_CPU0_SB_CB<0>
  A39  M_A_CPU0_SB_CA<6>  DDR0_SB_CA6  @S9S_MB_2U_LIB.S9S_MB_2U(SCH_1):M_A_CPU0_SB_CA<6>
  F40  M_A_CPU0_SB_CA<5>  DDR0_SB_CA5  @S9S_MB_2U_LIB.S9S_MB_2U(SCH_1):M_A_CPU0_SB_CA<5>
  B40  M_A_CPU0_SB_CA<4>  DDR0_SB_CA4  @S9S_MB_2U_LIB.S9S_MB_2U(SCH_1):M_A_CPU0_SB_CA<4>
  E41  M_A_CPU0_SB_CA<3>  DDR0_SB_CA3  @S9S_MB_2U_LIB.S9S_MB_2U(SCH_1):M_A_CPU0_SB_CA<3>
  C41  M_A_CPU0_SB_CA<2>  DDR0_SB_CA2  @S9S_MB_2U_LIB.S9S_MB_2U(SCH_1):M_A_CPU0_SB_CA<2>
  F44  M_A_CPU0_SB_CA<1>  DDR0_SB_CA1  @S9S_MB_2U_LIB.S9S_MB_2U(SCH_1):M_A_CPU0_SB_CA<1>
  E43  M_A_CPU0_SB_CA<0>  DDR0_SB_CA0  @S9S_MB_2U_LIB.S9S_MB_2U(SCH_1):M_A_CPU0_SB_CA<0>
  AU43  M_A_CPU0_SA_RSP<1>  DDR0_A_RSP1  @S9S_MB_2U_LIB.S9S_MB_2U(SCH_1):M_A_CPU0_SA_RSP<1>
  AT42  M_A_CPU0_SA_RSP<0>  DDR0_A_RSP0  @S9S_MB_2U_LIB.S9S_MB_2U(SCH_1):M_A_CPU0_SA_RSP<0>
  E48  M_A_CPU0_SA_PAR  DDR0_SA_PAR  @S9S_MB_2U_LIB.S9S_MB_2U(SCH_1):M_A_CPU0_SA_PAR
  E58  M_A_CPU0_SA_DQS_DP<9>  DDR0_SA_DQS_DP9  @S9S_MB_2U_LIB.S9S_MB_2U(SCH_1):M_A_CPU0_SA_DQS_DP<9>
  E64  M_A_CPU0_SA_DQS_DP<8>  DDR0_SA_DQS_DP8  @S9S_MB_2U_LIB.S9S_MB_2U(SCH_1):M_A_CPU0_SA_DQS_DP<8>
  E70  M_A_CPU0_SA_DQS_DP<7>  DDR0_SA_DQS_DP7  @S9S_MB_2U_LIB.S9S_MB_2U(SCH_1):M_A_CPU0_SA_DQS_DP<7>
  M67  M_A_CPU0_SA_DQS_DP<6>  DDR0_SA_DQS_DP6  @S9S_MB_2U_LIB.S9S_MB_2U(SCH_1):M_A_CPU0_SA_DQS_DP<6>
  F77  M_A_CPU0_SA_DQS_DP<5>  DDR0_SA_DQS_DP5  @S9S_MB_2U_LIB.S9S_MB_2U(SCH_1):M_A_CPU0_SA_DQS_DP<5>
  C58  M_A_CPU0_SA_DQS_DP<4>  DDR0_SA_DQS_DP4  @S9S_MB_2U_LIB.S9S_MB_2U(SCH_1):M_A_CPU0_SA_DQS_DP<4>
  C64  M_A_CPU0_SA_DQS_DP<3>  DDR0_SA_DQS_DP3  @S9S_MB_2U_LIB.S9S_MB_2U(SCH_1):M_A_CPU0_SA_DQS_DP<3>
  C70  M_A_CPU0_SA_DQS_DP<2>  DDR0_SA_DQS_DP2  @S9S_MB_2U_LIB.S9S_MB_2U(SCH_1):M_A_CPU0_SA_DQS_DP<2>
  K67  M_A_CPU0_SA_DQS_DP<1>  DDR0_SA_DQS_DP1  @S9S_MB_2U_LIB.S9S_MB_2U(SCH_1):M_A_CPU0_SA_DQS_DP<1>
  D77  M_A_CPU0_SA_DQS_DP<0>  DDR0_SA_DQS_DP0  @S9S_MB_2U_LIB.S9S_MB_2U(SCH_1):M_A_CPU0_SA_DQS_DP<0>
  G58  M_A_CPU0_SA_DQS_DN<9>  DDR0_SA_DQS_DN9  @S9S_MB_2U_LIB.S9S_MB_2U(SCH_1):M_A_CPU0_SA_DQS_DN<9>
  G64  M_A_CPU0_SA_DQS_DN<8>  DDR0_SA_DQS_DN8  @S9S_MB_2U_LIB.S9S_MB_2U(SCH_1):M_A_CPU0_SA_DQS_DN<8>
  G70  M_A_CPU0_SA_DQS_DN<7>  DDR0_SA_DQS_DN7  @S9S_MB_2U_LIB.S9S_MB_2U(SCH_1):M_A_CPU0_SA_DQS_DN<7>
  P67  M_A_CPU0_SA_DQS_DN<6>  DDR0_SA_DQS_DN6  @S9S_MB_2U_LIB.S9S_MB_2U(SCH_1):M_A_CPU0_SA_DQS_DN<6>
  H77  M_A_CPU0_SA_DQS_DN<5>  DDR0_SA_DQS_DN5  @S9S_MB_2U_LIB.S9S_MB_2U(SCH_1):M_A_CPU0_SA_DQS_DN<5>
  A58  M_A_CPU0_SA_DQS_DN<4>  DDR0_SA_DQS_DN4  @S9S_MB_2U_LIB.S9S_MB_2U(SCH_1):M_A_CPU0_SA_DQS_DN<4>
  A64  M_A_CPU0_SA_DQS_DN<3>  DDR0_SA_DQS_DN3  @S9S_MB_2U_LIB.S9S_MB_2U(SCH_1):M_A_CPU0_SA_DQS_DN<3>
  B71  M_A_CPU0_SA_DQS_DN<2>  DDR0_SA_DQS_DN2  @S9S_MB_2U_LIB.S9S_MB_2U(SCH_1):M_A_CPU0_SA_DQS_DN<2>
  H67  M_A_CPU0_SA_DQS_DN<1>  DDR0_SA_DQS_DN1  @S9S_MB_2U_LIB.S9S_MB_2U(SCH_1):M_A_CPU0_SA_DQS_DN<1>
  B77  M_A_CPU0_SA_DQS_DN<0>  DDR0_SA_DQS_DN0  @S9S_MB_2U_LIB.S9S_MB_2U(SCH_1):M_A_CPU0_SA_DQS_DN<0>
  J68  M_A_CPU0_SA_DQ<9>  DDR0_SA_DQ9  @S9S_MB_2U_LIB.S9S_MB_2U(SCH_1):M_A_CPU0_SA_DQ<9>
  K69  M_A_CPU0_SA_DQ<8>  DDR0_SA_DQ8  @S9S_MB_2U_LIB.S9S_MB_2U(SCH_1):M_A_CPU0_SA_DQ<8>
  F75  M_A_CPU0_SA_DQ<7>  DDR0_SA_DQ7  @S9S_MB_2U_LIB.S9S_MB_2U(SCH_1):M_A_CPU0_SA_DQ<7>
  G76  M_A_CPU0_SA_DQ<6>  DDR0_SA_DQ6  @S9S_MB_2U_LIB.S9S_MB_2U(SCH_1):M_A_CPU0_SA_DQ<6>
  D75  M_A_CPU0_SA_DQ<5>  DDR0_SA_DQ5  @S9S_MB_2U_LIB.S9S_MB_2U(SCH_1):M_A_CPU0_SA_DQ<5>
  C76  M_A_CPU0_SA_DQ<4>  DDR0_SA_DQ4  @S9S_MB_2U_LIB.S9S_MB_2U(SCH_1):M_A_CPU0_SA_DQ<4>
  G78  M_A_CPU0_SA_DQ<3>  DDR0_SA_DQ3  @S9S_MB_2U_LIB.S9S_MB_2U(SCH_1):M_A_CPU0_SA_DQ<3>
  E62  M_A_CPU0_SA_DQ<31>  DDR0_SA_DQ31  @S9S_MB_2U_LIB.S9S_MB_2U(SCH_1):M_A_CPU0_SA_DQ<31>
  F63  M_A_CPU0_SA_DQ<30>  DDR0_SA_DQ30  @S9S_MB_2U_LIB.S9S_MB_2U(SCH_1):M_A_CPU0_SA_DQ<30>
  M77  M_A_CPU0_SA_DQ<2>  DDR0_SA_DQ2  @S9S_MB_2U_LIB.S9S_MB_2U(SCH_1):M_A_CPU0_SA_DQ<2>
  C62  M_A_CPU0_SA_DQ<29>  DDR0_SA_DQ29  @S9S_MB_2U_LIB.S9S_MB_2U(SCH_1):M_A_CPU0_SA_DQ<29>
  B63  M_A_CPU0_SA_DQ<28>  DDR0_SA_DQ28  @S9S_MB_2U_LIB.S9S_MB_2U(SCH_1):M_A_CPU0_SA_DQ<28>
  F65  M_A_CPU0_SA_DQ<27>  DDR0_SA_DQ27  @S9S_MB_2U_LIB.S9S_MB_2U(SCH_1):M_A_CPU0_SA_DQ<27>
  E66  M_A_CPU0_SA_DQ<26>  DDR0_SA_DQ26  @S9S_MB_2U_LIB.S9S_MB_2U(SCH_1):M_A_CPU0_SA_DQ<26>
  B65  M_A_CPU0_SA_DQ<25>  DDR0_SA_DQ25  @S9S_MB_2U_LIB.S9S_MB_2U(SCH_1):M_A_CPU0_SA_DQ<25>
  C66  M_A_CPU0_SA_DQ<24>  DDR0_SA_DQ24  @S9S_MB_2U_LIB.S9S_MB_2U(SCH_1):M_A_CPU0_SA_DQ<24>
  E68  M_A_CPU0_SA_DQ<23>  DDR0_SA_DQ23  @S9S_MB_2U_LIB.S9S_MB_2U(SCH_1):M_A_CPU0_SA_DQ<23>
  F69  M_A_CPU0_SA_DQ<22>  DDR0_SA_DQ22  @S9S_MB_2U_LIB.S9S_MB_2U(SCH_1):M_A_CPU0_SA_DQ<22>
  C68  M_A_CPU0_SA_DQ<21>  DDR0_SA_DQ21  @S9S_MB_2U_LIB.S9S_MB_2U(SCH_1):M_A_CPU0_SA_DQ<21>
  B69  M_A_CPU0_SA_DQ<20>  DDR0_SA_DQ20  @S9S_MB_2U_LIB.S9S_MB_2U(SCH_1):M_A_CPU0_SA_DQ<20>
  B79  M_A_CPU0_SA_DQ<1>  DDR0_SA_DQ1  @S9S_MB_2U_LIB.S9S_MB_2U(SCH_1):M_A_CPU0_SA_DQ<1>
  F71  M_A_CPU0_SA_DQ<19>  DDR0_SA_DQ19  @S9S_MB_2U_LIB.S9S_MB_2U(SCH_1):M_A_CPU0_SA_DQ<19>
  D73  M_A_CPU0_SA_DQ<18>  DDR0_SA_DQ18  @S9S_MB_2U_LIB.S9S_MB_2U(SCH_1):M_A_CPU0_SA_DQ<18>
  E72  M_A_CPU0_SA_DQ<17>  DDR0_SA_DQ17  @S9S_MB_2U_LIB.S9S_MB_2U(SCH_1):M_A_CPU0_SA_DQ<17>
  B73  M_A_CPU0_SA_DQ<16>  DDR0_SA_DQ16  @S9S_MB_2U_LIB.S9S_MB_2U(SCH_1):M_A_CPU0_SA_DQ<16>
  M65  M_A_CPU0_SA_DQ<15>  DDR0_SA_DQ15  @S9S_MB_2U_LIB.S9S_MB_2U(SCH_1):M_A_CPU0_SA_DQ<15>
  N66  M_A_CPU0_SA_DQ<14>  DDR0_SA_DQ14  @S9S_MB_2U_LIB.S9S_MB_2U(SCH_1):M_A_CPU0_SA_DQ<14>
  K65  M_A_CPU0_SA_DQ<13>  DDR0_SA_DQ13  @S9S_MB_2U_LIB.S9S_MB_2U(SCH_1):M_A_CPU0_SA_DQ<13>
  J66  M_A_CPU0_SA_DQ<12>  DDR0_SA_DQ12  @S9S_MB_2U_LIB.S9S_MB_2U(SCH_1):M_A_CPU0_SA_DQ<12>
  N68  M_A_CPU0_SA_DQ<11>  DDR0_SA_DQ11  @S9S_MB_2U_LIB.S9S_MB_2U(SCH_1):M_A_CPU0_SA_DQ<11>
  M69  M_A_CPU0_SA_DQ<10>  DDR0_SA_DQ10  @S9S_MB_2U_LIB.S9S_MB_2U(SCH_1):M_A_CPU0_SA_DQ<10>
  B81  M_A_CPU0_SA_DQ<0>  DDR0_SA_DQ0  @S9S_MB_2U_LIB.S9S_MB_2U(SCH_1):M_A_CPU0_SA_DQ<0>
  F53  M_A_CPU0_SA_CS_N<3>  DDR0_SA_CS3_N  @S9S_MB_2U_LIB.S9S_MB_2U(SCH_1):M_A_CPU0_SA_CS_N<3>
  E54  M_A_CPU0_SA_CS_N<2>  DDR0_SA_CS2_N  @S9S_MB_2U_LIB.S9S_MB_2U(SCH_1):M_A_CPU0_SA_CS_N<2>
  B53  M_A_CPU0_SA_CS_N<1>  DDR0_SA_CS1_N  @S9S_MB_2U_LIB.S9S_MB_2U(SCH_1):M_A_CPU0_SA_CS_N<1>
  C54  M_A_CPU0_SA_CS_N<0>  DDR0_SA_CS0_N  @S9S_MB_2U_LIB.S9S_MB_2U(SCH_1):M_A_CPU0_SA_CS_N<0>
  E56  M_A_CPU0_SA_CB<7>  DDR0_SA_ECC7  @S9S_MB_2U_LIB.S9S_MB_2U(SCH_1):M_A_CPU0_SA_CB<7>
  F57  M_A_CPU0_SA_CB<6>  DDR0_SA_ECC6  @S9S_MB_2U_LIB.S9S_MB_2U(SCH_1):M_A_CPU0_SA_CB<6>
  C56  M_A_CPU0_SA_CB<5>  DDR0_SA_ECC5  @S9S_MB_2U_LIB.S9S_MB_2U(SCH_1):M_A_CPU0_SA_CB<5>
  B57  M_A_CPU0_SA_CB<4>  DDR0_SA_ECC4  @S9S_MB_2U_LIB.S9S_MB_2U(SCH_1):M_A_CPU0_SA_CB<4>
  F59  M_A_CPU0_SA_CB<3>  DDR0_SA_ECC3  @S9S_MB_2U_LIB.S9S_MB_2U(SCH_1):M_A_CPU0_SA_CB<3>
  E60  M_A_CPU0_SA_CB<2>  DDR0_SA_ECC2  @S9S_MB_2U_LIB.S9S_MB_2U(SCH_1):M_A_CPU0_SA_CB<2>
  B59  M_A_CPU0_SA_CB<1>  DDR0_SA_ECC1  @S9S_MB_2U_LIB.S9S_MB_2U(SCH_1):M_A_CPU0_SA_CB<1>
  C60  M_A_CPU0_SA_CB<0>  DDR0_SA_ECC0  @S9S_MB_2U_LIB.S9S_MB_2U(SCH_1):M_A_CPU0_SA_CB<0>
  C48  M_A_CPU0_SA_CA<6>  DDR0_SA_CA6  @S9S_MB_2U_LIB.S9S_MB_2U(SCH_1):M_A_CPU0_SA_CA<6>
  E50  M_A_CPU0_SA_CA<5>  DDR0_SA_CA5  @S9S_MB_2U_LIB.S9S_MB_2U(SCH_1):M_A_CPU0_SA_CA<5>
  C50  M_A_CPU0_SA_CA<4>  DDR0_SA_CA4  @S9S_MB_2U_LIB.S9S_MB_2U(SCH_1):M_A_CPU0_SA_CA<4>
  F51  M_A_CPU0_SA_CA<3>  DDR0_SA_CA3  @S9S_MB_2U_LIB.S9S_MB_2U(SCH_1):M_A_CPU0_SA_CA<3>
  B51  M_A_CPU0_SA_CA<2>  DDR0_SA_CA2  @S9S_MB_2U_LIB.S9S_MB_2U(SCH_1):M_A_CPU0_SA_CA<2>
  G52  M_A_CPU0_SA_CA<1>  DDR0_SA_CA1  @S9S_MB_2U_LIB.S9S_MB_2U(SCH_1):M_A_CPU0_SA_CA<1>
  A52  M_A_CPU0_SA_CA<0>  DDR0_SA_CA0  @S9S_MB_2U_LIB.S9S_MB_2U(SCH_1):M_A_CPU0_SA_CA<0>
  E45  M_A_CPU0_CLK_DP<1>  DDR0_CLK_DP1  @S9S_MB_2U_LIB.S9S_MB_2U(SCH_1):M_A_CPU0_CLK_DP<1>
  C43  M_A_CPU0_CLK_DP<0>  DDR0_CLK_DP0  @S9S_MB_2U_LIB.S9S_MB_2U(SCH_1):M_A_CPU0_CLK_DP<0>
  G45  M_A_CPU0_CLK_DN<1>  DDR0_CLK_DN1  @S9S_MB_2U_LIB.S9S_MB_2U(SCH_1):M_A_CPU0_CLK_DN<1>
  B44  M_A_CPU0_CLK_DN<0>  DDR0_CLK_DN0  @S9S_MB_2U_LIB.S9S_MB_2U(SCH_1):M_A_CPU0_CLK_DN<0>
  AT49  M_A_CPU0_ALERT_N  DDR0_ALERT_N  @S9S_MB_2U_LIB.S9S_MB_2U(SCH_1):M_A_CPU0_ALERT_N

SOCKET4677_AZIFS054P001C01  I1   U2     [SOCKET4677_AZIFS054P001C01-SOCA]
  CD28  NC             PTI_DIE001  NC
  BT28  NC             PTI_DIE009  NC
  BU27  NC             PTI_DIE008  NC
  BV28  NC             PTI_DIE007  NC
  CA27  NC             PTI_DIE006  NC
  BV30  NC             PTI_DIE005  NC
  CA29  NC             PTI_DIE004  NC
  BY30  NC             PTI_DIE003  NC
  BN66  NC             PTI_DIE0115  NC
  BM67  NC             PTI_DIE0114  NC
  CC27  NC             PTI_DIE002  NC
  BL66  NC             PTI_DIE0113  NC
  BJ66  NC             PTI_DIE0112  NC
  BG66  NC             PTI_DIE0111  NC
  BN68  NC             PTI_DIE0110  NC
  BM69  NC             PTI_DIE019  NC
  BK69  NC             PTI_DIE018  NC
  BD67  NC             PTI_DIE017  NC
  BG68  NC             PTI_DIE016  NC
  BC68  NC             PTI_DIE015  NC
  BH69  NC             PTI_DIE014  NC
  BF69  NC             PTI_DIE013  NC
  BD69  NC             PTI_DIE012  NC
  BE70  NC             PTI_DIE011  NC
  BC70  NC             PTI_DIE010  NC
  BP30  NC             PTI_DIE0015  NC
  BN29  NC             PTI_DIE0014  NC
  BP28  NC             PTI_DIE0013  NC
  BN27  NC             PTI_DIE0012  NC
  BT30  NC             PTI_DIE0011  NC
  BU29  NC             PTI_DIE0010  NC
  BK67  NC             PTI_DIE01_STB_1  NC
  BF67  NC             PTI_DIE01_STB_0  NC
  BY28  NC             PTI_DIE00_STB_1  NC
  CB30  NC             PTI_DIE00_STB_0  NC
  CC29  NC             PTI_DIE000  NC
  CK71  PU_CPU0_UPI3_AC_COUPLING  UPI3_AC_COUPLING  @S9S_MB_2U_LIB.S9S_MB_2U(SCH_1):PU_CPU0_UPI3_AC_COUPLING
  BB65  PU_CPU0_UPI2_AC_COUPLING  UPI2_AC_COUPLING  @S9S_MB_2U_LIB.S9S_MB_2U(SCH_1):PU_CPU0_UPI2_AC_COUPLING
  CW19  PU_CPU0_UPI1_AC_COUPLING  UPI1_AC_COUPLING  @S9S_MB_2U_LIB.S9S_MB_2U(SCH_1):PU_CPU0_UPI1_AC_COUPLING
  BA23  PU_CPU0_UPI0_AC_COUPLING  UPI0_AC_COUPLING  @S9S_MB_2U_LIB.S9S_MB_2U(SCH_1):PU_CPU0_UPI0_AC_COUPLING
  CR68  NC             UPI3_APROBE_1  NC
  CP69  NC             UPI3_APROBE_0  NC
  AT67  NC             UPI2_APROBE_1  NC
  AU68  NC             UPI2_APROBE_0  NC
  CA23  NC             UPI1_APROBE_1  NC
  BV22  NC             UPI1_APROBE_0  NC
  AR17  NC             UPI0_APROBE_1  NC
  AN17  NC             UPI0_APROBE_0  NC
  AU66  NC             PE4_APROBE_1  NC
  AV67  NC             PE4_APROBE_0  NC
  CM69  NC             PE3_APROBE_1  NC
  CL68  NC             PE3_APROBE_0  NC
  BW23  NC             PE2_APROBE_1  NC
  CC23  NC             PE2_APROBE_0  NC
  CC21  NC             PE1_APROBE_1  NC
  CE21  NC             PE1_APROBE_0  NC
  BL21  NC             PE0_APROBE_1  NC
  BN21  NC             PE0_APROBE_0  NC
  BW21  NC             DMI_APROBE_1  NC
  CA21  NC             DMI_APROBE_0  NC

SOCKET4677_AZIFS054P001C01  I1   U2     [SOCKET4677_AZIFS054P001C01-SOCA]
  CH61  NC             OVERCLK_BCLK0_DP  NC
  CK61  NC             OVERCLK_BCLK1_DN  NC
  CL60  NC             OVERCLK_BCLK1_DP  NC
  CW43  NC             SPARE_3  NC
  AU52  NC             SPARE_1  NC
  DA70  NC             SPARE_0  NC
  BD77  NC             SPARE_10  NC
  CL70  NC             SPARE_5  NC
  CD69  NC             OVERCLK_ENABLE  NC
  CG60  NC             OVERCLK_BCLK0_DN  NC
  J13  NC             SMBALERT_N  NC

SOCKET4677_AZIFS054P001C01  I1   U2     [SOCKET4677_AZIFS054P001C01-SOCA]
  BE21  NC             DIE_HVM  NC
  CY57  NC             SOC_SPARE1_DIE11  NC
  CR25  NC             SOC_SPARE1_DIE10  NC
  CW58  NC             SOC_SPARE0_DIE11  NC
  CT26  NC             SOC_SPARE0_DIE10  NC
  BP65  NC             SOC_SPARE1_DIE01  NC
  BA25  NC             SOC_SPARE1_DIE00  NC
  BM65  NC             SOC_SPARE0_DIE01  NC
  AY24  NC             SOC_SPARE0_DIE00  NC
  CK67  NC             MDFI_VIEW_DIE11_NS_1  NC
  CJ68  NC             MDFI_VIEW_DIE11_NS_0  NC
  CH69  NC             MDFI_VIEW_DIE11_EW_1  NC
  CJ70  NC             MDFI_VIEW_DIE11_EW_0  NC
  CD22  NC             MDFI_VIEW_DIE10_NS_1  NC
  CF22  NC             MDFI_VIEW_DIE10_NS_0  NC
  CD30  NC             MDFI_VIEW_DIE10_EW_1  NC
  CD26  NC             MDFI_VIEW_DIE10_EW_0  NC
  BD71  NC             MDFI_VIEW_DIE01_NS_1  NC
  BF71  NC             MDFI_VIEW_DIE01_NS_0  NC
  CC66  NC             MDFI_VIEW_DIE01_EW_1  NC
  AV65  NC             MDFI_VIEW_DIE01_EW_0  NC
  BJ21  NC             MDFI_VIEW_DIE00_NS_1  NC
  BK22  NC             MDFI_VIEW_DIE00_NS_0  NC
  BR21  NC             MDFI_VIEW_DIE00_EW_1  NC
  BP22  NC             MDFI_VIEW_DIE00_EW_0  NC
  BL60  NC             HBM3_VIEWPIN_1  NC
  BG78  NC             HBM3_VIEWPIN_0  NC
  AD77  NC             HBM2_VIEWPIN_1  NC
  AC78  NC             HBM2_VIEWPIN_0  NC
  CW41  NC             HBM1_VIEWPIN_1  NC
  W17  NC             HBM1_VIEWPIN_0  NC
  EG17  NC             HBM0_VIEWPIN_1  NC
  U17  NC             HBM0_VIEWPIN_0  NC

SOCKET4677_AZIFS054P001C01  I1   U2     [SOCKET4677_AZIFS054P001C01-SOCA]
  BD87  VSENSE_PVCCIN_CPU0_DP  VCCIN_SENSE  @S9S_MB_2U_LIB.S9S_MB_2U(SCH_1):VSENSE_PVCCIN_CPU0_DP
  BC90  VSENSE_PVCCIN_CPU0_DN  VSS_VCCIN_SENSE  @S9S_MB_2U_LIB.S9S_MB_2U(SCH_1):VSENSE_PVCCIN_CPU0_DN
  CA11  VSENSE_PVCCINFAON_CPU0_DP  VCCINFAON_SENSE  @S9S_MB_2U_LIB.S9S_MB_2U(SCH_1):VSENSE_PVCCINFAON_CPU0_DP
  CE11  VSENSE_PVCCINFAON_CPU0_DN  VSS_VCCINFAON_SENSE  @S9S_MB_2U_LIB.S9S_MB_2U(SCH_1):VSENSE_PVCCINFAON_CPU0_DN
  AY85  VSENSE_PVCCFA_EHV_FIVRA_CPU0_DP  VCCFA_EHV_FIVRA_SENSE  @S9S_MB_2U_LIB.S9S_MB_2U(SCH_1):VSENSE_PVCCFA_EHV_FIVRA_CPU0_DP
  AT85  VSENSE_PVCCFA_EHV_FIVRA_CPU0_DN  VSS_VCCFA_EHV_FIVRA_SENSE  @S9S_MB_2U_LIB.S9S_MB_2U(SCH_1):VSENSE_PVCCFA_EHV_FIVRA_CPU0_DN
  AU11  VSENSE_PVCCFA_EHV_CPU0_DP  VCCFA_EHV_SENSE  @S9S_MB_2U_LIB.S9S_MB_2U(SCH_1):VSENSE_PVCCFA_EHV_CPU0_DP
  BA11  VSENSE_PVCCFA_EHV_CPU0_DN  VSS_VCCFA_EHV_SENSE  @S9S_MB_2U_LIB.S9S_MB_2U(SCH_1):VSENSE_PVCCFA_EHV_CPU0_DN
  BU11  VSENSE_PVCCD_HV_CPU0_DP  VCCD_HV_SENSE  @S9S_MB_2U_LIB.S9S_MB_2U(SCH_1):VSENSE_PVCCD_HV_CPU0_DP
  BN11  VSENSE_PVCCD_HV_CPU0_DN  VSS_VCCD_HV_SENSE  @S9S_MB_2U_LIB.S9S_MB_2U(SCH_1):VSENSE_PVCCD_HV_CPU0_DN
  BF24  NC             IFST_TRIG  NC
  BE23  NC             IFST_KOT  NC
  BC23  NC             IFST_DONE  NC
  H12  NC             A0_DEBUG  NC
  AV38  NC             MAS_THERMADC  NC
  AV40  NC             MAS_THERMADA  NC
  CP61  NC             LGSPARE_5  NC
  CC64  NC             LGSPARE_4  NC
  CE62  NC             LGSPARE_3  NC
  CU62  NC             LGSPARE_2  NC
  CN60  NC             LGSPARE_1  NC
  CR60  NC             LGSPARE_0  NC
  CY49  NC             DDR67_VIEWDIG_1  NC
  DA45  NC             DDR67_VIEWDIG_0  NC
  CY38  NC             DDR45_VIEWDIG_1  NC
  CY24  NC             DDR45_VIEWDIG_0  NC
  AU33  NC             DDR23_VIEWDIG_1  NC
  AV32  NC             DDR23_VIEWDIG_0  NC
  AU56  NC             DDR01_VIEWDIG_1  NC
  AU58  NC             DDR01_VIEWDIG_0  NC
  BD24  H_PMAX_TRIGGER_IO_CPU0  PMAX_TRIGGER_IO  @S9S_MB_2U_LIB.S9S_MB_2U(SCH_1):H_PMAX_TRIGGER_IO_CPU0
  BH22  H_CPU0_RMCA_LVC1_R_N  RMCA_N  @S9S_MB_2U_LIB.S9S_MB_2U(SCH_1):H_CPU0_RMCA_LVC1_R_N
  BN25  DBP_CPU0_MBP1_GTL_R_N  MBP1_N  @S9S_MB_2U_LIB.S9S_MB_2U(SCH_1):DBP_CPU0_MBP1_GTL_R_N
  BL23  DBP_CPU0_MBP0_GTL_R_N  MBP0_N  @S9S_MB_2U_LIB.S9S_MB_2U(SCH_1):DBP_CPU0_MBP0_GTL_R_N
  BK24  DBP_CPU0_HOOK9_MBP3_GTL_QS_R_N  MBP3_N  @S9S_MB_2U_LIB.S9S_MB_2U(SCH_1):DBP_CPU0_HOOK9_MBP3_GTL_QS_R_N
  BJ23  DBP_CPU0_HOOK8_MBP2_GTL_QS_R_N  MBP2_N  @S9S_MB_2U_LIB.S9S_MB_2U(SCH_1):DBP_CPU0_HOOK8_MBP2_GTL_QS_R_N

SOCKET4677_AZIFS054P001C01  I1   U2     [SOCKET4677_AZIFS054P001C01-SOCA]
  BA68  NC             SPI_OE_N  NC
  BD61  NC             SPI_IO_3  NC
  BD65  NC             SPI_IO_2  NC
  AW64  NC             SPI_MISO_IO1  NC
  BA62  NC             SPI_MOSI_IO0  NC
  AV63  NC             SPI_CS1_N  NC
  BB61  NC             SPI_CS0_N  NC
  BC64  NC             SPI_CLK  NC
  BB67  NC             SPI_TPM_OE_N  NC
  AY61  NC             SPI_TPM_MISO_IO1  NC
  BA66  NC             SPI_TPM_MOSI_IO0  NC
  AY67  NC             SPI_TPM_CS0_N  NC
  AU62  NC             SPI_TPM_CLK  NC
  CD65  NC             GSXRESET_N  NC
  CF65  NC             GSXDOUT  NC
  CJ66  NC             GSXDLOAD  NC
  CH63  NC             GSXDIN  NC
  CF63  NC             GSXSCLK  NC
  BG64  NC             ESPI_RESET_N  NC
  CW21  NC             PLT_SLP_S5_N  NC
  CN21  NC             PLT_SLP_S4_N  NC
  CR21  NC             PLT_SLP_S3_N  NC
  CJ21  NC             PLT_GLB_RST_WARN_N  NC
  BC25  NC             I3C_MNG_SDA  NC
  BE25  NC             I3C_MNG_SCL  NC
  CJ23  NC             I2C_RTC_SDA  NC
  CL23  NC             I2C_RTC_SCL  NC
  CJ25  NC             I2C_RTC_ALERT_N  NC
  AW19  NC             PLT_WAKE_N  NC
  CK22  NC             PLT_SYS_RESET_N  NC
  CT24  NC             ADR_TRIGGER  NC
  CP24  NC             ADR_COMPLETE  NC
  CN23  NC             ADR_ACK  NC
  BH63  NC             ESPI_OE_N  NC
  BM63  NC             ESPI_IO_3  NC
  AU64  NC             ESPI_IO_2  NC
  BJ64  NC             ESPI_IO_1  NC
  BK63  NC             ESPI_IO_0  NC
  BH65  NC             ESPI_CS1_N  NC
  BF65  NC             ESPI_CS0_N  NC
  BD63  NC             ESPI_ALERT1_N  NC
  BE62  NC             ESPI_ALERT0_N  NC
  CL66  NC             SSC_SYNC  NC
  CK24  NC             PLT_PWRBUTTON_N  NC
  BG62  NC             ESPI_CLK  NC
  CD63  SMB_S3M_CPU0_SDA  SMB_DATA  @S9S_MB_2U_LIB.S9S_MB_2U(SCH_1):SMB_S3M_CPU0_SDA
  CE64  SMB_S3M_CPU0_SCL  SMB_CLK  @S9S_MB_2U_LIB.S9S_MB_2U(SCH_1):SMB_S3M_CPU0_SCL
  CH71  PWRGD_S0_PWROK_CPU0_LVC1  S0_PWROK  @S9S_MB_2U_LIB.S9S_MB_2U(SCH_1):PWRGD_S0_PWROK_CPU0_LVC1
  CV20  PWRGD_PLT_AUX_CPU0_LVT3  PLT_AUX_PWRGOOD  @S9S_MB_2U_LIB.S9S_MB_2U(SCH_1):PWRGD_PLT_AUX_CPU0_LVT3
  CH65  PU_S3M_CPU0_CPLD_STATUS  CPLD_NSTATUS  @S9S_MB_2U_LIB.S9S_MB_2U(SCH_1):PU_S3M_CPU0_CPLD_STATUS
  CJ64  PU_S3M_CPU0_CPLD_CONFD  CPLD_CONF_DONE  @S9S_MB_2U_LIB.S9S_MB_2U(SCH_1):PU_S3M_CPU0_CPLD_CONFD
  CF61  PUD_PCH_BOOT_MODE_CPU0  PCH_BOOT_MODE  @S9S_MB_2U_LIB.S9S_MB_2U(SCH_1):PUD_PCH_BOOT_MODE_CPU0
  CV69  NC             UART_RXD  NC
  CY69  NC             UART_TXD  NC
  CY71  NC             UART_RTS  NC
  CV71  NC             UART_CTS  NC
  CV22  JTAG_CPU0_PLD_TMS  CPLD_TMS  @S9S_MB_2U_LIB.S9S_MB_2U(SCH_1):JTAG_CPU0_PLD_TMS
  CP22  JTAG_CPU0_PLD_TDO  CPLD_TDO  @S9S_MB_2U_LIB.S9S_MB_2U(SCH_1):JTAG_CPU0_PLD_TDO
  CT22  JTAG_CPU0_PLD_TDI  CPLD_TDI  @S9S_MB_2U_LIB.S9S_MB_2U(SCH_1):JTAG_CPU0_PLD_TDI
  CY22  JTAG_CPU0_PLD_TCK  CPLD_TCK  @S9S_MB_2U_LIB.S9S_MB_2U(SCH_1):JTAG_CPU0_PLD_TCK
  AW70  FM_S3M_CPU0_LVC1_GPIO_4  GPIO_4  @S9S_MB_2U_LIB.S9S_MB_2U(SCH_1):FM_S3M_CPU0_LVC1_GPIO_4
  AY69  FM_S3M_CPU0_LVC1_GPIO_3  GPIO_3  @S9S_MB_2U_LIB.S9S_MB_2U(SCH_1):FM_S3M_CPU0_LVC1_GPIO_3
  AV69  FM_S3M_CPU0_LVC1_GPIO_2  GPIO_2  @S9S_MB_2U_LIB.S9S_MB_2U(SCH_1):FM_S3M_CPU0_LVC1_GPIO_2
  AV71  FM_S3M_CPU0_LVC1_GPIO_1  GPIO_1  @S9S_MB_2U_LIB.S9S_MB_2U(SCH_1):FM_S3M_CPU0_LVC1_GPIO_1
  BA70  FM_S3M_CPU0_LVC1_GPIO_0  GPIO_0  @S9S_MB_2U_LIB.S9S_MB_2U(SCH_1):FM_S3M_CPU0_LVC1_GPIO_0
  CY20  FM_S3M_CPU0_CPLD_CRC_ERROR  CPLD_CRC_ERROR  @S9S_MB_2U_LIB.S9S_MB_2U(SCH_1):FM_S3M_CPU0_CPLD_CRC_ERROR
  CK65  FM_S3M_CPU0_CPLD_CONFIG_N  CPLD_NCONFIG  @S9S_MB_2U_LIB.S9S_MB_2U(SCH_1):FM_S3M_CPU0_CPLD_CONFIG_N

SOCKET4677_AZIFS054P001C01  I1   U2     [SOCKET4677_AZIFS054P001C01-SOCA]
  CL21  NC             PLT_PLTRST_SYNC_N  NC
  CF24  NC             PMSYNC6  NC
  CC25  NC             PMDOWN6  NC
  CH24  NC             PMSYNC5  NC
  CE23  NC             PMDOWN5  NC
  CR19  NC             PMSYNC4  NC
  CV18  NC             PMDOWN4  NC
  CE25  NC             PMSYNC3  NC
  CD24  NC             PMDOWN3  NC
  CH26  NC             PMSYNC2  NC
  CM26  NC             PMDOWN2  NC
  CL25  NC             PMSYNC1  NC
  CP26  NC             PMDOWN1  NC
  AV59  NC             MAS_EXT_BGREF  NC
  BL25  SVID_DIO1_CPU0  SVIDDATA1  @S9S_MB_2U_LIB.S9S_MB_2U(SCH_1):SVID_DIO1_CPU0
  BD26  SVID_DIO0_CPU0  SVIDDATA0  @S9S_MB_2U_LIB.S9S_MB_2U(SCH_1):SVID_DIO0_CPU0
  BF26  SVID_CLK1_CPU0  SVIDCLK1  @S9S_MB_2U_LIB.S9S_MB_2U(SCH_1):SVID_CLK1_CPU0
  BH26  SVID_CLK0_CPU0  SVIDCLK0  @S9S_MB_2U_LIB.S9S_MB_2U(SCH_1):SVID_CLK0_CPU0
  BJ25  SVID_ALERT1_CPU0_N  SVIDALERT1_N  @S9S_MB_2U_LIB.S9S_MB_2U(SCH_1):SVID_ALERT1_CPU0_N
  BK26  SVID_ALERT0_CPU0_N  SVIDALERT0_N  @S9S_MB_2U_LIB.S9S_MB_2U(SCH_1):SVID_ALERT0_CPU0_N
  BY26  SMB_PEHPCPU0_GTL_SDA  CXPSMBUSSDA  @S9S_MB_2U_LIB.S9S_MB_2U(SCH_1):SMB_PEHPCPU0_GTL_SDA
  CA25  SMB_PEHPCPU0_GTL_SCL  CXPSMBUSSCL  @S9S_MB_2U_LIB.S9S_MB_2U(SCH_1):SMB_PEHPCPU0_GTL_SCL
  CM71  SMB_CPU0_PIROM_3V3AUX_SDA_R  I2C_PIROM_SDA  @S9S_MB_2U_LIB.S9S_MB_2U(SCH_1):SMB_CPU0_PIROM_3V3AUX_SDA_R
  CU70  SMB_CPU0_PIROM_3V3AUX_SCL_R  I2C_PIROM_SCL  @S9S_MB_2U_LIB.S9S_MB_2U(SCH_1):SMB_CPU0_PIROM_3V3AUX_SCL_R
  BH61  RST_CPU0_LVC1_N  RESET_N  @S9S_MB_2U_LIB.S9S_MB_2U(SCH_1):RST_CPU0_LVC1_N
  CW45  PWRGD_DRAMPWRGD_CPU0_GH_LVC1_R  DDR67_DRAM_PWR_OK  @S9S_MB_2U_LIB.S9S_MB_2U(SCH_1):PWRGD_DRAMPWRGD_CPU0_GH_LVC1_R
  CY44  PWRGD_DRAMPWRGD_CPU0_EF_LVC1_R  DDR45_DRAM_PWR_OK  @S9S_MB_2U_LIB.S9S_MB_2U(SCH_1):PWRGD_DRAMPWRGD_CPU0_EF_LVC1_R
  F47  PWRGD_DRAMPWRGD_CPU0_CD_LVC1_R  DDR23_DRAM_PWR_OK  @S9S_MB_2U_LIB.S9S_MB_2U(SCH_1):PWRGD_DRAMPWRGD_CPU0_CD_LVC1_R
  A43  PWRGD_DRAMPWRGD_CPU0_AB_LVC1_R  DDR01_DRAM_PWR_OK  @S9S_MB_2U_LIB.S9S_MB_2U(SCH_1):PWRGD_DRAMPWRGD_CPU0_AB_LVC1_R
  AV20  PWRGD_CPU0_LVC1  CPUPWRGOOD  @S9S_MB_2U_LIB.S9S_MB_2U(SCH_1):PWRGD_CPU0_LVC1
  AY20  PU_TAP_ODT_CPU0_EN  TAP_ODT_EN  @S9S_MB_2U_LIB.S9S_MB_2U(SCH_1):PU_TAP_ODT_CPU0_EN
  CR72  PU_PIROM_CPU0_SM_WP  I2C_PIROM_SM_WP  @S9S_MB_2U_LIB.S9S_MB_2U(SCH_1):PU_PIROM_CPU0_SM_WP
  CP71  PD_PIROM_CPU0_ADDR2  I2C_PIROM_AD_2  @S9S_MB_2U_LIB.S9S_MB_2U(SCH_1):PD_PIROM_CPU0_ADDR2
  CT71  PD_PIROM_CPU0_ADDR1  I2C_PIROM_AD_1  @S9S_MB_2U_LIB.S9S_MB_2U(SCH_1):PD_PIROM_CPU0_ADDR1
  CR70  PD_PIROM_CPU0_ADDR0  I2C_PIROM_AD_0  @S9S_MB_2U_LIB.S9S_MB_2U(SCH_1):PD_PIROM_CPU0_ADDR0
  CH22  PD_CPU0_ENH_MCECC_DIS  ENH_MCECC_DIS  @S9S_MB_2U_LIB.S9S_MB_2U(SCH_1):PD_CPU0_ENH_MCECC_DIS
  CL64  NC             VIEWPIN_DIE11_3  NC
  CM63  NC             VIEWPIN_DIE11_2  NC
  CN62  NC             VIEWPIN_DIE11_1  NC
  CJ62  NC             VIEWPIN_DIE11_0  NC
  CW23  NC             VIEWPIN_DIE10_3  NC
  CV24  NC             VIEWPIN_DIE10_2  NC
  CW25  NC             VIEWPIN_DIE10_1  NC
  CR23  NC             VIEWPIN_DIE10_0  NC
  BJ70  NC             VIEWPIN_DIE01_3  NC
  AY65  NC             VIEWPIN_DIE01_2  NC
  BP67  NC             VIEWPIN_DIE01_1  NC
  BP69  NC             VIEWPIN_DIE01_0  NC
  AV26  NC             VIEWPIN_DIE00_3  NC
  AU25  NC             VIEWPIN_DIE00_2  NC
  AT24  NC             VIEWPIN_DIE00_1  NC
  AY26  NC             VIEWPIN_DIE00_0  NC
  CW68  NC             FIVR_CLKREF  NC
  BL62  H_CPU0_THERMTRIP_LVC1_R_N  THERMTRIP_N  @S9S_MB_2U_LIB.S9S_MB_2U(SCH_1):H_CPU0_THERMTRIP_LVC1_R_N
  AU19  H_CPU0_PROCHOT_LVC1_N  PROCHOT_N  @S9S_MB_2U_LIB.S9S_MB_2U(SCH_1):H_CPU0_PROCHOT_LVC1_N
  CP20  H_CPU0_PM_FAST_WAKE_N  PMFAST_WAKE_N  @S9S_MB_2U_LIB.S9S_MB_2U(SCH_1):H_CPU0_PM_FAST_WAKE_N
  DA39  H_CPU0_PMSYNC_PCH  PMSYNC_PCH  @S9S_MB_2U_LIB.S9S_MB_2U(SCH_1):H_CPU0_PMSYNC_PCH
  CN25  H_CPU0_PMSYNC_CPU1_R  PMSYNC0  @S9S_MB_2U_LIB.S9S_MB_2U(SCH_1):H_CPU0_PMSYNC_CPU1_R
  CY40  H_CPU0_PMDOWN_PCH_R2  PMDOWN_PCH  @S9S_MB_2U_LIB.S9S_MB_2U(SCH_1):H_CPU0_PMDOWN_PCH_R2
  CW39  H_CPU0_PMDOWN_CPU1_R  PMDOWN0  @S9S_MB_2U_LIB.S9S_MB_2U(SCH_1):H_CPU0_PMDOWN_CPU1_R
  AV18  H_CPU0_NMI_LVC1_N    NMI  @S9S_MB_2U_LIB.S9S_MB_2U(SCH_1):H_CPU0_NMI_LVC1_N
  AV24  H_CPU0_MEMTRIP_LVC1_R_N  MEMTRIP_N  @S9S_MB_2U_LIB.S9S_MB_2U(SCH_1):H_CPU0_MEMTRIP_LVC1_R_N
  CF26  H_CPU0_MEMHOT_OUT_LVC1_R_N  MEMHOT_OUT_N  @S9S_MB_2U_LIB.S9S_MB_2U(SCH_1):H_CPU0_MEMHOT_OUT_LVC1_R_N
  AU21  H_CPU0_MEMHOT_IN_LVC1_N  MEMHOT_IN_N  @S9S_MB_2U_LIB.S9S_MB_2U(SCH_1):H_CPU0_MEMHOT_IN_LVC1_N
  BD22  H_CPU0_ERR2_LVC1_R_N  ERROR2_N  @S9S_MB_2U_LIB.S9S_MB_2U(SCH_1):H_CPU0_ERR2_LVC1_R_N
  AY22  H_CPU0_ERR1_LVC1_R_N  ERROR1_N  @S9S_MB_2U_LIB.S9S_MB_2U(SCH_1):H_CPU0_ERR1_LVC1_R_N
  BF22  H_CPU0_ERR0_LVC1_R_N  ERROR0_N  @S9S_MB_2U_LIB.S9S_MB_2U(SCH_1):H_CPU0_ERR0_LVC1_R_N
  BP24  H_CPU0_CATERR_LVC1_R_N  CATERR_N  @S9S_MB_2U_LIB.S9S_MB_2U(SCH_1):H_CPU0_CATERR_LVC1_R_N
  BV26  FM_PEHPCPU0_ALERT_N  CXPSMBUS_ALERT_N  @S9S_MB_2U_LIB.S9S_MB_2U(SCH_1):FM_PEHPCPU0_ALERT_N
  AV57  FM_CPU_FBRK_DEBUG_R_N  FBRK_N  @S9S_MB_2U_LIB.S9S_MB_2U(SCH_1):FM_CPU_FBRK_DEBUG_R_N
  CG66  FM_CPU0_SKTOCC_LVT3_N  SKTOCC_N  @S9S_MB_2U_LIB.S9S_MB_2U(SCH_1):FM_CPU0_SKTOCC_LVT3_N

SOCKET4677_AZIFS054P001C01  I57  U2     [SOCKET4677_AZIFS054P001C01-SOCA]
  DA52  NC             PROCDIS_N  NC
  CY55  RST_CPU0_DRAM_GH_N  DDR67_RESET_N  @S9S_MB_2U_LIB.S9S_MB_2U(SCH_1):RST_CPU0_DRAM_GH_N
  CY42  RST_CPU0_DRAM_EF_N  DDR45_RESET_N  @S9S_MB_2U_LIB.S9S_MB_2U(SCH_1):RST_CPU0_DRAM_EF_N
  AV51  RST_CPU0_DRAM_CD_N  DDR23_RESET_N  @S9S_MB_2U_LIB.S9S_MB_2U(SCH_1):RST_CPU0_DRAM_CD_N
  AU50  RST_CPU0_DRAM_AB_N  DDR01_RESET_N  @S9S_MB_2U_LIB.S9S_MB_2U(SCH_1):RST_CPU0_DRAM_AB_N
  BT26  PU_CPU0_TXT_AGENT  TXT_AGENT  @S9S_MB_2U_LIB.S9S_MB_2U(SCH_1):PU_CPU0_TXT_AGENT
  CT61  PU_CPU0_SOCKET_ID2  SOCKET_ID2  @S9S_MB_2U_LIB.S9S_MB_2U(SCH_1):PU_CPU0_SOCKET_ID2
  CY61  PU_CPU0_SOCKET_ID1  SOCKET_ID1  @S9S_MB_2U_LIB.S9S_MB_2U(SCH_1):PU_CPU0_SOCKET_ID1
  CW60  PU_CPU0_SOCKET_ID0  SOCKET_ID0  @S9S_MB_2U_LIB.S9S_MB_2U(SCH_1):PU_CPU0_SOCKET_ID0
  AU23  PU_CPU0_SAFE_MODE_BOOT  SAFE_MODE_BOOT  @S9S_MB_2U_LIB.S9S_MB_2U(SCH_1):PU_CPU0_SAFE_MODE_BOOT
  CY59  PU_CPU0_LEGACY_SKT  LEGACY_SKT  @S9S_MB_2U_LIB.S9S_MB_2U(SCH_1):PU_CPU0_LEGACY_SKT
  AU17  PU_CPU0_FRMAGENT  FRMAGENT  @S9S_MB_2U_LIB.S9S_MB_2U(SCH_1):PU_CPU0_FRMAGENT
  CJ72  PUD_XTAL_CPU0_MODE1  XTAL_MODE_1  @S9S_MB_2U_LIB.S9S_MB_2U(SCH_1):PUD_XTAL_CPU0_MODE1
  CL72  PUD_XTAL_CPU0_MODE0  XTAL_MODE_0  @S9S_MB_2U_LIB.S9S_MB_2U(SCH_1):PUD_XTAL_CPU0_MODE0
  BH24  PECI_CPU0_GTL_R   PECI  @S9S_MB_2U_LIB.S9S_MB_2U(SCH_1):PECI_CPU0_GTL_R
  BY24  PD_EXT_CLK_SEL_CPU0  EXT_CLK_SEL  @S9S_MB_2U_LIB.S9S_MB_2U(SCH_1):PD_EXT_CLK_SEL_CPU0
  CT20  PD_CPU0_TXT_PLTEN  TXT_PLTEN  @S9S_MB_2U_LIB.S9S_MB_2U(SCH_1):PD_CPU0_TXT_PLTEN
  AW17  PD_CPU0_DMIMODE_OVERRIDE  DMIMODE_OVERRIDE  @S9S_MB_2U_LIB.S9S_MB_2U(SCH_1):PD_CPU0_DMIMODE_OVERRIDE
  AT18  PD_CPU0_BIST_ENABLE  BIST_ENABLE  @S9S_MB_2U_LIB.S9S_MB_2U(SCH_1):PD_CPU0_BIST_ENABLE
   D4  NC             XTAL_OUT  NC
   G5  NC             XTAL_IN  NC
  CD71  NC             PFT_OUT_DP  NC
  CE70  NC             PFT_OUT_DN  NC
  BR25  JTAG_DBP_CPU0_QS_GTL_R_TMS    TMS  @S9S_MB_2U_LIB.S9S_MB_2U(SCH_1):JTAG_DBP_CPU0_QS_GTL_R_TMS
  BV24  JTAG_DBP_CPU0_GTL_R_TDI    TDI  @S9S_MB_2U_LIB.S9S_MB_2U(SCH_1):JTAG_DBP_CPU0_GTL_R_TDI
  BT24  JTAG_DBP_CPU0_GTL_R_TCK    TCK  @S9S_MB_2U_LIB.S9S_MB_2U(SCH_1):JTAG_DBP_CPU0_GTL_R_TCK
  BW25  JTAG_CPU0_MUX_GTL_TDO    TDO  @S9S_MB_2U_LIB.S9S_MB_2U(SCH_1):JTAG_CPU0_MUX_GTL_TDO
  CT18  I3C_SPD_DDREFGH_CPU0_SDA  SPD_I2CBUS_SDA1  @S9S_MB_2U_LIB.S9S_MB_2U(SCH_1):I3C_SPD_DDREFGH_CPU0_SDA
  CU17  I3C_SPD_DDREFGH_CPU0_SCL  SPD_I2CBUS_SCL1  @S9S_MB_2U_LIB.S9S_MB_2U(SCH_1):I3C_SPD_DDREFGH_CPU0_SCL
  BY22  I3C_SPD_DDRABCD_CPU0_SDA  SPD_I2CBUS_SDA0  @S9S_MB_2U_LIB.S9S_MB_2U(SCH_1):I3C_SPD_DDRABCD_CPU0_SDA
  BT22  I3C_SPD_DDRABCD_CPU0_SCL  SPD_I2CBUS_SCL0  @S9S_MB_2U_LIB.S9S_MB_2U(SCH_1):I3C_SPD_DDRABCD_CPU0_SCL
  AV22  H_CPU0_PREQ_QS_GTL_R_N  PREQ_N  @S9S_MB_2U_LIB.S9S_MB_2U(SCH_1):H_CPU0_PREQ_QS_GTL_R_N
  BP26  H_CPU0_PRDY_QS_GTL_R_N  PRDY_N  @S9S_MB_2U_LIB.S9S_MB_2U(SCH_1):H_CPU0_PRDY_QS_GTL_R_N
  BR23  H_CPU0_MON_FAIL_LVC1_R_N  MON_FAIL_N  @S9S_MB_2U_LIB.S9S_MB_2U(SCH_1):H_CPU0_MON_FAIL_LVC1_R_N
  BN23  H_CPU0_BMCINIT_LVC1  BMCINIT  @S9S_MB_2U_LIB.S9S_MB_2U(SCH_1):H_CPU0_BMCINIT_LVC1
  BH71  FM_CPU0_PROC_ID1  PROC_ID1  @S9S_MB_2U_LIB.S9S_MB_2U(SCH_1):FM_CPU0_PROC_ID1
  BG72  FM_CPU0_PROC_ID0  PROC_ID0  @S9S_MB_2U_LIB.S9S_MB_2U(SCH_1):FM_CPU0_PROC_ID0
  BN64  FM_CPU0_PKGID2  PKG_ID2  @S9S_MB_2U_LIB.S9S_MB_2U(SCH_1):FM_CPU0_PKGID2
  AY63  FM_CPU0_PKGID1  PKG_ID1  @S9S_MB_2U_LIB.S9S_MB_2U(SCH_1):FM_CPU0_PKGID1
  BL64  FM_CPU0_PKGID0  PKG_ID0  @S9S_MB_2U_LIB.S9S_MB_2U(SCH_1):FM_CPU0_PKGID0
  CY32  CLK_25M_NSSC_CPU0_DP  XTAL_CLK_DP  @S9S_MB_2U_LIB.S9S_MB_2U(SCH_1):CLK_25M_NSSC_CPU0_DP
  CW31  CLK_25M_NSSC_CPU0_DN  XTAL_CLK_DN  @S9S_MB_2U_LIB.S9S_MB_2U(SCH_1):CLK_25M_NSSC_CPU0_DN
  DA27  CLK_100M_DB2000_CPU0_BCLK3_DP  BCLK3_DP  @S9S_MB_2U_LIB.S9S_MB_2U(SCH_1):CLK_100M_DB2000_CPU0_BCLK3_DP
  CW27  CLK_100M_DB2000_CPU0_BCLK3_DN  BCLK3_DN  @S9S_MB_2U_LIB.S9S_MB_2U(SCH_1):CLK_100M_DB2000_CPU0_BCLK3_DN
  AV28  CLK_100M_DB2000_CPU0_BCLK2_DP  BCLK2_DP  @S9S_MB_2U_LIB.S9S_MB_2U(SCH_1):CLK_100M_DB2000_CPU0_BCLK2_DP
  AU29  CLK_100M_DB2000_CPU0_BCLK2_DN  BCLK2_DN  @S9S_MB_2U_LIB.S9S_MB_2U(SCH_1):CLK_100M_DB2000_CPU0_BCLK2_DN
  CW29  CLK_100M_DB2000_CPU0_BCLK1_DP  BCLK1_DP  @S9S_MB_2U_LIB.S9S_MB_2U(SCH_1):CLK_100M_DB2000_CPU0_BCLK1_DP
  CY28  CLK_100M_DB2000_CPU0_BCLK1_DN  BCLK1_DN  @S9S_MB_2U_LIB.S9S_MB_2U(SCH_1):CLK_100M_DB2000_CPU0_BCLK1_DN
  AV30  CLK_100M_DB2000_CPU0_BCLK0_DP  BCLK0_DP  @S9S_MB_2U_LIB.S9S_MB_2U(SCH_1):CLK_100M_DB2000_CPU0_BCLK0_DP
  AT30  CLK_100M_DB2000_CPU0_BCLK0_DN  BCLK0_DN  @S9S_MB_2U_LIB.S9S_MB_2U(SCH_1):CLK_100M_DB2000_CPU0_BCLK0_DN

EMMITSBURG_REV0P9  I9   U4     [EMMITSBURG_REV0P9-GFNOCPU04302A]
  F43  GND            VSS_F43  @S9S_MB_2U_LIB.S9S_MB_2U(SCH_1):GND
  E42  GND            VSS_E42  @S9S_MB_2U_LIB.S9S_MB_2U(SCH_1):GND
   E2  GND            VSS_E2  @S9S_MB_2U_LIB.S9S_MB_2U(SCH_1):GND
  D43  GND            VSS_D43  @S9S_MB_2U_LIB.S9S_MB_2U(SCH_1):GND
  D41  GND            VSS_D41  @S9S_MB_2U_LIB.S9S_MB_2U(SCH_1):GND
   D3  GND            VSS_D3  @S9S_MB_2U_LIB.S9S_MB_2U(SCH_1):GND
   D1  GND            VSS_D1  @S9S_MB_2U_LIB.S9S_MB_2U(SCH_1):GND
  C43  GND            VSS_C43  @S9S_MB_2U_LIB.S9S_MB_2U(SCH_1):GND
  C41  GND            VSS_C41  @S9S_MB_2U_LIB.S9S_MB_2U(SCH_1):GND
   C3  GND            VSS_C3  @S9S_MB_2U_LIB.S9S_MB_2U(SCH_1):GND
  BG41  GND            VSS_BG41  @S9S_MB_2U_LIB.S9S_MB_2U(SCH_1):GND
  BG38  GND            VSS_BG38  @S9S_MB_2U_LIB.S9S_MB_2U(SCH_1):GND
  BG6  GND            VSS_BG6  @S9S_MB_2U_LIB.S9S_MB_2U(SCH_1):GND
  BG4  GND            VSS_BG4  @S9S_MB_2U_LIB.S9S_MB_2U(SCH_1):GND
  BE43  GND            VSS_BE43  @S9S_MB_2U_LIB.S9S_MB_2U(SCH_1):GND
  BE41  GND            VSS_BE41  @S9S_MB_2U_LIB.S9S_MB_2U(SCH_1):GND
  BE3  GND            VSS_BE3  @S9S_MB_2U_LIB.S9S_MB_2U(SCH_1):GND
  BE1  GND            VSS_BE1  @S9S_MB_2U_LIB.S9S_MB_2U(SCH_1):GND
  BD43  GND            VSS_BD43  @S9S_MB_2U_LIB.S9S_MB_2U(SCH_1):GND
  BD41  GND            VSS_BD41  @S9S_MB_2U_LIB.S9S_MB_2U(SCH_1):GND
  BD3  GND            VSS_BD3  @S9S_MB_2U_LIB.S9S_MB_2U(SCH_1):GND
  BD1  GND            VSS_BD1  @S9S_MB_2U_LIB.S9S_MB_2U(SCH_1):GND
  BC42  GND            VSS_BC42  @S9S_MB_2U_LIB.S9S_MB_2U(SCH_1):GND
  BC2  GND            VSS_BC2  @S9S_MB_2U_LIB.S9S_MB_2U(SCH_1):GND
  BB1  GND            VSS_BB1  @S9S_MB_2U_LIB.S9S_MB_2U(SCH_1):GND
  AY24  GND            VSS_AY24  @S9S_MB_2U_LIB.S9S_MB_2U(SCH_1):GND
  AY21  GND            VSS_AY21  @S9S_MB_2U_LIB.S9S_MB_2U(SCH_1):GND
  AY18  GND            VSS_AY18  @S9S_MB_2U_LIB.S9S_MB_2U(SCH_1):GND
  AY15  GND            VSS_AY15  @S9S_MB_2U_LIB.S9S_MB_2U(SCH_1):GND
  AY11  GND            VSS_AY11  @S9S_MB_2U_LIB.S9S_MB_2U(SCH_1):GND
  AW7  GND            VSS_AW7  @S9S_MB_2U_LIB.S9S_MB_2U(SCH_1):GND
  AV39  GND            VSS_AV39  @S9S_MB_2U_LIB.S9S_MB_2U(SCH_1):GND
  AV37  GND            VSS_AV37  @S9S_MB_2U_LIB.S9S_MB_2U(SCH_1):GND
  AV8  GND            VSS_AV8  @S9S_MB_2U_LIB.S9S_MB_2U(SCH_1):GND
  AV5  GND            VSS_AV5  @S9S_MB_2U_LIB.S9S_MB_2U(SCH_1):GND
  AU36  GND            VSS_AU36  @S9S_MB_2U_LIB.S9S_MB_2U(SCH_1):GND
  AU32  GND            VSS_AU32  @S9S_MB_2U_LIB.S9S_MB_2U(SCH_1):GND
  AU29  GND            VSS_AU29  @S9S_MB_2U_LIB.S9S_MB_2U(SCH_1):GND
  AU26  GND            VSS_AU26  @S9S_MB_2U_LIB.S9S_MB_2U(SCH_1):GND
  AU23  GND            VSS_AU23  @S9S_MB_2U_LIB.S9S_MB_2U(SCH_1):GND
  AU20  GND            VSS_AU20  @S9S_MB_2U_LIB.S9S_MB_2U(SCH_1):GND
  AT39  GND            VSS_AT39  @S9S_MB_2U_LIB.S9S_MB_2U(SCH_1):GND
  AT34  GND            VSS_AT34  @S9S_MB_2U_LIB.S9S_MB_2U(SCH_1):GND
  AT31  GND            VSS_AT31  @S9S_MB_2U_LIB.S9S_MB_2U(SCH_1):GND
  AT28  GND            VSS_AT28  @S9S_MB_2U_LIB.S9S_MB_2U(SCH_1):GND
  AT24  GND            VSS_AT24  @S9S_MB_2U_LIB.S9S_MB_2U(SCH_1):GND
  AT21  GND            VSS_AT21  @S9S_MB_2U_LIB.S9S_MB_2U(SCH_1):GND
  AT15  GND            VSS_AT15  @S9S_MB_2U_LIB.S9S_MB_2U(SCH_1):GND
  AT11  GND            VSS_AT11  @S9S_MB_2U_LIB.S9S_MB_2U(SCH_1):GND
  AT8  GND            VSS_AT8  @S9S_MB_2U_LIB.S9S_MB_2U(SCH_1):GND
  AT5  GND            VSS_AT5  @S9S_MB_2U_LIB.S9S_MB_2U(SCH_1):GND
  AR32  GND            VSS_AR32  @S9S_MB_2U_LIB.S9S_MB_2U(SCH_1):GND
  AR20  GND            VSS_AR20  @S9S_MB_2U_LIB.S9S_MB_2U(SCH_1):GND
  AP39  GND            VSS_AP39  @S9S_MB_2U_LIB.S9S_MB_2U(SCH_1):GND
  AP37  GND            VSS_AP37  @S9S_MB_2U_LIB.S9S_MB_2U(SCH_1):GND
  AP28  GND            VSS_AP28  @S9S_MB_2U_LIB.S9S_MB_2U(SCH_1):GND
  AP24  GND            VSS_AP24  @S9S_MB_2U_LIB.S9S_MB_2U(SCH_1):GND
  AP18  GND            VSS_AP18  @S9S_MB_2U_LIB.S9S_MB_2U(SCH_1):GND
  AP11  GND            VSS_AP11  @S9S_MB_2U_LIB.S9S_MB_2U(SCH_1):GND
  AP5  GND            VSS_AP5  @S9S_MB_2U_LIB.S9S_MB_2U(SCH_1):GND
  AN32  GND            VSS_AN32  @S9S_MB_2U_LIB.S9S_MB_2U(SCH_1):GND
  AN29  GND            VSS_AN29  @S9S_MB_2U_LIB.S9S_MB_2U(SCH_1):GND
  AN16  GND            VSS_AN16  @S9S_MB_2U_LIB.S9S_MB_2U(SCH_1):GND
  AN13  GND            VSS_AN13  @S9S_MB_2U_LIB.S9S_MB_2U(SCH_1):GND
  AM31  GND            VSS_AM31  @S9S_MB_2U_LIB.S9S_MB_2U(SCH_1):GND
  AM15  GND            VSS_AM15  @S9S_MB_2U_LIB.S9S_MB_2U(SCH_1):GND
  AM8  GND            VSS_AM8  @S9S_MB_2U_LIB.S9S_MB_2U(SCH_1):GND
  AL39  GND            VSS_AL39  @S9S_MB_2U_LIB.S9S_MB_2U(SCH_1):GND
  AL29  GND            VSS_AL29  @S9S_MB_2U_LIB.S9S_MB_2U(SCH_1):GND
  AL27  GND            VSS_AL27  @S9S_MB_2U_LIB.S9S_MB_2U(SCH_1):GND
  AL24  GND            VSS_AL24  @S9S_MB_2U_LIB.S9S_MB_2U(SCH_1):GND
  AL19  GND            VSS_AL19  @S9S_MB_2U_LIB.S9S_MB_2U(SCH_1):GND
  AK37  GND            VSS_AK37  @S9S_MB_2U_LIB.S9S_MB_2U(SCH_1):GND
  AK11  GND            VSS_AK11  @S9S_MB_2U_LIB.S9S_MB_2U(SCH_1):GND
  AK4  GND            VSS_AK4  @S9S_MB_2U_LIB.S9S_MB_2U(SCH_1):GND
  AK2  GND            VSS_AK2  @S9S_MB_2U_LIB.S9S_MB_2U(SCH_1):GND
  AJ39  GND            VSS_AJ39  @S9S_MB_2U_LIB.S9S_MB_2U(SCH_1):GND
  AJ36  GND            VSS_AJ36  @S9S_MB_2U_LIB.S9S_MB_2U(SCH_1):GND
  AJ29  GND            VSS_AJ29  @S9S_MB_2U_LIB.S9S_MB_2U(SCH_1):GND
  AJ24  GND            VSS_AJ24  @S9S_MB_2U_LIB.S9S_MB_2U(SCH_1):GND
  AJ19  GND            VSS_AJ19  @S9S_MB_2U_LIB.S9S_MB_2U(SCH_1):GND
  AJ5  GND            VSS_AJ5  @S9S_MB_2U_LIB.S9S_MB_2U(SCH_1):GND
  AH31  GND            VSS_AH31  @S9S_MB_2U_LIB.S9S_MB_2U(SCH_1):GND
  AH8  GND            VSS_AH8  @S9S_MB_2U_LIB.S9S_MB_2U(SCH_1):GND
  AG39  GND            VSS_AG39  @S9S_MB_2U_LIB.S9S_MB_2U(SCH_1):GND
  AG24  GND            VSS_AG24  @S9S_MB_2U_LIB.S9S_MB_2U(SCH_1):GND
  AG19  GND            VSS_AG19  @S9S_MB_2U_LIB.S9S_MB_2U(SCH_1):GND
  AG13  GND            VSS_AG13  @S9S_MB_2U_LIB.S9S_MB_2U(SCH_1):GND
  AG5  GND            VSS_AG5  @S9S_MB_2U_LIB.S9S_MB_2U(SCH_1):GND
  AF42  GND            VSS_AF42  @S9S_MB_2U_LIB.S9S_MB_2U(SCH_1):GND
  AF40  GND            VSS_AF40  @S9S_MB_2U_LIB.S9S_MB_2U(SCH_1):GND
  AF31  GND            VSS_AF31  @S9S_MB_2U_LIB.S9S_MB_2U(SCH_1):GND
  AF24  GND            VSS_AF24  @S9S_MB_2U_LIB.S9S_MB_2U(SCH_1):GND
  AF19  GND            VSS_AF19  @S9S_MB_2U_LIB.S9S_MB_2U(SCH_1):GND
  AE39  GND            VSS_AE39  @S9S_MB_2U_LIB.S9S_MB_2U(SCH_1):GND
  AE13  GND            VSS_AE13  @S9S_MB_2U_LIB.S9S_MB_2U(SCH_1):GND
  AE5  GND            VSS_AE5  @S9S_MB_2U_LIB.S9S_MB_2U(SCH_1):GND
  AD34  GND            VSS_AD34  @S9S_MB_2U_LIB.S9S_MB_2U(SCH_1):GND
  AD31  GND            VSS_AD31  @S9S_MB_2U_LIB.S9S_MB_2U(SCH_1):GND
  AD24  GND            VSS_AD24  @S9S_MB_2U_LIB.S9S_MB_2U(SCH_1):GND
  AD22  GND            VSS_AD22  @S9S_MB_2U_LIB.S9S_MB_2U(SCH_1):GND
  AD20  GND            VSS_AD20  @S9S_MB_2U_LIB.S9S_MB_2U(SCH_1):GND
  AD19  GND            VSS_AD19  @S9S_MB_2U_LIB.S9S_MB_2U(SCH_1):GND
  AD11  GND            VSS_AD11  @S9S_MB_2U_LIB.S9S_MB_2U(SCH_1):GND
  AD8  GND            VSS_AD8  @S9S_MB_2U_LIB.S9S_MB_2U(SCH_1):GND
  AC39  GND            VSS_AC39  @S9S_MB_2U_LIB.S9S_MB_2U(SCH_1):GND
  AC36  GND            VSS_AC36  @S9S_MB_2U_LIB.S9S_MB_2U(SCH_1):GND
  AC32  GND            VSS_AC32  @S9S_MB_2U_LIB.S9S_MB_2U(SCH_1):GND
  AC29  GND            VSS_AC29  @S9S_MB_2U_LIB.S9S_MB_2U(SCH_1):GND
  AC5  GND            VSS_AC5  @S9S_MB_2U_LIB.S9S_MB_2U(SCH_1):GND
  AB37  GND            VSS_AB37  @S9S_MB_2U_LIB.S9S_MB_2U(SCH_1):GND
  AB25  GND            VSS_AB25  @S9S_MB_2U_LIB.S9S_MB_2U(SCH_1):GND
  AB17  GND            VSS_AB17  @S9S_MB_2U_LIB.S9S_MB_2U(SCH_1):GND
  AB15  GND            VSS_AB15  @S9S_MB_2U_LIB.S9S_MB_2U(SCH_1):GND
  AA39  GND            VSS_AA39  @S9S_MB_2U_LIB.S9S_MB_2U(SCH_1):GND
  AA36  GND            VSS_AA36  @S9S_MB_2U_LIB.S9S_MB_2U(SCH_1):GND
  AA32  GND            VSS_AA32  @S9S_MB_2U_LIB.S9S_MB_2U(SCH_1):GND
  AA27  GND            VSS_AA27  @S9S_MB_2U_LIB.S9S_MB_2U(SCH_1):GND
  AA25  GND            VSS_AA25  @S9S_MB_2U_LIB.S9S_MB_2U(SCH_1):GND
  AA24  GND            VSS_AA24  @S9S_MB_2U_LIB.S9S_MB_2U(SCH_1):GND
  AA22  GND            VSS_AA22  @S9S_MB_2U_LIB.S9S_MB_2U(SCH_1):GND
  AA20  GND            VSS_AA20  @S9S_MB_2U_LIB.S9S_MB_2U(SCH_1):GND
  AA19  GND            VSS_AA19  @S9S_MB_2U_LIB.S9S_MB_2U(SCH_1):GND
  AA17  GND            VSS_AA17  @S9S_MB_2U_LIB.S9S_MB_2U(SCH_1):GND
  AA5  GND            VSS_AA5  @S9S_MB_2U_LIB.S9S_MB_2U(SCH_1):GND
  A40  GND            VSS_A40  @S9S_MB_2U_LIB.S9S_MB_2U(SCH_1):GND
  A38  GND            VSS_A38  @S9S_MB_2U_LIB.S9S_MB_2U(SCH_1):GND
  A26  GND            VSS_A26  @S9S_MB_2U_LIB.S9S_MB_2U(SCH_1):GND
  A24  GND            VSS_A24  @S9S_MB_2U_LIB.S9S_MB_2U(SCH_1):GND
  A22  GND            VSS_A22  @S9S_MB_2U_LIB.S9S_MB_2U(SCH_1):GND
  A20  GND            VSS_A20  @S9S_MB_2U_LIB.S9S_MB_2U(SCH_1):GND
   A6  GND            VSS_A6  @S9S_MB_2U_LIB.S9S_MB_2U(SCH_1):GND

EMMITSBURG_REV0P9  I7   U4     [EMMITSBURG_REV0P9-GFNOCPU04302A]
  Y34  GND            VSS_Y34  @S9S_MB_2U_LIB.S9S_MB_2U(SCH_1):GND
  Y31  GND            VSS_Y31  @S9S_MB_2U_LIB.S9S_MB_2U(SCH_1):GND
  Y15  GND            VSS_Y15  @S9S_MB_2U_LIB.S9S_MB_2U(SCH_1):GND
  Y11  GND            VSS_Y11  @S9S_MB_2U_LIB.S9S_MB_2U(SCH_1):GND
   Y8  GND            VSS_Y8  @S9S_MB_2U_LIB.S9S_MB_2U(SCH_1):GND
  W39  GND            VSS_W39  @S9S_MB_2U_LIB.S9S_MB_2U(SCH_1):GND
  W25  GND            VSS_W25  @S9S_MB_2U_LIB.S9S_MB_2U(SCH_1):GND
   W5  GND            VSS_W5  @S9S_MB_2U_LIB.S9S_MB_2U(SCH_1):GND
   W3  GND            VSS_W3  @S9S_MB_2U_LIB.S9S_MB_2U(SCH_1):GND
  V31  GND            VSS_V31  @S9S_MB_2U_LIB.S9S_MB_2U(SCH_1):GND
   V2  GND            VSS_V2  @S9S_MB_2U_LIB.S9S_MB_2U(SCH_1):GND
  U39  GND            VSS_U39  @S9S_MB_2U_LIB.S9S_MB_2U(SCH_1):GND
  U25  GND            VSS_U25  @S9S_MB_2U_LIB.S9S_MB_2U(SCH_1):GND
  U13  GND            VSS_U13  @S9S_MB_2U_LIB.S9S_MB_2U(SCH_1):GND
  U10  GND            VSS_U10  @S9S_MB_2U_LIB.S9S_MB_2U(SCH_1):GND
   U5  GND            VSS_U5  @S9S_MB_2U_LIB.S9S_MB_2U(SCH_1):GND
  T31  GND            VSS_T31  @S9S_MB_2U_LIB.S9S_MB_2U(SCH_1):GND
  R36  GND            VSS_R36  @S9S_MB_2U_LIB.S9S_MB_2U(SCH_1):GND
  R20  GND            VSS_R20  @S9S_MB_2U_LIB.S9S_MB_2U(SCH_1):GND
  R16  GND            VSS_R16  @S9S_MB_2U_LIB.S9S_MB_2U(SCH_1):GND
  R13  GND            VSS_R13  @S9S_MB_2U_LIB.S9S_MB_2U(SCH_1):GND
  P43  GND            VSS_P43  @S9S_MB_2U_LIB.S9S_MB_2U(SCH_1):GND
  P41  GND            VSS_P41  @S9S_MB_2U_LIB.S9S_MB_2U(SCH_1):GND
  P39  GND            VSS_P39  @S9S_MB_2U_LIB.S9S_MB_2U(SCH_1):GND
  P37  GND            VSS_P37  @S9S_MB_2U_LIB.S9S_MB_2U(SCH_1):GND
  P31  GND            VSS_P31  @S9S_MB_2U_LIB.S9S_MB_2U(SCH_1):GND
  P28  GND            VSS_P28  @S9S_MB_2U_LIB.S9S_MB_2U(SCH_1):GND
  P24  GND            VSS_P24  @S9S_MB_2U_LIB.S9S_MB_2U(SCH_1):GND
  P11  GND            VSS_P11  @S9S_MB_2U_LIB.S9S_MB_2U(SCH_1):GND
   P8  GND            VSS_P8  @S9S_MB_2U_LIB.S9S_MB_2U(SCH_1):GND
   P5  GND            VSS_P5  @S9S_MB_2U_LIB.S9S_MB_2U(SCH_1):GND
  N32  GND            VSS_N32  @S9S_MB_2U_LIB.S9S_MB_2U(SCH_1):GND
  N16  GND            VSS_N16  @S9S_MB_2U_LIB.S9S_MB_2U(SCH_1):GND
  M39  GND            VSS_M39  @S9S_MB_2U_LIB.S9S_MB_2U(SCH_1):GND
  M37  GND            VSS_M37  @S9S_MB_2U_LIB.S9S_MB_2U(SCH_1):GND
  M34  GND            VSS_M34  @S9S_MB_2U_LIB.S9S_MB_2U(SCH_1):GND
  M31  GND            VSS_M31  @S9S_MB_2U_LIB.S9S_MB_2U(SCH_1):GND
  M28  GND            VSS_M28  @S9S_MB_2U_LIB.S9S_MB_2U(SCH_1):GND
  M21  GND            VSS_M21  @S9S_MB_2U_LIB.S9S_MB_2U(SCH_1):GND
  M18  GND            VSS_M18  @S9S_MB_2U_LIB.S9S_MB_2U(SCH_1):GND
  M15  GND            VSS_M15  @S9S_MB_2U_LIB.S9S_MB_2U(SCH_1):GND
  M11  GND            VSS_M11  @S9S_MB_2U_LIB.S9S_MB_2U(SCH_1):GND
   M5  GND            VSS_M5  @S9S_MB_2U_LIB.S9S_MB_2U(SCH_1):GND
   M3  GND            VSS_M3  @S9S_MB_2U_LIB.S9S_MB_2U(SCH_1):GND
   M1  GND            VSS_M1  @S9S_MB_2U_LIB.S9S_MB_2U(SCH_1):GND
  L36  GND            VSS_L36  @S9S_MB_2U_LIB.S9S_MB_2U(SCH_1):GND
  L29  GND            VSS_L29  @S9S_MB_2U_LIB.S9S_MB_2U(SCH_1):GND
  L26  GND            VSS_L26  @S9S_MB_2U_LIB.S9S_MB_2U(SCH_1):GND
  L23  GND            VSS_L23  @S9S_MB_2U_LIB.S9S_MB_2U(SCH_1):GND
  L20  GND            VSS_L20  @S9S_MB_2U_LIB.S9S_MB_2U(SCH_1):GND
  L16  GND            VSS_L16  @S9S_MB_2U_LIB.S9S_MB_2U(SCH_1):GND
  L10  GND            VSS_L10  @S9S_MB_2U_LIB.S9S_MB_2U(SCH_1):GND
  K39  GND            VSS_K39  @S9S_MB_2U_LIB.S9S_MB_2U(SCH_1):GND
  K34  GND            VSS_K34  @S9S_MB_2U_LIB.S9S_MB_2U(SCH_1):GND
  K24  GND            VSS_K24  @S9S_MB_2U_LIB.S9S_MB_2U(SCH_1):GND
  K15  GND            VSS_K15  @S9S_MB_2U_LIB.S9S_MB_2U(SCH_1):GND
  K11  GND            VSS_K11  @S9S_MB_2U_LIB.S9S_MB_2U(SCH_1):GND
   K5  GND            VSS_K5  @S9S_MB_2U_LIB.S9S_MB_2U(SCH_1):GND
  J26  GND            VSS_J26  @S9S_MB_2U_LIB.S9S_MB_2U(SCH_1):GND
  J20  GND            VSS_J20  @S9S_MB_2U_LIB.S9S_MB_2U(SCH_1):GND
  J13  GND            VSS_J13  @S9S_MB_2U_LIB.S9S_MB_2U(SCH_1):GND
  H39  GND            VSS_H39  @S9S_MB_2U_LIB.S9S_MB_2U(SCH_1):GND
   H8  GND            VSS_H8  @S9S_MB_2U_LIB.S9S_MB_2U(SCH_1):GND
   H5  GND            VSS_H5  @S9S_MB_2U_LIB.S9S_MB_2U(SCH_1):GND
  G26  GND            VSS_G26  @S9S_MB_2U_LIB.S9S_MB_2U(SCH_1):GND
  G20  GND            VSS_G20  @S9S_MB_2U_LIB.S9S_MB_2U(SCH_1):GND
  G13  GND            VSS_G13  @S9S_MB_2U_LIB.S9S_MB_2U(SCH_1):GND
  F41  GND            VSS_F41  @S9S_MB_2U_LIB.S9S_MB_2U(SCH_1):GND
  F39  GND            VSS_F39  @S9S_MB_2U_LIB.S9S_MB_2U(SCH_1):GND
  F34  GND            VSS_F34  @S9S_MB_2U_LIB.S9S_MB_2U(SCH_1):GND
  F31  GND            VSS_F31  @S9S_MB_2U_LIB.S9S_MB_2U(SCH_1):GND
  F24  GND            VSS_F24  @S9S_MB_2U_LIB.S9S_MB_2U(SCH_1):GND
  F15  GND            VSS_F15  @S9S_MB_2U_LIB.S9S_MB_2U(SCH_1):GND
  E40  GND            VSS_E40  @S9S_MB_2U_LIB.S9S_MB_2U(SCH_1):GND
  E38  GND            VSS_E38  @S9S_MB_2U_LIB.S9S_MB_2U(SCH_1):GND
  E36  GND            VSS_E36  @S9S_MB_2U_LIB.S9S_MB_2U(SCH_1):GND
  E34  GND            VSS_E34  @S9S_MB_2U_LIB.S9S_MB_2U(SCH_1):GND
  E32  GND            VSS_E32  @S9S_MB_2U_LIB.S9S_MB_2U(SCH_1):GND
  E30  GND            VSS_E30  @S9S_MB_2U_LIB.S9S_MB_2U(SCH_1):GND
  E28  GND            VSS_E28  @S9S_MB_2U_LIB.S9S_MB_2U(SCH_1):GND
  E26  GND            VSS_E26  @S9S_MB_2U_LIB.S9S_MB_2U(SCH_1):GND
  E24  GND            VSS_E24  @S9S_MB_2U_LIB.S9S_MB_2U(SCH_1):GND
  E22  GND            VSS_E22  @S9S_MB_2U_LIB.S9S_MB_2U(SCH_1):GND
  E20  GND            VSS_E20  @S9S_MB_2U_LIB.S9S_MB_2U(SCH_1):GND
  E18  GND            VSS_E18  @S9S_MB_2U_LIB.S9S_MB_2U(SCH_1):GND
  E16  GND            VSS_E16  @S9S_MB_2U_LIB.S9S_MB_2U(SCH_1):GND
  E14  GND            VSS_E14  @S9S_MB_2U_LIB.S9S_MB_2U(SCH_1):GND
  E12  GND            VSS_E12  @S9S_MB_2U_LIB.S9S_MB_2U(SCH_1):GND
  E10  GND            VSS_E10  @S9S_MB_2U_LIB.S9S_MB_2U(SCH_1):GND
   E8  GND            VSS_E8  @S9S_MB_2U_LIB.S9S_MB_2U(SCH_1):GND
   E6  GND            VSS_E6  @S9S_MB_2U_LIB.S9S_MB_2U(SCH_1):GND
  D29  GND            VSS_D29  @S9S_MB_2U_LIB.S9S_MB_2U(SCH_1):GND
  D13  GND            VSS_D13  @S9S_MB_2U_LIB.S9S_MB_2U(SCH_1):GND
   D9  GND            VSS_D9  @S9S_MB_2U_LIB.S9S_MB_2U(SCH_1):GND
   D5  GND            VSS_D5  @S9S_MB_2U_LIB.S9S_MB_2U(SCH_1):GND
  C38  GND            VSS_C38  @S9S_MB_2U_LIB.S9S_MB_2U(SCH_1):GND
  C26  GND            VSS_C26  @S9S_MB_2U_LIB.S9S_MB_2U(SCH_1):GND
  C24  GND            VSS_C24  @S9S_MB_2U_LIB.S9S_MB_2U(SCH_1):GND
  C22  GND            VSS_C22  @S9S_MB_2U_LIB.S9S_MB_2U(SCH_1):GND
  C20  GND            VSS_C20  @S9S_MB_2U_LIB.S9S_MB_2U(SCH_1):GND
   C4  GND            VSS_C4  @S9S_MB_2U_LIB.S9S_MB_2U(SCH_1):GND
  BG34  GND            VSS_BG34  @S9S_MB_2U_LIB.S9S_MB_2U(SCH_1):GND
  BG10  GND            VSS_BG10  @S9S_MB_2U_LIB.S9S_MB_2U(SCH_1):GND
  BF21  GND            VSS_BF21  @S9S_MB_2U_LIB.S9S_MB_2U(SCH_1):GND
  BE34  GND            VSS_BE34  @S9S_MB_2U_LIB.S9S_MB_2U(SCH_1):GND
  BE10  GND            VSS_BE10  @S9S_MB_2U_LIB.S9S_MB_2U(SCH_1):GND
  BD39  GND            VSS_BD39  @S9S_MB_2U_LIB.S9S_MB_2U(SCH_1):GND
  BD21  GND            VSS_BD21  @S9S_MB_2U_LIB.S9S_MB_2U(SCH_1):GND
  BD5  GND            VSS_BD5  @S9S_MB_2U_LIB.S9S_MB_2U(SCH_1):GND
  BC38  GND            VSS_BC38  @S9S_MB_2U_LIB.S9S_MB_2U(SCH_1):GND
  BC36  GND            VSS_BC36  @S9S_MB_2U_LIB.S9S_MB_2U(SCH_1):GND
  BC34  GND            VSS_BC34  @S9S_MB_2U_LIB.S9S_MB_2U(SCH_1):GND
  BC32  GND            VSS_BC32  @S9S_MB_2U_LIB.S9S_MB_2U(SCH_1):GND
  BC30  GND            VSS_BC30  @S9S_MB_2U_LIB.S9S_MB_2U(SCH_1):GND
  BC28  GND            VSS_BC28  @S9S_MB_2U_LIB.S9S_MB_2U(SCH_1):GND
  BC26  GND            VSS_BC26  @S9S_MB_2U_LIB.S9S_MB_2U(SCH_1):GND
  BC24  GND            VSS_BC24  @S9S_MB_2U_LIB.S9S_MB_2U(SCH_1):GND
  BC22  GND            VSS_BC22  @S9S_MB_2U_LIB.S9S_MB_2U(SCH_1):GND
  BC20  GND            VSS_BC20  @S9S_MB_2U_LIB.S9S_MB_2U(SCH_1):GND
  BC18  GND            VSS_BC18  @S9S_MB_2U_LIB.S9S_MB_2U(SCH_1):GND
  BC16  GND            VSS_BC16  @S9S_MB_2U_LIB.S9S_MB_2U(SCH_1):GND
  BC14  GND            VSS_BC14  @S9S_MB_2U_LIB.S9S_MB_2U(SCH_1):GND
  BC12  GND            VSS_BC12  @S9S_MB_2U_LIB.S9S_MB_2U(SCH_1):GND
  BC10  GND            VSS_BC10  @S9S_MB_2U_LIB.S9S_MB_2U(SCH_1):GND
  BC8  GND            VSS_BC8  @S9S_MB_2U_LIB.S9S_MB_2U(SCH_1):GND
  BC6  GND            VSS_BC6  @S9S_MB_2U_LIB.S9S_MB_2U(SCH_1):GND
  BB39  GND            VSS_BB39  @S9S_MB_2U_LIB.S9S_MB_2U(SCH_1):GND
  BB5  GND            VSS_BB5  @S9S_MB_2U_LIB.S9S_MB_2U(SCH_1):GND
  B39  GND            VSS_B39  @S9S_MB_2U_LIB.S9S_MB_2U(SCH_1):GND
  B29  GND            VSS_B29  @S9S_MB_2U_LIB.S9S_MB_2U(SCH_1):GND
  B13  GND            VSS_B13  @S9S_MB_2U_LIB.S9S_MB_2U(SCH_1):GND
   B9  GND            VSS_B9  @S9S_MB_2U_LIB.S9S_MB_2U(SCH_1):GND
  AY39  GND            VSS_AY39  @S9S_MB_2U_LIB.S9S_MB_2U(SCH_1):GND
  AY37  GND            VSS_AY37  @S9S_MB_2U_LIB.S9S_MB_2U(SCH_1):GND
  AY34  GND            VSS_AY34  @S9S_MB_2U_LIB.S9S_MB_2U(SCH_1):GND
  AY31  GND            VSS_AY31  @S9S_MB_2U_LIB.S9S_MB_2U(SCH_1):GND
  AY28  GND            VSS_AY28  @S9S_MB_2U_LIB.S9S_MB_2U(SCH_1):GND
  AY8  GND            VSS_AY8  @S9S_MB_2U_LIB.S9S_MB_2U(SCH_1):GND
  AY5  GND            VSS_AY5  @S9S_MB_2U_LIB.S9S_MB_2U(SCH_1):GND
  AY3  GND            VSS_AY3  @S9S_MB_2U_LIB.S9S_MB_2U(SCH_1):GND

EMMITSBURG_REV0P9  I4   U4     [EMMITSBURG_REV0P9-GFNOCPU04302A]
  BB43  NC             RSVD_BB43  NC
  P18  NC             RSVD_P18  NC
   A4  NC             RSVD_A4  NC
   F1  NC             RSVD_F1  NC
  L13  NC             RSVD_L13  NC
  N13  NC             RSVD_N13  NC
   H1  NC             RSVD_H1  NC
  AC13  PD_RCOMP_1P8_3P3  GPIO_RCOMP_1P8_3P3  @S9S_MB_2U_LIB.S9S_MB_2U(SCH_1):PD_RCOMP_1P8_3P3

EMMITSBURG_REV0P9  I11  U4     [EMMITSBURG_REV0P9-GFNOCPU04302A]
  AF15  NC             RSVD_AF15  NC
  AN26  NC             RSVD_AN26  NC
  AH15  P3V3_RTC_AUX   VCCRTC  @S9S_MB_2U_LIB.S9S_MB_2U(SCH_1):P3V3_RTC_AUX
  AD17  P3V3_AUX       VCCP_GPPI_1P8_3P3  @S9S_MB_2U_LIB.S9S_MB_2U(SCH_1):P3V3_AUX
  AN20  P3V3_AUX       VCCP_GPPE_1P8_3P3  @S9S_MB_2U_LIB.S9S_MB_2U(SCH_1):P3V3_AUX
  T15  P3V3_AUX       VCCP_GPPD_1P8_3P3  @S9S_MB_2U_LIB.S9S_MB_2U(SCH_1):P3V3_AUX
  P21  P3V3_AUX       VCCP_3P3_P21  @S9S_MB_2U_LIB.S9S_MB_2U(SCH_1):P3V3_AUX
  V15  P3V3_AUX       VCCP_3P3_DSW_V15  @S9S_MB_2U_LIB.S9S_MB_2U(SCH_1):P3V3_AUX
  AD15  P3V3_AUX       VCCP_3P3_DSW_AD15  @S9S_MB_2U_LIB.S9S_MB_2U(SCH_1):P3V3_AUX
  AL17  P3V3_AUX       VCCP_3P3_AL17  @S9S_MB_2U_LIB.S9S_MB_2U(SCH_1):P3V3_AUX
  AK15  P3V3_AUX       VCCP_3P3_AK15  @S9S_MB_2U_LIB.S9S_MB_2U(SCH_1):P3V3_AUX
  AJ17  P3V3_AUX       VCCP_3P3_AJ17  @S9S_MB_2U_LIB.S9S_MB_2U(SCH_1):P3V3_AUX
  AG17  P3V3_AUX       VCCP_3P3_AG17  @S9S_MB_2U_LIB.S9S_MB_2U(SCH_1):P3V3_AUX
  AF17  P3V3_AUX       VCCP_3P3_AF17  @S9S_MB_2U_LIB.S9S_MB_2U(SCH_1):P3V3_AUX
  W29  P1V8_PCH_PLL_AUX  VCCP_1P8_FILTERED_W29  @S9S_MB_2U_LIB.S9S_MB_2U(SCH_1):P1V8_PCH_PLL_AUX
  W27  P1V8_PCH_PLL_AUX  VCCP_1P8_FILTERED_W27  @S9S_MB_2U_LIB.S9S_MB_2U(SCH_1):P1V8_PCH_PLL_AUX
  U29  P1V8_PCH_PLL_AUX  VCCP_1P8_FILTERED_U29  @S9S_MB_2U_LIB.S9S_MB_2U(SCH_1):P1V8_PCH_PLL_AUX
  AB34  P1V8_PCH_PLL_AUX  VCCP_1P8_FILTERED_AB34  @S9S_MB_2U_LIB.S9S_MB_2U(SCH_1):P1V8_PCH_PLL_AUX
  AB31  P1V8_PCH_PLL_AUX  VCCP_1P8_FILTERED_AB31  @S9S_MB_2U_LIB.S9S_MB_2U(SCH_1):P1V8_PCH_PLL_AUX
  U24  P1V8_PCH_AUX   VCCP_1P8_U24  @S9S_MB_2U_LIB.S9S_MB_2U(SCH_1):P1V8_PCH_AUX
  U22  P1V8_PCH_AUX   VCCP_1P8_U22  @S9S_MB_2U_LIB.S9S_MB_2U(SCH_1):P1V8_PCH_AUX
  U20  P1V8_PCH_AUX   VCCP_1P8_U20  @S9S_MB_2U_LIB.S9S_MB_2U(SCH_1):P1V8_PCH_AUX
  U19  P1V8_PCH_AUX   VCCP_1P8_U19  @S9S_MB_2U_LIB.S9S_MB_2U(SCH_1):P1V8_PCH_AUX
  U17  P1V8_PCH_AUX   VCCP_1P8_U17  @S9S_MB_2U_LIB.S9S_MB_2U(SCH_1):P1V8_PCH_AUX
  N20  P1V8_PCH_AUX   VCCP_1P8_N20  @S9S_MB_2U_LIB.S9S_MB_2U(SCH_1):P1V8_PCH_AUX
  U27  P1V05_PCH_PLL_AUX  VCCP_1P05_FILTERED_U27  @S9S_MB_2U_LIB.S9S_MB_2U(SCH_1):P1V05_PCH_PLL_AUX
  R29  P1V05_PCH_PLL_AUX  VCCP_1P05_FILTERED_R29  @S9S_MB_2U_LIB.S9S_MB_2U(SCH_1):P1V05_PCH_PLL_AUX
  R26  P1V05_PCH_PLL_AUX  VCCP_1P05_FILTERED_R26  @S9S_MB_2U_LIB.S9S_MB_2U(SCH_1):P1V05_PCH_PLL_AUX
  R23  P1V05_PCH_PLL_AUX  VCCP_1P05_FILTERED_R23  @S9S_MB_2U_LIB.S9S_MB_2U(SCH_1):P1V05_PCH_PLL_AUX
  AL25  P1V05_PCH_PLL_AUX  VCCP_1P05_FILTERED_AL25  @S9S_MB_2U_LIB.S9S_MB_2U(SCH_1):P1V05_PCH_PLL_AUX
  AG29  P1V05_PCH_PLL_AUX  VCCP_1P05_FILTERED_AG29  @S9S_MB_2U_LIB.S9S_MB_2U(SCH_1):P1V05_PCH_PLL_AUX
  AE29  P1V05_PCH_PLL_AUX  VCCP_1P05_FILTERED_AE29  @S9S_MB_2U_LIB.S9S_MB_2U(SCH_1):P1V05_PCH_PLL_AUX
  AB27  P1V05_PCH_PLL_AUX  VCCP_1P05_FILTERED_AB27  @S9S_MB_2U_LIB.S9S_MB_2U(SCH_1):P1V05_PCH_PLL_AUX
  AA29  P1V05_PCH_PLL_AUX  VCCP_1P05_FILTERED_AA29  @S9S_MB_2U_LIB.S9S_MB_2U(SCH_1):P1V05_PCH_PLL_AUX
  AR23  P1V05_PCH_AUX  VCCP_VNN_AR23  @S9S_MB_2U_LIB.S9S_MB_2U(SCH_1):P1V05_PCH_AUX
  AP21  P1V05_PCH_AUX  VCCP_VNN_AP21  @S9S_MB_2U_LIB.S9S_MB_2U(SCH_1):P1V05_PCH_AUX
  AN23  P1V05_PCH_AUX  VCCP_VNN_AN23  @S9S_MB_2U_LIB.S9S_MB_2U(SCH_1):P1V05_PCH_AUX
  AL22  P1V05_PCH_AUX  VCCP_VNN_AL22  @S9S_MB_2U_LIB.S9S_MB_2U(SCH_1):P1V05_PCH_AUX
  AL20  P1V05_PCH_AUX  VCCP_VNN_AL20  @S9S_MB_2U_LIB.S9S_MB_2U(SCH_1):P1V05_PCH_AUX
  AJ22  P1V05_PCH_AUX  VCCP_VNN_AJ22  @S9S_MB_2U_LIB.S9S_MB_2U(SCH_1):P1V05_PCH_AUX
  AJ20  P1V05_PCH_AUX  VCCP_VNN_AJ20  @S9S_MB_2U_LIB.S9S_MB_2U(SCH_1):P1V05_PCH_AUX
  AG22  P1V05_PCH_AUX  VCCP_VNN_AG22  @S9S_MB_2U_LIB.S9S_MB_2U(SCH_1):P1V05_PCH_AUX
  AG20  P1V05_PCH_AUX  VCCP_VNN_AG20  @S9S_MB_2U_LIB.S9S_MB_2U(SCH_1):P1V05_PCH_AUX
  AF22  P1V05_PCH_AUX  VCCP_VNN_AF22  @S9S_MB_2U_LIB.S9S_MB_2U(SCH_1):P1V05_PCH_AUX
  AF20  P1V05_PCH_AUX  VCCP_VNN_AF20  @S9S_MB_2U_LIB.S9S_MB_2U(SCH_1):P1V05_PCH_AUX
  W24  P1V05_PCH_AUX  VCCP_1P05_W24  @S9S_MB_2U_LIB.S9S_MB_2U(SCH_1):P1V05_PCH_AUX
  W22  P1V05_PCH_AUX  VCCP_1P05_W22  @S9S_MB_2U_LIB.S9S_MB_2U(SCH_1):P1V05_PCH_AUX
  W20  P1V05_PCH_AUX  VCCP_1P05_W20  @S9S_MB_2U_LIB.S9S_MB_2U(SCH_1):P1V05_PCH_AUX
  W19  P1V05_PCH_AUX  VCCP_1P05_W19  @S9S_MB_2U_LIB.S9S_MB_2U(SCH_1):P1V05_PCH_AUX
  W17  P1V05_PCH_AUX  VCCP_1P05_W17  @S9S_MB_2U_LIB.S9S_MB_2U(SCH_1):P1V05_PCH_AUX
  P15  P1V05_PCH_AUX  VCCP_1P05_P15  @S9S_MB_2U_LIB.S9S_MB_2U(SCH_1):P1V05_PCH_AUX
  N26  P1V05_PCH_AUX  VCCP_1P05_N26  @S9S_MB_2U_LIB.S9S_MB_2U(SCH_1):P1V05_PCH_AUX
  N23  P1V05_PCH_AUX  VCCP_1P05_N23  @S9S_MB_2U_LIB.S9S_MB_2U(SCH_1):P1V05_PCH_AUX
  M24  P1V05_PCH_AUX  VCCP_1P05_M24  @S9S_MB_2U_LIB.S9S_MB_2U(SCH_1):P1V05_PCH_AUX
  AR26  P1V05_PCH_AUX  VCCP_1P05_AR26  @S9S_MB_2U_LIB.S9S_MB_2U(SCH_1):P1V05_PCH_AUX
  AJ27  P1V05_PCH_AUX  VCCP_1P05_AJ27  @S9S_MB_2U_LIB.S9S_MB_2U(SCH_1):P1V05_PCH_AUX
  AJ25  P1V05_PCH_AUX  VCCP_1P05_AJ25  @S9S_MB_2U_LIB.S9S_MB_2U(SCH_1):P1V05_PCH_AUX
  AG27  P1V05_PCH_AUX  VCCP_1P05_AG27  @S9S_MB_2U_LIB.S9S_MB_2U(SCH_1):P1V05_PCH_AUX
  AG25  P1V05_PCH_AUX  VCCP_1P05_AG25  @S9S_MB_2U_LIB.S9S_MB_2U(SCH_1):P1V05_PCH_AUX
  AF27  P1V05_PCH_AUX  VCCP_1P05_AF27  @S9S_MB_2U_LIB.S9S_MB_2U(SCH_1):P1V05_PCH_AUX
  AF25  P1V05_PCH_AUX  VCCP_1P05_AF25  @S9S_MB_2U_LIB.S9S_MB_2U(SCH_1):P1V05_PCH_AUX
  AD27  P1V05_PCH_AUX  VCCP_1P05_AD27  @S9S_MB_2U_LIB.S9S_MB_2U(SCH_1):P1V05_PCH_AUX
  AD25  P1V05_PCH_AUX  VCCP_1P05_AD25  @S9S_MB_2U_LIB.S9S_MB_2U(SCH_1):P1V05_PCH_AUX
  AB24  P1V05_PCH_AUX  VCCP_1P05_AB24  @S9S_MB_2U_LIB.S9S_MB_2U(SCH_1):P1V05_PCH_AUX
  AB22  P1V05_PCH_AUX  VCCP_1P05_AB22  @S9S_MB_2U_LIB.S9S_MB_2U(SCH_1):P1V05_PCH_AUX
  AB20  P1V05_PCH_AUX  VCCP_1P05_AB20  @S9S_MB_2U_LIB.S9S_MB_2U(SCH_1):P1V05_PCH_AUX
  AB19  P1V05_PCH_AUX  VCCP_1P05_AB19  @S9S_MB_2U_LIB.S9S_MB_2U(SCH_1):P1V05_PCH_AUX
  BG40  GND            VSS_BG40  @S9S_MB_2U_LIB.S9S_MB_2U(SCH_1):GND

EMMITSBURG_REV0P9  I27  U4     [EMMITSBURG_REV0P9-GFNOCPU04302A]
  V11  NC             GPP_N_4  NC
  T11  NC             GPP_N_1  NC
  BG3  NC             NC_CGC_DUT_DETECT_N  NC
  BB11  SPI_PCH_TPM_CS_N  SPI0_TPM_CS_N  @S9S_MB_2U_LIB.S9S_MB_2U(SCH_1):SPI_PCH_TPM_CS_N
  BA16  SPI_PCH_IO3    SPI0_IO_3  @S9S_MB_2U_LIB.S9S_MB_2U(SCH_1):SPI_PCH_IO3
  AV15  SPI_PCH_IO2    SPI0_IO_2  @S9S_MB_2U_LIB.S9S_MB_2U(SCH_1):SPI_PCH_IO2
  AW16  SPI_PCH_IO1    SPI0_MISO_IO_1  @S9S_MB_2U_LIB.S9S_MB_2U(SCH_1):SPI_PCH_IO1
  BA13  SPI_PCH_IO0    SPI0_MOSI_IO_0  @S9S_MB_2U_LIB.S9S_MB_2U(SCH_1):SPI_PCH_IO0
  BA10  SPI_PCH_CS1_R_N  SPI0_FLASH_1_CS_N  @S9S_MB_2U_LIB.S9S_MB_2U(SCH_1):SPI_PCH_CS1_R_N
  AW13  SPI_PCH_CS0_R_N  SPI0_FLASH_0_CS_N  @S9S_MB_2U_LIB.S9S_MB_2U(SCH_1):SPI_PCH_CS0_R_N
  BB15  SPI_PCH_CLK    SPI0_CLK  @S9S_MB_2U_LIB.S9S_MB_2U(SCH_1):SPI_PCH_CLK
  BF9  RST_SRTCRST_N  SRTCRST_N  @S9S_MB_2U_LIB.S9S_MB_2U(SCH_1):RST_SRTCRST_N
  BD7  RST_RTCRST_N   RCTRST_N  @S9S_MB_2U_LIB.S9S_MB_2U(SCH_1):RST_RTCRST_N
  AU16  PU_NO_REBOOT_STRAP  GPPC_S_1_SPKR_TIME_SYNC_1  @S9S_MB_2U_LIB.S9S_MB_2U(SCH_1):PU_NO_REBOOT_STRAP
  AV18  IRQ_SMI_ACTIVE_N  GPPC_S_9_SMI_N  @S9S_MB_2U_LIB.S9S_MB_2U(SCH_1):IRQ_SMI_ACTIVE_N
  AP15  IRQ_PCH_CPU_NMI_EVENT_R_N  GPPC_S_8_NMI_N  @S9S_MB_2U_LIB.S9S_MB_2U(SCH_1):IRQ_PCH_CPU_NMI_EVENT_R_N
  AR16  FM_XTAL_INPUT_FREQUENCY_1_MGPIO  GPPC_S_2_CPU_GP_0  @S9S_MB_2U_LIB.S9S_MB_2U(SCH_1):FM_XTAL_INPUT_FREQUENCY_1_MGPIO_TEST5
  BB18  FM_XTAL_INPUT_FREQUENCY_0_MGPIO  GPPC_S_0_TIME_SYNC_0  @S9S_MB_2U_LIB.S9S_MB_2U(SCH_1):FM_XTAL_INPUT_FREQUENCY_0_MGPIO_TEST4
  BA7  FM_SUSACK_N    GPPC_S_7_SUSACK_N  @S9S_MB_2U_LIB.S9S_MB_2U(SCH_1):FM_SUSACK_N
  AU13  FM_SPI_3V3_1V8_VOLTAGE  GPPC_S_4_CPU_GP_2  @S9S_MB_2U_LIB.S9S_MB_2U(SCH_1):FM_SPI_3V3_1V8_VOLTAGE
  A41  FM_PCH_PRSNT_N  VSS_A41  @S9S_MB_2U_LIB.S9S_MB_2U(SCH_1):FM_PCH_PRSNT_N
  AT18  FM_PCH_CONSENT_STRAP_N  GPPC_S_5_CPU_GP_3  @S9S_MB_2U_LIB.S9S_MB_2U(SCH_1):FM_PCH_CONSENT_STRAP_N
  AW10  FM_JTAG_ODT_DISABLE  GPPC_S_10  @S9S_MB_2U_LIB.S9S_MB_2U(SCH_1):FM_JTAG_ODT_DISABLE
  AR13  FM_EUP_LOT6_N  GPPC_S_6_SUSWARN_N_SUSPWRDNACK  @S9S_MB_2U_LIB.S9S_MB_2U(SCH_1):FM_EUP_LOT6_N
  BB8  FM_ESPI_CS_SWIZZLE  GPPC_S_11  @S9S_MB_2U_LIB.S9S_MB_2U(SCH_1):FM_ESPI_CS_SWIZZLE
  AV11  FM_ADR_MODE0   GPPC_S_3_CPU_GP_1  @S9S_MB_2U_LIB.S9S_MB_2U(SCH_1):FM_ADR_MODE0

EMMITSBURG_REV0P9  I22  U4     [EMMITSBURG_REV0P9-GFNOCPU04302A]
  BA36  NC             GPP_E_17_ERR0_N  NC
   J2  NC             GPPC_H_15_FLEX_CLK_OUT_0  NC
   V4  NC             GPP_I_17_HDA_SDI_1  NC
   U1  NC             GPP_I_16_HDA_SDI_0  NC
   R2  NC             GPP_I_15_HDA_SDO  NC
  BA32  NC             GPP_E_13_SATA1_SDATAOUT_SATA1_DEVSLP  NC
  BB28  NC             GPP_E_12_SATA1_SLOAD_SATA1_GP  NC
  AV34  NC             GPP_E_11_SATA1_SCLOCK_SATA1_LED_N  NC
  AB11  NC             GPP_M_7  NC
  R10  NC             GPP_M_6  NC
  AA13  NC             GPP_M_1  NC
   N7  NC             GPP_M_0  NC
  BB34  NC             GPP_E_14_SATA2_SCLOCK_SATA2_LED_N  NC
   W7  RISER3_TYPE_ID  GPP_M_4  @S9S_MB_2U_LIB.S9S_MB_2U(SCH_1):RISER3_TYPE_ID
  AA7  RISER2_TYPE_ID  GPP_M_2  @S9S_MB_2U_LIB.S9S_MB_2U(SCH_1):RISER2_TYPE_ID
   J4  PU_PCH_PMCALERT_N  GPPC_H_18_PMCALERT_N  @S9S_MB_2U_LIB.S9S_MB_2U(SCH_1):PU_PCH_PMCALERT_N
   V8  PCIE_RISER3_PRSNT2_N  GPP_M_5  @S9S_MB_2U_LIB.S9S_MB_2U(SCH_1):PCIE_RISER3_PRSNT2_N
  AA10  NC             GPP_M_3  NC
   P1  OCP_SFF_BIF2_N  GPP_I_14_HDA_SYNC  @S9S_MB_2U_LIB.S9S_MB_2U(SCH_1):OCP_SFF_BIF2_N
   N2  OCP_SFF_BIF1_N  GPP_I_13_HDA_RST_N  @S9S_MB_2U_LIB.S9S_MB_2U(SCH_1):OCP_SFF_BIF1_N
   U3  OCP_SFF_BIF0_N  GPP_I_12_HDA_BCLK  @S9S_MB_2U_LIB.S9S_MB_2U(SCH_1):OCP_SFF_BIF0_N
   N4  IRQ_TPM_SPI_N  GPP_I_21  @S9S_MB_2U_LIB.S9S_MB_2U(SCH_1):IRQ_TPM_SPI_N
  AF8  H_CPU0_PMSYNC_PCH_R2  GPP_L_0_PM_SYNC_0  @S9S_MB_2U_LIB.S9S_MB_2U(SCH_1):H_CPU0_PMSYNC_PCH_R2
  AE7  H_CPU0_PMDOWN_PCH  GPP_L_1_PM_DOWN_0  @S9S_MB_2U_LIB.S9S_MB_2U(SCH_1):H_CPU0_PMDOWN_PCH
  BB31  FM_TPM_PRSNT_N  GPP_E_19_ERR2_N  @S9S_MB_2U_LIB.S9S_MB_2U(SCH_1):FM_TPM_PRSNT_N
  BA20  FM_PS_PWROK_DLY_R_SEL  GPP_E_18_ERR1_N  @S9S_MB_2U_LIB.S9S_MB_2U(SCH_1):FM_PS_PWROK_DLY_R_SEL
  AE10  FM_PCIE_EDSFF4B_PRSNT_1_N  GPP_L_8  @S9S_MB_2U_LIB.S9S_MB_2U(SCH_1):FM_PCIE_EDSFF4B_PRSNT_1_N
  W13  FM_PCIE_EDSFF4A_PRSNT_1_N  GPP_M_17  @S9S_MB_2U_LIB.S9S_MB_2U(SCH_1):FM_PCIE_EDSFF4A_PRSNT_1_N
  N10  FM_PCIE_EDSFF3_PRSNT_1_N  GPP_M_16  @S9S_MB_2U_LIB.S9S_MB_2U(SCH_1):FM_PCIE_EDSFF3_PRSNT_1_N
  AC7  FM_PCIE_EDSFF2B_PRSNT_1_N  GPP_L_7  @S9S_MB_2U_LIB.S9S_MB_2U(SCH_1):FM_PCIE_EDSFF2B_PRSNT_1_N
   T8  FM_PCIE_EDSFF2A_PRSNT_1_N  GPP_M_15  @S9S_MB_2U_LIB.S9S_MB_2U(SCH_1):FM_PCIE_EDSFF2A_PRSNT_1_N
  AC10  FM_PCIE_EDSFF1B_PRSNT_1_N  GPP_L_2  @S9S_MB_2U_LIB.S9S_MB_2U(SCH_1):FM_PCIE_EDSFF1B_PRSNT_1_N
   U7  FM_PCIE_EDSFF1A_PRSNT_1_N  GPP_M_12  @S9S_MB_2U_LIB.S9S_MB_2U(SCH_1):FM_PCIE_EDSFF1A_PRSNT_1_N
   H3  FM_PCH_XTAL_INPUT_MODE_MGPIO_TE  GPPC_H_17_FLEX_CLK_OUT_2  @S9S_MB_2U_LIB.S9S_MB_2U(SCH_1):FM_PCH_XTAL_INPUT_MODE_MGPIO_TEST3
   R4  FM_PCH_XTALSEL  GPP_I_23  @S9S_MB_2U_LIB.S9S_MB_2U(SCH_1):FM_PCH_XTALSEL
   G4  FM_PCH_VISA_DEFAULT  GPPC_H_0  @S9S_MB_2U_LIB.S9S_MB_2U(SCH_1):FM_PCH_VISA_DEFAULT
   G2  FM_PCH_RING_OSC_BYPASS_MGPIO_TE  GPPC_H_16_FLEX_CLK_OUT_1  @S9S_MB_2U_LIB.S9S_MB_2U(SCH_1):FM_PCH_RING_OSC_BYPASS_MGPIO_TEST2
   K3  FM_PCH_MCRO_LDO  GPPC_H_7  @S9S_MB_2U_LIB.S9S_MB_2U(SCH_1):FM_PCH_MCRO_LDO
   K1  FM_PCH_IO_EXPANDER  GPPC_H_1  @S9S_MB_2U_LIB.S9S_MB_2U(SCH_1):FM_PCH_IO_EXPANDER
   L2  FM_PCH_EXTERNALCLKMODE  GPPC_H_6  @S9S_MB_2U_LIB.S9S_MB_2U(SCH_1):FM_PCH_EXTERNALCLKMODE
   P3  FM_PCH_DFXTESTMODE  GPP_I_22  @S9S_MB_2U_LIB.S9S_MB_2U(SCH_1):FM_PCH_DFXTESTMODE
   R7  FM_PCH_BIOS_RCVR_MODE  GPP_M_11  @S9S_MB_2U_LIB.S9S_MB_2U(SCH_1):FM_PCH_BIOS_RCVR_MODE
  AB8  FM_PASSWORD_CLEAR_N  GPP_L_5  @S9S_MB_2U_LIB.S9S_MB_2U(SCH_1):FM_PASSWORD_CLEAR_N
  AG10  FM_MFG_MODE    GPP_L_6  @S9S_MB_2U_LIB.S9S_MB_2U(SCH_1):FM_MFG_MODE
  AG7  FM_ME_RCVR_N   GPP_L_4  @S9S_MB_2U_LIB.S9S_MB_2U(SCH_1):FM_ME_RCVR_N
  AW29  FM_ME_BT_DONE  GPP_E_16_SATA2_SDATAOUT_SATA2_DEVSLP  @S9S_MB_2U_LIB.S9S_MB_2U(SCH_1):FM_ME_BT_DONE
  AW20  FM_ME_AUTHN_FAIL  GPP_E_15_SATA2_SLOAD_SATA2_GP  @S9S_MB_2U_LIB.S9S_MB_2U(SCH_1):FM_ME_AUTHN_FAIL
  BB21  FM_M2_SSD_1_PEDET  GPP_E_3_SATA1_XPCIE_3  @S9S_MB_2U_LIB.S9S_MB_2U(SCH_1):FM_M2_SSD_1_PEDET
  AW23  FM_M2_SSD_1_PEDET  GPP_E_2_SATA1_XPCIE_2  @S9S_MB_2U_LIB.S9S_MB_2U(SCH_1):FM_M2_SSD_1_PEDET
  BA23  FM_M2_SSD_1_PEDET  GPP_E_1_SATA1_XPCIE_1  @S9S_MB_2U_LIB.S9S_MB_2U(SCH_1):FM_M2_SSD_1_PEDET
  BA26  FM_M2_SSD_1_PEDET  GPP_E_0_SATA1_XPCIE_0  @S9S_MB_2U_LIB.S9S_MB_2U(SCH_1):FM_M2_SSD_1_PEDET
   L4  FM_LT_KEY_DOWNGRADE_N  GPPC_H_19  @S9S_MB_2U_LIB.S9S_MB_2U(SCH_1):FM_LT_KEY_DOWNGRADE_N
  AV31  FM_EDSFF4B_TYPE_ID  GPP_E_10_SATA0_SDATAOUT_SATA0_GP  @S9S_MB_2U_LIB.S9S_MB_2U(SCH_1):FM_EDSFF4B_TYPE_ID
  BA29  FM_EDSFF4A_TYPE_ID  GPP_E_9_SATA0_SLOAD_SATA0_DEVSLP  @S9S_MB_2U_LIB.S9S_MB_2U(SCH_1):FM_EDSFF4A_TYPE_ID
  AW36  FM_EDSFF3_TYPE_ID  GPP_E_8_SATA0_SCLOCK_SATA0_LED_N  @S9S_MB_2U_LIB.S9S_MB_2U(SCH_1):FM_EDSFF3_TYPE_ID
  AW32  FM_EDSFF2B_TYPE_ID  GPP_E_7_SATA0_USB3_XPCIE_1  @S9S_MB_2U_LIB.S9S_MB_2U(SCH_1):FM_EDSFF2B_TYPE_ID
  BB24  FM_EDSFF2A_TYPE_ID  GPP_E_6_SATA0_USB3_XPCIE_0  @S9S_MB_2U_LIB.S9S_MB_2U(SCH_1):FM_EDSFF2A_TYPE_ID
  AV28  FM_EDSFF1B_TYPE_ID  GPP_E_5_SATA0_XPCIE_3  @S9S_MB_2U_LIB.S9S_MB_2U(SCH_1):FM_EDSFF1B_TYPE_ID
  AV24  FM_EDSFF1A_TYPE_ID  GPP_E_4_SATA0_XPCIE_2  @S9S_MB_2U_LIB.S9S_MB_2U(SCH_1):FM_EDSFF1A_TYPE_ID
  W10  FM_BMC_READY_R_N  GPP_M_8  @S9S_MB_2U_LIB.S9S_MB_2U(SCH_1):FM_BMC_READY_R_N
  AF11  FM_BIOS_ADV_FUNCTIONS  GPP_L_3  @S9S_MB_2U_LIB.S9S_MB_2U(SCH_1):FM_BIOS_ADV_FUNCTIONS

EMMITSBURG_REV0P9  I93  U4     [EMMITSBURG_REV0P9-GFNOCPU04302A]
  BG30  USB_OC2_INT_R_N  GPPC_B_7_USB2_OCB_2  @S9S_MB_2U_LIB.S9S_MB_2U(SCH_1):USB_OC2_INT_R_N
  BG32  USB_OC1_REAR_R_N  GPPC_B_6_USB2_OCB_1  @S9S_MB_2U_LIB.S9S_MB_2U(SCH_1):USB_OC1_REAR_R_N
  AG3  NC             GPP_D_20_CATERR_N  NC
  AD2  NC             GPP_D_2_HS_SMBALERT_N_DMA_SMBALERT_N  NC
  AT3  NC             GPPC_C_5_ME_SML0BALERT_N  NC
  BE14  NC             GPPC_A_15_SRCCLKREQ_N_5  NC
  BE12  NC             GPPC_A_14_SRCCLKREQ_N_4  NC
  BF15  NC             GPPC_A_13_SRCCLKREQ_N_3  NC
  BG18  NC             GPPC_A_11_SRCCLKREQ_N_1  NC
  BD17  NC             GPPC_A_10_SRCCLKREQ_N_0  NC
  BG14  NC             GPPC_A_19_SRCCLKREQ_N_9  NC
  BF11  NC             GPPC_A_18_SRCCLKREQ_N_8  NC
  AW4  SMB_SML1_PMBUS_3V3AUX_PCH_SDA  GPPC_C_7_ME_SML1DATA  @S9S_MB_2U_LIB.S9S_MB_2U(SCH_1):SMB_SML1_PMBUS_3V3AUX_PCH_SDA
  AP1  SMB_SML1_PMBUS_3V3AUX_PCH_SCL  GPPC_C_6_ME_SML1CLK  @S9S_MB_2U_LIB.S9S_MB_2U(SCH_1):SMB_SML1_PMBUS_3V3AUX_PCH_SCL
  BA4  SMB_SML0_3V3AUX_PCH_SDA  GPPC_C_1_ME_SML0DATA  @S9S_MB_2U_LIB.S9S_MB_2U(SCH_1):SMB_SML0_3V3AUX_PCH_SDA
  BC4  SMB_SML0_3V3AUX_PCH_SCL  GPPC_C_0_ME_SML0CLK  @S9S_MB_2U_LIB.S9S_MB_2U(SCH_1):SMB_SML0_3V3AUX_PCH_SCL
  AU4  SMB_SML0B_3V3AUX_SDA  GPPC_C_3_ME_SML0BDATA  @S9S_MB_2U_LIB.S9S_MB_2U(SCH_1):SMB_SML0B_3V3AUX_SDA
  BB3  SMB_SML0B_3V3AUX_SCL  GPPC_C_4_ME_SML0BCLK  @S9S_MB_2U_LIB.S9S_MB_2U(SCH_1):SMB_SML0B_3V3AUX_SCL
  AP3  NC             GPPC_C_10_ME_SML2DATA  NC
  AR2  NC             GPPC_C_9_ME_SML2CLK  NC
  AE1  SMB_HOST_BMC_3V3AUX_SDA  GPP_D_1_HS_SMBDATA_DMA_SMBDATA  @S9S_MB_2U_LIB.S9S_MB_2U(SCH_1):SMB_HOST_BMC_3V3AUX_SDA
  AF2  SMB_HOST_BMC_3V3AUX_SCL  GPP_D_0_HS_SMBCLK_DMA_SMBCLK  @S9S_MB_2U_LIB.S9S_MB_2U(SCH_1):SMB_HOST_BMC_3V3AUX_SCL
  AB4  RST_PLTRST_N   GPP_D_11_PLTRST_N  @S9S_MB_2U_LIB.S9S_MB_2U(SCH_1):RST_PLTRST_N
  BF17  RST_ESPI_RESET_N  GPPC_A_8_ESPI_RESET_N  @S9S_MB_2U_LIB.S9S_MB_2U(SCH_1):RST_ESPI_RESET_N
  AV1  PU_SMB_SML4_3V3AUX_PCH_SDA  GPPC_C_16_ME_SML4DATA  @S9S_MB_2U_LIB.S9S_MB_2U(SCH_1):PU_SMB_SML4_3V3AUX_PCH_SDA
  BA2  PU_SMB_SML4_3V3AUX_PCH_SCL  GPPC_C_15_ME_SML4CLK  @S9S_MB_2U_LIB.S9S_MB_2U(SCH_1):PU_SMB_SML4_3V3AUX_PCH_SCL
  AY1  PU_SMB_SML3_3V3AUX_PCH_SDA  GPPC_C_13_ME_SML3DATA  @S9S_MB_2U_LIB.S9S_MB_2U(SCH_1):PU_SMB_SML3_3V3AUX_PCH_SDA
  AN4  PU_SMB_SML3_3V3AUX_PCH_SCL  GPPC_C_12_ME_SML3CLK  @S9S_MB_2U_LIB.S9S_MB_2U(SCH_1):PU_SMB_SML3_3V3AUX_PCH_SCL
  AT1  PU_SMB_PCH_PLD_3V3AUX_SDA  GPPC_C_20_MC_SMBDATA  @S9S_MB_2U_LIB.S9S_MB_2U(SCH_1):PU_SMB_PCH_PLD_3V3AUX_SDA
  AL1  PU_SMB_PCH_PLD_3V3AUX_SCL  GPPC_C_19_MC_SMBCLK  @S9S_MB_2U_LIB.S9S_MB_2U(SCH_1):PU_SMB_PCH_PLD_3V3AUX_SCL
  AC3  PU_PCH_VRALERT_N  GPP_D_15_VRALERT_N  @S9S_MB_2U_LIB.S9S_MB_2U(SCH_1):PU_PCH_VRALERT_N
  AN2  PU_PCH_PLD_3V3AUX_ALERT_N  GPPC_C_21_MC_SMBALERT_N  @S9S_MB_2U_LIB.S9S_MB_2U(SCH_1):PU_PCH_PLD_3V3AUX_ALERT_N
  BG22  PU_OC6_USB_N   GPPC_B_11_USB2_OCB_6  @S9S_MB_2U_LIB.S9S_MB_2U(SCH_1):PU_OC6_USB_N
  BG24  PU_OC5_USB_N   GPPC_B_10_USB2_OCB_5  @S9S_MB_2U_LIB.S9S_MB_2U(SCH_1):PU_OC5_USB_N
  BG26  PU_OC4_USB_N   GPPC_B_9_USB2_OCB_4  @S9S_MB_2U_LIB.S9S_MB_2U(SCH_1):PU_OC4_USB_N
  BG28  PU_OC3_USB_N   GPPC_B_8_USB2_OCB_3  @S9S_MB_2U_LIB.S9S_MB_2U(SCH_1):PU_OC3_USB_N
  AJ3  PU_LPC_PME_N   GPP_D_9_PME_N  @S9S_MB_2U_LIB.S9S_MB_2U(SCH_1):PU_LPC_PME_N
  BG16  M2_SSD0_CLKREQ_LV_EN_N  GPPC_A_12_SRCCLKREQ_N_2  @S9S_MB_2U_LIB.S9S_MB_2U(SCH_1):M2_SSD0_CLKREQ_LV_EN_N
  BE26  JTAG_TRC_PCH_PTI<9>  GPPC_B_16_HS_UART1_RXD  @S9S_MB_2U_LIB.S9S_MB_2U(SCH_1):JTAG_TRC_PCH_PTI<9>
  BD27  JTAG_TRC_PCH_PTI<8>  GPPC_B_15_HS_UART0_CTS_N  @S9S_MB_2U_LIB.S9S_MB_2U(SCH_1):JTAG_TRC_PCH_PTI<8>
  BF29  JTAG_TRC_PCH_PTI<7>  GPPC_B_14_HS_UART0_RTS_N  @S9S_MB_2U_LIB.S9S_MB_2U(SCH_1):JTAG_TRC_PCH_PTI<7>
  BE28  JTAG_TRC_PCH_PTI<6>  GPPC_B_13_HS_UART0_TXD  @S9S_MB_2U_LIB.S9S_MB_2U(SCH_1):JTAG_TRC_PCH_PTI<6>
  BD29  JTAG_TRC_PCH_PTI<5>  GPPC_B_12_HS_UART0_RXD  @S9S_MB_2U_LIB.S9S_MB_2U(SCH_1):JTAG_TRC_PCH_PTI<5>
  BF31  JTAG_TRC_PCH_PTI<4>  GPPC_B_5_USB2_OCB_0  @S9S_MB_2U_LIB.S9S_MB_2U(SCH_1):JTAG_TRC_PCH_PTI<4>
  BE30  JTAG_TRC_PCH_PTI<3>  GPPC_B_4_GSXCLK  @S9S_MB_2U_LIB.S9S_MB_2U(SCH_1):JTAG_TRC_PCH_PTI<3>
  BD31  JTAG_TRC_PCH_PTI<2>  GPPC_B_3_GSXRESET_N  @S9S_MB_2U_LIB.S9S_MB_2U(SCH_1):JTAG_TRC_PCH_PTI<2>
  BF33  JTAG_TRC_PCH_PTI<1>  GPPC_B_2_GSXDIN  @S9S_MB_2U_LIB.S9S_MB_2U(SCH_1):JTAG_TRC_PCH_PTI<1>
  BE22  JTAG_TRC_PCH_PTI<15>  GPPC_B_22  @S9S_MB_2U_LIB.S9S_MB_2U(SCH_1):JTAG_TRC_PCH_PTI<15>
  BF23  JTAG_TRC_PCH_PTI<14>  GPPC_B_21  @S9S_MB_2U_LIB.S9S_MB_2U(SCH_1):JTAG_TRC_PCH_PTI<14>
  BE24  JTAG_TRC_PCH_PTI<13>  GPPC_B_20  @S9S_MB_2U_LIB.S9S_MB_2U(SCH_1):JTAG_TRC_PCH_PTI<13>
  BF25  JTAG_TRC_PCH_PTI<12>  GPPC_B_19_HS_UART1_CTS_N  @S9S_MB_2U_LIB.S9S_MB_2U(SCH_1):JTAG_TRC_PCH_PTI<12>
  BD25  JTAG_TRC_PCH_PTI<11>  GPPC_B_18_HS_UART1_RTS_N  @S9S_MB_2U_LIB.S9S_MB_2U(SCH_1):JTAG_TRC_PCH_PTI<11>
  BF27  JTAG_TRC_PCH_PTI<10>  GPPC_B_17_HS_UART1_TXD  @S9S_MB_2U_LIB.S9S_MB_2U(SCH_1):JTAG_TRC_PCH_PTI<10>
  BE32  JTAG_TRC_PCH_PTI<0>  GPPC_B_1_GSXSLOAD  @S9S_MB_2U_LIB.S9S_MB_2U(SCH_1):JTAG_TRC_PCH_PTI<0>
  BD23  JTAG_TRC_PCH_PTI1_CLK  GPPC_B_23  @S9S_MB_2U_LIB.S9S_MB_2U(SCH_1):JTAG_TRC_PCH_PTI1_CLK
  BD33  JTAG_TRC_PCH_PTI0_CLK  GPPC_B_0_GSXDOUT  @S9S_MB_2U_LIB.S9S_MB_2U(SCH_1):JTAG_TRC_PCH_PTI0_CLK
  AR4  IRQ_SML1_PMBUS_ALERT_N  GPPC_C_8_ME_SML1ALERT_N  @S9S_MB_2U_LIB.S9S_MB_2U(SCH_1):IRQ_SML1_PMBUS_ALERT_N
  AU2  IRQ_SML0_ALERT_N  GPPC_C_2_ME_SML0ALERT_N  @S9S_MB_2U_LIB.S9S_MB_2U(SCH_1):IRQ_SML0_ALERT_N
  AB2  IRQ_PCH_SCI_WHEA_N  GPP_D_10_BM_BUSY_N_SX_EXIT_HOLDOFF_N  @S9S_MB_2U_LIB.S9S_MB_2U(SCH_1):IRQ_PCH_SCI_WHEA_N
  BE16  IRQ_LPC_SERIRQ_ESPI_CS1_N  GPPC_A_7_ESPI_CS1_N  @S9S_MB_2U_LIB.S9S_MB_2U(SCH_1):IRQ_LPC_SERIRQ_ESPI_CS1_N
  BG20  IRQ_LPC_PIRQA_N_ESPI_ALERT0_N  GPPC_A_0_ESPI_ALERT0_N  @S9S_MB_2U_LIB.S9S_MB_2U(SCH_1):IRQ_LPC_PIRQA_N_ESPI_ALERT0_N
  BF13  IRQ_BMC_PCH_NMI  GPPC_A_17_SRCCLKREQ_N_7  @S9S_MB_2U_LIB.S9S_MB_2U(SCH_1):IRQ_BMC_PCH_NMI
  AW2  FM_THROTTLE_N  GPPC_C_14_ME_SML3ALERT_N  @S9S_MB_2U_LIB.S9S_MB_2U(SCH_1):FM_THROTTLE_N
  AV3  FM_PMBUS_ALERT_B_EN  GPPC_C_11_ME_SML2ALERT_N  @S9S_MB_2U_LIB.S9S_MB_2U(SCH_1):FM_PMBUS_ALERT_B_EN
   Y2  FM_PLT_BMC_THERMTRIP_R_N  GPP_D_17_THERMTRIP_N  @S9S_MB_2U_LIB.S9S_MB_2U(SCH_1):FM_PLT_BMC_THERMTRIP_R_N
  BD11  FM_PCH_SATA_RAID_KEY  GPPC_A_16_SRCCLKREQ_N_6  @S9S_MB_2U_LIB.S9S_MB_2U(SCH_1):FM_PCH_SATA_RAID_KEY
  AA1  FM_PCH_GLB_RST_WARN_N  GPP_D_21_GLB_RST_WARN_N  @S9S_MB_2U_LIB.S9S_MB_2U(SCH_1):FM_PCH_GLB_RST_WARN_N
  AE3  FM_PCH_CRASHLOG_TRIG_N  GPP_D_8_CRASHLOG_TRIG_N  @S9S_MB_2U_LIB.S9S_MB_2U(SCH_1):FM_PCH_CRASHLOG_TRIG_N
   W1  FM_PCH_BOOT_BIOS_STRAP  GPP_D_23  @S9S_MB_2U_LIB.S9S_MB_2U(SCH_1):FM_PCH_BOOT_BIOS_STRAP
  AH2  FM_PCHHOT_N    GPP_D_12_PCHHOT_N  @S9S_MB_2U_LIB.S9S_MB_2U(SCH_1):FM_PCHHOT_N
  AJ1  FM_FLASH_SECURITY_STRAP  GPP_D_6  @S9S_MB_2U_LIB.S9S_MB_2U(SCH_1):FM_FLASH_SECURITY_STRAP
  AG1  FM_ESPI_FLASH_MODE  GPP_D_7  @S9S_MB_2U_LIB.S9S_MB_2U(SCH_1):FM_ESPI_FLASH_MODE
  AF4  FM_CPU_RMCA_CATERR_DLY_N  GPP_D_18_MEMTRIP_N  @S9S_MB_2U_LIB.S9S_MB_2U(SCH_1):FM_CPU_RMCA_CATERR_DLY_N
  AL3  FM_BIOS_POST_CMPLT_N  GPPC_C_17_ME_SML4ALERT_N  @S9S_MB_2U_LIB.S9S_MB_2U(SCH_1):FM_BIOS_POST_CMPLT_N
   Y4  FM_BIOS_IMAGE_SWAP_N  GPP_D_19_MSMI_N  @S9S_MB_2U_LIB.S9S_MB_2U(SCH_1):FM_BIOS_IMAGE_SWAP_N
  AA3  FM_BIOS_DEBUG_EN_R_N  GPP_D_22_USB2_OCB_7  @S9S_MB_2U_LIB.S9S_MB_2U(SCH_1):FM_BIOS_DEBUG_EN_R_N
  AH4  FM_ADR_TRIGGER_R_N  GPP_D_14_ADR_TRIGGER_N  @S9S_MB_2U_LIB.S9S_MB_2U(SCH_1):FM_ADR_TRIGGER_R_N
  AL5  FM_ADR_MODE1   GPPC_C_18  @S9S_MB_2U_LIB.S9S_MB_2U(SCH_1):FM_ADR_MODE1
  AC1  FM_ADR_COMPLETE  GPP_D_13_ADR_COMPLETE  @S9S_MB_2U_LIB.S9S_MB_2U(SCH_1):FM_ADR_COMPLETE
  AD4  FM_ADR_ACK     GPP_D_16_ADR_ACK  @S9S_MB_2U_LIB.S9S_MB_2U(SCH_1):FM_ADR_ACK
  BE20  ESPI_LFRAME_N_BMC_CS0_N  GPPC_A_6_ESPI_CS0_N  @S9S_MB_2U_LIB.S9S_MB_2U(SCH_1):ESPI_LFRAME_N_BMC_CS0_N
  BD19  ESPI_LAD0_DATA_IO3  GPPC_A_5_ESPI_IO_3  @S9S_MB_2U_LIB.S9S_MB_2U(SCH_1):ESPI_LAD0_DATA_IO3
  BE18  ESPI_LAD0_DATA_IO2  GPPC_A_4_ESPI_IO_2  @S9S_MB_2U_LIB.S9S_MB_2U(SCH_1):ESPI_LAD0_DATA_IO2
  BF19  ESPI_LAD0_DATA_IO1  GPPC_A_3_ESPI_IO_1  @S9S_MB_2U_LIB.S9S_MB_2U(SCH_1):ESPI_LAD0_DATA_IO1
  BG12  ESPI_LAD0_DATA_IO0  GPPC_A_2_ESPI_IO_0  @S9S_MB_2U_LIB.S9S_MB_2U(SCH_1):ESPI_LAD0_DATA_IO0
  BD15  ESPI_ALERT1_N_LPC_RCIN_N  GPPC_A_1_ESPI_ALERT1_N  @S9S_MB_2U_LIB.S9S_MB_2U(SCH_1):ESPI_ALERT1_N_LPC_RCIN_N
  BD13  CLK_24M_66M_LPC0_ESPI  GPPC_A_9_ESPI_CLK  @S9S_MB_2U_LIB.S9S_MB_2U(SCH_1):CLK_24M_66M_LPC0_ESPI

EMMITSBURG_REV0P9  I36  U4     [EMMITSBURG_REV0P9-GFNOCPU04302A]
  AK8  NC             SLP_LAN_N  NC
   M8  NC             PLTRST_CPU_N  NC
  AJ13  NC             SLP_S5_N  NC
  AM11  NC             SLP_A_N  NC
  AJ7  NC             LANPHYPC  NC
  F11  NC             CPU_MSMI_N  NC
   E4  NC             CPU_MEMTRIP_N  NC
  BD9  RST_RSMRST_PCH_N  RSMRST_N  @S9S_MB_2U_LIB.S9S_MB_2U(SCH_1):RST_RSMRST_PCH_N
  AJ10  RST_PCH_RSTBTN_R_N  SYS_RESET_N  @S9S_MB_2U_LIB.S9S_MB_2U(SCH_1):RST_PCH_RSTBTN_R_N
  AL10  PWRGD_SYS_PWROK  SYS_PWROK  @S9S_MB_2U_LIB.S9S_MB_2U(SCH_1):PWRGD_SYS_PWROK
  BE4  PWRGD_PCH_PWROK  PCH_PWROK  @S9S_MB_2U_LIB.S9S_MB_2U(SCH_1):PWRGD_PCH_PWROK
  BE8  PWRGD_DSW_PWROK  DSW_PWROK  @S9S_MB_2U_LIB.S9S_MB_2U(SCH_1):PWRGD_DSW_PWROK
  G10  PWRGD_CPUPWRGD_GTL  CPUPWRGD  @S9S_MB_2U_LIB.S9S_MB_2U(SCH_1):PWRGD_CPUPWRGD_GTL
  AU7  PU_LAN_WAKE_N  LAN_WAKE_N  @S9S_MB_2U_LIB.S9S_MB_2U(SCH_1):PU_LAN_WAKE_N
  AN7  PU_ACPRESENT   ACPRESENT  @S9S_MB_2U_LIB.S9S_MB_2U(SCH_1):PU_ACPRESENT
  J10  PECI_PCH       ME_PECI  @S9S_MB_2U_LIB.S9S_MB_2U(SCH_1):PECI_PCH
  AR7  PD_SUSCLK      SUSCLK  @S9S_MB_2U_LIB.S9S_MB_2U(SCH_1):PD_SUSCLK
  BF39  NC             RSVD_BF39  NC
  AV21  NC             RSVD_AV21  NC
  AW26  NC             RSVD_AW23  NC
  BG36  NC             RSVD_BG36  NC
  BD37  JTAG_DBP_TMS_PCH  JTAG_TMS  @S9S_MB_2U_LIB.S9S_MB_2U(SCH_1):JTAG_DBP_TMS_PCH
  BE36  JTAG_DBP_TDO_PCH  JTAG_TDO  @S9S_MB_2U_LIB.S9S_MB_2U(SCH_1):JTAG_DBP_TDO_PCH
  BE38  JTAG_DBP_TDI_PCH  JTAG_TDI  @S9S_MB_2U_LIB.S9S_MB_2U(SCH_1):JTAG_DBP_TDI_PCH
  BF35  JTAG_DBP_TCK_PCH  JTAG_TCK  @S9S_MB_2U_LIB.S9S_MB_2U(SCH_1):JTAG_DBP_TCK_PCH
  BE40  JTAG_DBP_PMODE  DBG_PMODE  @S9S_MB_2U_LIB.S9S_MB_2U(SCH_1):JTAG_DBP_PMODE
  BD35  JTAG_DBP_CPU_GTL_TCK  JTAGX  @S9S_MB_2U_LIB.S9S_MB_2U(SCH_1):JTAG_DBP_CPU_GTL_TCK
  AH11  IRQ_LVC3_WAKE_N  WAKE_N  @S9S_MB_2U_LIB.S9S_MB_2U(SCH_1):IRQ_LVC3_WAKE_N
   F3  H_THERMTRIP_LVC1_N  CPU_THRMTRIP_N  @S9S_MB_2U_LIB.S9S_MB_2U(SCH_1):H_THERMTRIP_LVC1_N
  BF37  H_DBP_PREQ_N_PCH  PREQ_N  @S9S_MB_2U_LIB.S9S_MB_2U(SCH_1):H_DBP_PREQ_N_PCH
  BB37  H_DBP_PRDY_N_PCH  PRDY_N  @S9S_MB_2U_LIB.S9S_MB_2U(SCH_1):H_DBP_PRDY_N_PCH
   L7  H_CPU_ERR2_PCH_R_N  CPU_ERR2_N  @S9S_MB_2U_LIB.S9S_MB_2U(SCH_1):H_CPU_ERR2_PCH_R_N
   G7  H_CPU_ERR1_PCH_R_N  CPU_ERR1_N  @S9S_MB_2U_LIB.S9S_MB_2U(SCH_1):H_CPU_ERR1_PCH_R_N
   J7  H_CPU_ERR0_PCH_R_N  CPU_ERR0_N  @S9S_MB_2U_LIB.S9S_MB_2U(SCH_1):H_CPU_ERR0_PCH_R_N
   F8  FM_PCIE_EV_BIF_EN  CPU_CATERR_N  @S9S_MB_2U_LIB.S9S_MB_2U(SCH_1):FM_PCIE_EV_BIF_EN
   K8  FM_PCH_TRIGGER1_R_N  TRIGGER1_N  @S9S_MB_2U_LIB.S9S_MB_2U(SCH_1):FM_PCH_TRIGGER1_R_N
  H11  FM_PCH_TRIGGER0_R_N  TRIGGER0_N  @S9S_MB_2U_LIB.S9S_MB_2U(SCH_1):FM_PCH_TRIGGER0_R_N
  AN10  FM_PCH_SPARE0  GPP_O_0  @S9S_MB_2U_LIB.S9S_MB_2U(SCH_1):FM_PCH_SPARE0
  AL7  FM_PCH_SLP_SUS_N  SLP_SUS_N  @S9S_MB_2U_LIB.S9S_MB_2U(SCH_1):FM_PCH_SLP_SUS_N
  AL13  FM_PCH_SLP_S4_N  SLP_S4_N  @S9S_MB_2U_LIB.S9S_MB_2U(SCH_1):FM_PCH_SLP_S4_N
  AP8  FM_PCH_SLP_S3_N  SLP_S3_N  @S9S_MB_2U_LIB.S9S_MB_2U(SCH_1):FM_PCH_SLP_S3_N
  AU10  FM_PCH_SKIP_RTC_CLOCK  GPP_O_7  @S9S_MB_2U_LIB.S9S_MB_2U(SCH_1):FM_PCH_SKIP_RTC_CLOCK
   F5  FM_PCH_CPU_PWR_DEBUG_N  CPU_PWR_DEBUG_N  @S9S_MB_2U_LIB.S9S_MB_2U(SCH_1):FM_PCH_CPU_PWR_DEBUG_N
  BG8  FM_INTRUDER_HDR_PCH_N  INTRUDER_N  @S9S_MB_2U_LIB.S9S_MB_2U(SCH_1):FM_INTRUDER_HDR_PCH_N
  AR10  FM_BMC_PWRBTN_N  PWRBTN_N  @S9S_MB_2U_LIB.S9S_MB_2U(SCH_1):FM_BMC_PWRBTN_N

EMMITSBURG_REV0P9  I119  U4     [EMMITSBURG_REV0P9-GFNOCPU04302A]
  AG32  USB3_9_TX_DP   SATA_9_PCIE3_9_USB3_9_TXP  @S9S_MB_2U_LIB.S9S_MB_2U(SCH_1):USB3_9_TX_DP
  AE32  USB3_9_TX_DN   SATA_9_PCIE3_9_USB3_9_TXN  @S9S_MB_2U_LIB.S9S_MB_2U(SCH_1):USB3_9_TX_DN
  R42  USB3_9_RX_DP   SATA_9_PCIE3_9_USB3_9_RXP  @S9S_MB_2U_LIB.S9S_MB_2U(SCH_1):USB3_9_RX_DP
  R40  USB3_9_RX_DN   SATA_9_PCIE3_9_USB3_9_RXN  @S9S_MB_2U_LIB.S9S_MB_2U(SCH_1):USB3_9_RX_DN
  AD37  NC             SATA_8_PCIE3_8_USB3_8_TXP  NC
  AE36  NC             SATA_8_PCIE3_8_USB3_8_TXN  NC
  U43  NC             SATA_8_PCIE3_8_USB3_8_RXP  NC
  U41  NC             SATA_8_PCIE3_8_USB3_8_RXN  NC
  AG36  NC             SATA_7_PCIE3_7_USB3_7_TXP  NC
  AH37  NC             SATA_6_PCIE3_6_USB3_6_TXP  NC
  AJ32  NC             SATA_5_PCIE3_5_USB3_5_TXP  NC
  AF34  NC             SATA_7_PCIE3_7_USB3_7_TXN  NC
  AF37  NC             SATA_6_PCIE3_6_USB3_6_TXN  NC
  AH34  NC             SATA_5_PCIE3_5_USB3_5_TXN  NC
  V42  NC             SATA_7_PCIE3_7_USB3_7_RXP  NC
  W43  NC             SATA_6_PCIE3_6_USB3_6_RXP  NC
  Y42  NC             SATA_5_PCIE3_5_USB3_5_RXP  NC
  V40  NC             SATA_7_PCIE3_7_USB3_7_RXN  NC
  W41  NC             SATA_6_PCIE3_6_USB3_6_RXN  NC
  Y40  NC             SATA_5_PCIE3_5_USB3_5_RXN  NC
  N36  NC             SATA_15_PCIE3_15_TXP  NC
  P34  NC             SATA_15_PCIE3_15_TXN  NC
  G42  NC             SATA_15_PCIE3_15_RXP  NC
  G40  NC             SATA_15_PCIE3_15_RXN  NC
  T34  NC             SATA_14_PCIE3_14_GBE_2_TXP  NC
  R32  NC             SATA_14_PCIE3_14_GBE_2_TXN  NC
  H43  NC             SATA_14_PCIE3_14_GBE_2_RXP  NC
  H41  NC             SATA_14_PCIE3_14_GBE_2_RXN  NC
  W32  NC             SATA_13_PCIE3_13_TXP  NC
  U32  NC             SATA_13_PCIE3_13_TXN  NC
  J42  NC             SATA_13_PCIE3_13_RXP  NC
  J40  NC             SATA_13_PCIE3_13_RXN  NC
  U36  NC             SATA_12_PCIE3_12_GBE_1_TXP  NC
  V34  NC             SATA_12_PCIE3_12_GBE_1_TXN  NC
  K43  NC             SATA_12_PCIE3_12_GBE_1_RXP  NC
  K41  NC             SATA_12_PCIE3_12_GBE_1_RXN  NC
  V37  SATA_P11_TX_DP  SATA_11_PCIE3_11_TXP  @S9S_MB_2U_LIB.S9S_MB_2U(SCH_1):SATA_P11_TX_DP
  T37  SATA_P11_TX_DN  SATA_11_PCIE3_11_TXN  @S9S_MB_2U_LIB.S9S_MB_2U(SCH_1):SATA_P11_TX_DN
  L42  SATA_P11_RX_DP  SATA_11_PCIE3_11_RXP  @S9S_MB_2U_LIB.S9S_MB_2U(SCH_1):SATA_P11_RX_DP
  L40  SATA_P11_RX_DN  SATA_11_PCIE3_11_RXN  @S9S_MB_2U_LIB.S9S_MB_2U(SCH_1):SATA_P11_RX_DN
  AR29  PCH_PCIEUP_RCOMPP  PHY_PCIE3_RCOMPP  @S9S_MB_2U_LIB.S9S_MB_2U(SCH_1):PCH_PCIEUP_RCOMPP
  AP31  PCH_PCIEUP_RCOMPN  PHY_PCIE3_RCOMPN  @S9S_MB_2U_LIB.S9S_MB_2U(SCH_1):PCH_PCIEUP_RCOMPN
  AM37  P3E_PCH_M2_TX_DP<4>  SATA_4_PCIE3_4_USB3_4_TXP  @S9S_MB_2U_LIB.S9S_MB_2U(SCH_1):P3E_PCH_M2_TX_DP<4>
  AM34  P3E_PCH_M2_TX_DP<3>  SATA_3_PCIE3_3_USB3_3_TXP  @S9S_MB_2U_LIB.S9S_MB_2U(SCH_1):P3E_PCH_M2_TX_DP<3>
  AT37  P3E_PCH_M2_TX_DP<2>  SATA_2_PCIE3_2_USB3_2_TXP  @S9S_MB_2U_LIB.S9S_MB_2U(SCH_1):P3E_PCH_M2_TX_DP<2>
  AP34  P3E_PCH_M2_TX_DP<1>  SATA_1_PCIE3_1_USB3_1_TXP  @S9S_MB_2U_LIB.S9S_MB_2U(SCH_1):P3E_PCH_M2_TX_DP<1>
  AK31  P3E_PCH_M2_TX_DP<0>  SATA_0_PCIE3_0_USB3_0_TXP  @S9S_MB_2U_LIB.S9S_MB_2U(SCH_1):P3E_PCH_M2_TX_DP<0>
  AL36  P3E_PCH_M2_TX_DN<4>  SATA_4_PCIE3_4_USB3_4_TXN  @S9S_MB_2U_LIB.S9S_MB_2U(SCH_1):P3E_PCH_M2_TX_DN<4>
  AK34  P3E_PCH_M2_TX_DN<3>  SATA_3_PCIE3_3_USB3_3_TXN  @S9S_MB_2U_LIB.S9S_MB_2U(SCH_1):P3E_PCH_M2_TX_DN<3>
  AR36  P3E_PCH_M2_TX_DN<2>  SATA_2_PCIE3_2_USB3_2_TXN  @S9S_MB_2U_LIB.S9S_MB_2U(SCH_1):P3E_PCH_M2_TX_DN<2>
  AN36  P3E_PCH_M2_TX_DN<1>  SATA_1_PCIE3_1_USB3_1_TXN  @S9S_MB_2U_LIB.S9S_MB_2U(SCH_1):P3E_PCH_M2_TX_DN<1>
  AL32  P3E_PCH_M2_TX_DN<0>  SATA_0_PCIE3_0_USB3_0_TXN  @S9S_MB_2U_LIB.S9S_MB_2U(SCH_1):P3E_PCH_M2_TX_DN<0>
  AA43  P3E_PCH_M2_RX_DP<4>  SATA_4_PCIE3_4_USB3_4_RXP  @S9S_MB_2U_LIB.S9S_MB_2U(SCH_1):P3E_PCH_M2_RX_DP<4>
  AB42  P3E_PCH_M2_RX_DP<3>  SATA_3_PCIE3_3_USB3_3_RXP  @S9S_MB_2U_LIB.S9S_MB_2U(SCH_1):P3E_PCH_M2_RX_DP<3>
  AC43  P3E_PCH_M2_RX_DP<2>  SATA_2_PCIE3_2_USB3_2_RXP  @S9S_MB_2U_LIB.S9S_MB_2U(SCH_1):P3E_PCH_M2_RX_DP<2>
  AD42  P3E_PCH_M2_RX_DP<1>  SATA_1_PCIE3_1_USB3_1_RXP  @S9S_MB_2U_LIB.S9S_MB_2U(SCH_1):P3E_PCH_M2_RX_DP<1>
  AE43  P3E_PCH_M2_RX_DP<0>  SATA_0_PCIE3_0_USB3_0_RXP  @S9S_MB_2U_LIB.S9S_MB_2U(SCH_1):P3E_PCH_M2_RX_DP<0>
  AA41  P3E_PCH_M2_RX_DN<4>  SATA_4_PCIE3_4_USB3_4_RXN  @S9S_MB_2U_LIB.S9S_MB_2U(SCH_1):P3E_PCH_M2_RX_DN<4>
  AB40  P3E_PCH_M2_RX_DN<3>  SATA_3_PCIE3_3_USB3_3_RXN  @S9S_MB_2U_LIB.S9S_MB_2U(SCH_1):P3E_PCH_M2_RX_DN<3>
  AC41  P3E_PCH_M2_RX_DN<2>  SATA_2_PCIE3_2_USB3_2_RXN  @S9S_MB_2U_LIB.S9S_MB_2U(SCH_1):P3E_PCH_M2_RX_DN<2>
  AD40  P3E_PCH_M2_RX_DN<1>  SATA_1_PCIE3_1_USB3_1_RXN  @S9S_MB_2U_LIB.S9S_MB_2U(SCH_1):P3E_PCH_M2_RX_DN<1>
  AE41  P3E_PCH_M2_RX_DN<0>  SATA_0_PCIE3_0_USB3_0_RXN  @S9S_MB_2U_LIB.S9S_MB_2U(SCH_1):P3E_PCH_M2_RX_DN<0>
  Y37  P3E_PCH_BMC_TX_DP  SATA_10_PCIE3_10_GBE_0_TXP  @S9S_MB_2U_LIB.S9S_MB_2U(SCH_1):P3E_PCH_BMC_TX_DP
  W36  P3E_PCH_BMC_TX_DN  SATA_10_PCIE3_10_GBE_0_TXN  @S9S_MB_2U_LIB.S9S_MB_2U(SCH_1):P3E_PCH_BMC_TX_DN
  M43  P3E_PCH_BMC_RX_DP  SATA_10_PCIE3_10_GBE_0_RXP  @S9S_MB_2U_LIB.S9S_MB_2U(SCH_1):P3E_PCH_BMC_RX_DP
  M41  P3E_PCH_BMC_RX_DN  SATA_10_PCIE3_10_GBE_0_RXN  @S9S_MB_2U_LIB.S9S_MB_2U(SCH_1):P3E_PCH_BMC_RX_DN
  D39  NC             RSVD_D39  NC
  C40  NC             RSVD_C40  NC
  N42  NC             RSVD_N42  NC
  N40  NC             RSVD_N40  NC
  D37  DMI_CPU0_PCH_TX_C_DP<7>  DMI_7_SATA_16_PCIE3_16_RXP  @S9S_MB_2U_LIB.S9S_MB_2U(SCH_1):DMI_CPU0_PCH_TX_C_DP<7>
  C36  DMI_CPU0_PCH_TX_C_DP<6>  DMI_6_SATA_17_PCIE3_17_RXP  @S9S_MB_2U_LIB.S9S_MB_2U(SCH_1):DMI_CPU0_PCH_TX_C_DP<6>
  D35  DMI_CPU0_PCH_TX_C_DP<5>  DMI_5_SATA_18_PCIE3_18_RXP  @S9S_MB_2U_LIB.S9S_MB_2U(SCH_1):DMI_CPU0_PCH_TX_C_DP<5>
  C34  DMI_CPU0_PCH_TX_C_DP<4>  DMI_4_SATA_19_PCIE3_19_RXP  @S9S_MB_2U_LIB.S9S_MB_2U(SCH_1):DMI_CPU0_PCH_TX_C_DP<4>
  D33  DMI_CPU0_PCH_TX_C_DP<3>  DMI_3_RXP  @S9S_MB_2U_LIB.S9S_MB_2U(SCH_1):DMI_CPU0_PCH_TX_C_DP<3>
  C32  DMI_CPU0_PCH_TX_C_DP<2>  DMI_2_RXP  @S9S_MB_2U_LIB.S9S_MB_2U(SCH_1):DMI_CPU0_PCH_TX_C_DP<2>
  D31  DMI_CPU0_PCH_TX_C_DP<1>  DMI_1_RXP  @S9S_MB_2U_LIB.S9S_MB_2U(SCH_1):DMI_CPU0_PCH_TX_C_DP<1>
  C30  DMI_CPU0_PCH_TX_C_DP<0>  DMI_0_RXP  @S9S_MB_2U_LIB.S9S_MB_2U(SCH_1):DMI_CPU0_PCH_TX_C_DP<0>
  B37  DMI_CPU0_PCH_TX_C_DN<7>  DMI_7_SATA_16_PCIE3_16_RXN  @S9S_MB_2U_LIB.S9S_MB_2U(SCH_1):DMI_CPU0_PCH_TX_C_DN<7>
  A36  DMI_CPU0_PCH_TX_C_DN<6>  DMI_6_SATA_17_PCIE3_17_RXN  @S9S_MB_2U_LIB.S9S_MB_2U(SCH_1):DMI_CPU0_PCH_TX_C_DN<6>
  B35  DMI_CPU0_PCH_TX_C_DN<5>  DMI_5_SATA_18_PCIE3_18_RXN  @S9S_MB_2U_LIB.S9S_MB_2U(SCH_1):DMI_CPU0_PCH_TX_C_DN<5>
  A34  DMI_CPU0_PCH_TX_C_DN<4>  DMI_4_SATA_19_PCIE3_19_RXN  @S9S_MB_2U_LIB.S9S_MB_2U(SCH_1):DMI_CPU0_PCH_TX_C_DN<4>
  B33  DMI_CPU0_PCH_TX_C_DN<3>  DMI_3_RXN  @S9S_MB_2U_LIB.S9S_MB_2U(SCH_1):DMI_CPU0_PCH_TX_C_DN<3>
  A32  DMI_CPU0_PCH_TX_C_DN<2>  DMI_2_RXN  @S9S_MB_2U_LIB.S9S_MB_2U(SCH_1):DMI_CPU0_PCH_TX_C_DN<2>
  B31  DMI_CPU0_PCH_TX_C_DN<1>  DMI_1_RXN  @S9S_MB_2U_LIB.S9S_MB_2U(SCH_1):DMI_CPU0_PCH_TX_C_DN<1>
  A30  DMI_CPU0_PCH_TX_C_DN<0>  DMI_0_RXN  @S9S_MB_2U_LIB.S9S_MB_2U(SCH_1):DMI_CPU0_PCH_TX_C_DN<0>
  H37  DMI_CPU0_PCH_RX_DP<7>  DMI_7_SATA_16_PCIE3_16_TXP  @S9S_MB_2U_LIB.S9S_MB_2U(SCH_1):DMI_CPU0_PCH_RX_DP<7>
  J36  DMI_CPU0_PCH_RX_DP<6>  DMI_6_SATA_17_PCIE3_17_TXP  @S9S_MB_2U_LIB.S9S_MB_2U(SCH_1):DMI_CPU0_PCH_RX_DP<6>
  H34  DMI_CPU0_PCH_RX_DP<5>  DMI_5_SATA_18_PCIE3_18_TXP  @S9S_MB_2U_LIB.S9S_MB_2U(SCH_1):DMI_CPU0_PCH_RX_DP<5>
  G32  DMI_CPU0_PCH_RX_DP<4>  DMI_4_SATA_19_PCIE3_19_TXP  @S9S_MB_2U_LIB.S9S_MB_2U(SCH_1):DMI_CPU0_PCH_RX_DP<4>
  K31  DMI_CPU0_PCH_RX_DP<3>  DMI_3_TXP  @S9S_MB_2U_LIB.S9S_MB_2U(SCH_1):DMI_CPU0_PCH_RX_DP<3>
  H31  DMI_CPU0_PCH_RX_DP<2>  DMI_2_TXP  @S9S_MB_2U_LIB.S9S_MB_2U(SCH_1):DMI_CPU0_PCH_RX_DP<2>
  F28  DMI_CPU0_PCH_RX_DP<1>  DMI_1_TXP  @S9S_MB_2U_LIB.S9S_MB_2U(SCH_1):DMI_CPU0_PCH_RX_DP<1>
  H28  DMI_CPU0_PCH_RX_DP<0>  DMI_0_TXP  @S9S_MB_2U_LIB.S9S_MB_2U(SCH_1):DMI_CPU0_PCH_RX_DP<0>
  F37  DMI_CPU0_PCH_RX_DN<7>  DMI_7_SATA_16_PCIE3_16_TXN  @S9S_MB_2U_LIB.S9S_MB_2U(SCH_1):DMI_CPU0_PCH_RX_DN<7>
  K37  DMI_CPU0_PCH_RX_DN<6>  DMI_6_SATA_17_PCIE3_17_TXN  @S9S_MB_2U_LIB.S9S_MB_2U(SCH_1):DMI_CPU0_PCH_RX_DN<6>
  G36  DMI_CPU0_PCH_RX_DN<5>  DMI_5_SATA_18_PCIE3_18_TXN  @S9S_MB_2U_LIB.S9S_MB_2U(SCH_1):DMI_CPU0_PCH_RX_DN<5>
  J32  DMI_CPU0_PCH_RX_DN<4>  DMI_4_SATA_19_PCIE3_19_TXN  @S9S_MB_2U_LIB.S9S_MB_2U(SCH_1):DMI_CPU0_PCH_RX_DN<4>
  L32  DMI_CPU0_PCH_RX_DN<3>  DMI_3_TXN  @S9S_MB_2U_LIB.S9S_MB_2U(SCH_1):DMI_CPU0_PCH_RX_DN<3>
  J29  DMI_CPU0_PCH_RX_DN<2>  DMI_2_TXN  @S9S_MB_2U_LIB.S9S_MB_2U(SCH_1):DMI_CPU0_PCH_RX_DN<2>
  G29  DMI_CPU0_PCH_RX_DN<1>  DMI_1_TXN  @S9S_MB_2U_LIB.S9S_MB_2U(SCH_1):DMI_CPU0_PCH_RX_DN<1>
  K28  DMI_CPU0_PCH_RX_DN<0>  DMI_0_TXN  @S9S_MB_2U_LIB.S9S_MB_2U(SCH_1):DMI_CPU0_PCH_RX_DN<0>

EMMITSBURG_REV0P9  I11  U4     [EMMITSBURG_REV0P9-GFNOCPU04302A]
  AJ41  USB2_9_DP      USB2P_9  @S9S_MB_2U_LIB.S9S_MB_2U(SCH_1):USB2_9_DP
  AJ43  USB2_9_DN      USB2N_9  @S9S_MB_2U_LIB.S9S_MB_2U(SCH_1):USB2_9_DN
  AW40  USB2_8_DP      USB2P_8  @S9S_MB_2U_LIB.S9S_MB_2U(SCH_1):USB2_8_DP
  AW42  USB2_8_DN      USB2N_8  @S9S_MB_2U_LIB.S9S_MB_2U(SCH_1):USB2_8_DN
  AL41  USB2_5_DP      USB2P_5  @S9S_MB_2U_LIB.S9S_MB_2U(SCH_1):USB2_5_DP
  AL43  USB2_5_DN      USB2N_5  @S9S_MB_2U_LIB.S9S_MB_2U(SCH_1):USB2_5_DN
  AU40  USB2_4_DP      USB2P_4  @S9S_MB_2U_LIB.S9S_MB_2U(SCH_1):USB2_4_DP
  AU42  USB2_4_DN      USB2N_4  @S9S_MB_2U_LIB.S9S_MB_2U(SCH_1):USB2_4_DN
  AN40  USB2_3_DP      USB2P_3  @S9S_MB_2U_LIB.S9S_MB_2U(SCH_1):USB2_3_DP
  AN42  USB2_3_DN      USB2N_3  @S9S_MB_2U_LIB.S9S_MB_2U(SCH_1):USB2_3_DN
  AP41  USB2_1_DP      USB2P_1  @S9S_MB_2U_LIB.S9S_MB_2U(SCH_1):USB2_1_DP
  AP43  USB2_1_DN      USB2N_1  @S9S_MB_2U_LIB.S9S_MB_2U(SCH_1):USB2_1_DN
  AR40  USB2_0_DP      USB2P_0  @S9S_MB_2U_LIB.S9S_MB_2U(SCH_1):USB2_0_DP
  AR42  USB2_0_DN      USB2N_0  @S9S_MB_2U_LIB.S9S_MB_2U(SCH_1):USB2_0_DN
  AK40  NC             USB2P_7  NC
  AK42  NC             USB2N_7  NC
  AV41  NC             USB2P_6  NC
  AV43  NC             USB2N_6  NC
  AT41  NC             USB2P_2  NC
  AT43  NC             USB2N_2  NC
  AG41  NC             USB2P_13  NC
  AG43  NC             USB2N_13  NC
  BA40  NC             USB2P_12  NC
  BA42  NC             USB2N_12  NC
  AH40  NC             USB2P_11  NC
  AH42  NC             USB2N_11  NC
  AY41  NC             USB2P_10  NC
  AY43  NC             USB2N_10  NC
  BB41  PD_PCH_USB2_COMP  USB2_COMP  @S9S_MB_2U_LIB.S9S_MB_2U(SCH_1):PD_PCH_USB2_COMP
  BC40  NC             RSVD_BC40  NC

EMMITSBURG_REV0P9  I78  U4     [EMMITSBURG_REV0P9-GFNOCPU04302A]
  BF7  XTAL_PCH_RTC2  RTCX2  @S9S_MB_2U_LIB.S9S_MB_2U(SCH_1):XTAL_PCH_RTC2
  BE6  XTAL_PCH_RTC1  RTCX1  @S9S_MB_2U_LIB.S9S_MB_2U(SCH_1):XTAL_PCH_RTC1
  D23  XTAL_PCH_25M_OUT  XTAL_OUT  @S9S_MB_2U_LIB.S9S_MB_2U(SCH_1):XTAL_PCH_25M_OUT
  B23  XTAL_PCH_25M_IN  XTAL_IN  @S9S_MB_2U_LIB.S9S_MB_2U(SCH_1):XTAL_PCH_25M_IN
  J23  NC             RSVD_J23  NC
  H24  NC             RSVD_H24  NC
  D15  NC             CLKOUT_SRC_P_9  NC
  B15  NC             CLKOUT_SRC_N_9  NC
  H18  NC             CLKOUT_SRC_P_8  NC
  F18  NC             CLKOUT_SRC_N_8  NC
  C14  NC             CLKOUT_SRC_P_7  NC
  A14  NC             CLKOUT_SRC_N_7  NC
  C12  NC             CLKOUT_SRC_P_5  NC
  A12  NC             CLKOUT_SRC_N_5  NC
  D19  NC             CLKOUT_SRC_P_4  NC
  B19  NC             CLKOUT_SRC_N_4  NC
  D17  NC             CLKOUT_SRC_P_3  NC
  B17  NC             CLKOUT_SRC_N_3  NC
  F21  NC             CLKOUT_SRC_P_1  NC
  G23  NC             CLKOUT_SRC_N_1  NC
  C18  NC             CLKOUT_SRC_P_16  NC
  A18  NC             CLKOUT_SRC_N_16  NC
   C6  NC             CLKOUT_SRC_P_15  NC
   B5  NC             CLKOUT_SRC_N_15  NC
   D7  NC             CLKOUT_SRC_P_14  NC
   B7  NC             CLKOUT_SRC_N_14  NC
   C8  NC             CLKOUT_SRC_P_13  NC
   A8  NC             CLKOUT_SRC_N_13  NC
  C10  NC             CLKOUT_SRC_P_12  NC
  A10  NC             CLKOUT_SRC_N_12  NC
  H15  NC             CLKOUT_SRC_P_11  NC
  G16  NC             CLKOUT_SRC_N_11  NC
  K18  NC             CLKOUT_SRC_P_10  NC
  J16  NC             CLKOUT_SRC_N_10  NC
  C16  NC             CLKOUT_SRC_P_0  NC
  A16  NC             CLKOUT_SRC_N_0  NC
  BF5  RTC_EXT_CAP    RTC_EXTCAP  @S9S_MB_2U_LIB.S9S_MB_2U(SCH_1):RTC_EXT_CAP
  N29  PD_PCH_XCLK_BIASREF  XCLK_BIASREF  @S9S_MB_2U_LIB.S9S_MB_2U(SCH_1):PD_PCH_XCLK_BIASREF
  B25  CLK_25M_PCH_REF_NS_DP  REFCLK_INJ_NS_P  @S9S_MB_2U_LIB.S9S_MB_2U(SCH_1):CLK_25M_PCH_REF_NS_DP
  D25  CLK_25M_PCH_REF_NS_DN  REFCLK_INJ_NS_N  @S9S_MB_2U_LIB.S9S_MB_2U(SCH_1):CLK_25M_PCH_REF_NS_DN
  A28  CLK_25M_PCH_CPU1_DP  PMSYNC_CLK_P_1  @S9S_MB_2U_LIB.S9S_MB_2U(SCH_1):CLK_25M_PCH_CPU1_DP
  C28  CLK_25M_PCH_CPU1_DN  PMSYNC_CLK_N_1  @S9S_MB_2U_LIB.S9S_MB_2U(SCH_1):CLK_25M_PCH_CPU1_DN
  B27  CLK_25M_PCH_CPU0_DP  PMSYNC_CLK_P_0  @S9S_MB_2U_LIB.S9S_MB_2U(SCH_1):CLK_25M_PCH_CPU0_DP
  D27  CLK_25M_PCH_CPU0_DN  PMSYNC_CLK_N_0  @S9S_MB_2U_LIB.S9S_MB_2U(SCH_1):CLK_25M_PCH_CPU0_DN
  K21  CLK_100M_PE_M2_0_DP  CLKOUT_SRC_P_2  @S9S_MB_2U_LIB.S9S_MB_2U(SCH_1):CLK_100M_PE_M2_0_DP
  H21  CLK_100M_PE_M2_0_DN  CLKOUT_SRC_N_2  @S9S_MB_2U_LIB.S9S_MB_2U(SCH_1):CLK_100M_PE_M2_0_DN
  B21  CLK_100M_CK440_PCH_EXTCLK_DP  REFCLK_INJ_S_P  @S9S_MB_2U_LIB.S9S_MB_2U(SCH_1):CLK_100M_CK440_PCH_EXTCLK_DP
  D21  CLK_100M_CK440_PCH_EXTCLK_DN  REFCLK_INJ_S_N  @S9S_MB_2U_LIB.S9S_MB_2U(SCH_1):CLK_100M_CK440_PCH_EXTCLK_DN
  D11  CLK_100M_BMC_P3E_DP  CLKOUT_SRC_P_6  @S9S_MB_2U_LIB.S9S_MB_2U(SCH_1):CLK_100M_BMC_P3E_DP
  B11  CLK_100M_BMC_P3E_DN  CLKOUT_SRC_N_6  @S9S_MB_2U_LIB.S9S_MB_2U(SCH_1):CLK_100M_BMC_P3E_DN

PCA9546APWR  I194  U10    [PCA9546APWR-PCA9546APWR,SMLF,IA]
   11  SMB_PCIE1_3V3AUX_SDA_R3    SD3  @S9S_MB_2U_LIB.S9S_MB_2U(SCH_1):SMB_PCIE1_3V3AUX_SDA_R3
    9  SMB_PCIE1_3V3AUX_SDA_R2    SD2  @S9S_MB_2U_LIB.S9S_MB_2U(SCH_1):SMB_PCIE1_3V3AUX_SDA_R2
    6  SMB_PCIE1_3V3AUX_SDA_R1    SD1  @S9S_MB_2U_LIB.S9S_MB_2U(SCH_1):SMB_PCIE1_3V3AUX_SDA_R1
    4  SMB_PCIE1_3V3AUX_SDA_R0    SD0  @S9S_MB_2U_LIB.S9S_MB_2U(SCH_1):SMB_PCIE1_3V3AUX_SDA_R0
   15  SMB_PCIE1_3V3AUX_SDA_R    SDA  @S9S_MB_2U_LIB.S9S_MB_2U(SCH_1):SMB_PCIE1_3V3AUX_SDA_R
   12  SMB_PCIE1_3V3AUX_SCL_R3    SC3  @S9S_MB_2U_LIB.S9S_MB_2U(SCH_1):SMB_PCIE1_3V3AUX_SCL_R3
   10  SMB_PCIE1_3V3AUX_SCL_R2    SC2  @S9S_MB_2U_LIB.S9S_MB_2U(SCH_1):SMB_PCIE1_3V3AUX_SCL_R2
    7  SMB_PCIE1_3V3AUX_SCL_R1    SC1  @S9S_MB_2U_LIB.S9S_MB_2U(SCH_1):SMB_PCIE1_3V3AUX_SCL_R1
    5  SMB_PCIE1_3V3AUX_SCL_R0    SC0  @S9S_MB_2U_LIB.S9S_MB_2U(SCH_1):SMB_PCIE1_3V3AUX_SCL_R0
   14  SMB_PCIE1_3V3AUX_SCL_R    SCL  @S9S_MB_2U_LIB.S9S_MB_2U(SCH_1):SMB_PCIE1_3V3AUX_SCL_R
    3  PU_RST_SMB_PCIE3_N  RESET#  @S9S_MB_2U_LIB.S9S_MB_2U(SCH_1):PU_RST_SMB_PCIE3_N
   13  PCA9546_PCIE1_ADDR2     A2  @S9S_MB_2U_LIB.S9S_MB_2U(SCH_1):PCA9546_PCIE1_ADDR2
    2  PCA9546_PCIE1_ADDR1     A1  @S9S_MB_2U_LIB.S9S_MB_2U(SCH_1):PCA9546_PCIE1_ADDR1
    1  PCA9546_PCIE1_ADDR0     A0  @S9S_MB_2U_LIB.S9S_MB_2U(SCH_1):PCA9546_PCIE1_ADDR0
   16  P3V3_AUX         VCC  @S9S_MB_2U_LIB.S9S_MB_2U(SCH_1):P3V3_AUX
    8  GND              GND  @S9S_MB_2U_LIB.S9S_MB_2U(SCH_1):GND

9SQ440NQQI8  I288  U13    [9SQ440NQQI8-9SQ440NQQI8,SMLF,IA]
   B7  NC             NC_B7  NC
   B5  NC             NC_B5  NC
  B44  NC             NC_B44  NC
  B41  NC             NC_B41  NC
  B39  NC             NC_B39  NC
  B37  NC             NC_B37  NC
  B36  NC             NC_B36  NC
  B34  NC             NC_B34  NC
  B33  NC             NC_B33  NC
  B31  NC             NC_B31  NC
  B30  NC             NC_B30  NC
   B3  NC             NC_B3  NC
  B28  NC             NC_B28  NC
  B26  NC             NC_B26  NC
  B25  NC             NC_B25  NC
  B24  NC             NC_B24  NC
  B22  NC             NC_B22  NC
  B20  NC             NC_B20  NC
   B2  NC             NC_B2  NC
  B18  NC             NC_B18  NC
  B16  NC             NC_B16  NC
  B13  NC             NC_B13  NC
  A15  NC             NC_A15  NC

9SQ440NQQI8  I180  U13    [9SQ440NQQI8-9SQ440NQQI8,SMLF,IA]
  B11  XTAL_CLK_GEN1_25M_X2   XOUT  @S9S_MB_2U_LIB.S9S_MB_2U(SCH_1):XTAL_CLK_GEN1_25M_X2
  A13  XTAL_CLK_GEN1_25M_X1  XIN_CLKIN  @S9S_MB_2U_LIB.S9S_MB_2U(SCH_1):XTAL_CLK_GEN1_25M_X1
   A8  NC             PFT_IN  NC
   A9  NC             PFT_IN#  NC
   A6  NC             PFT_OUT  NC
   A7  NC             PFT_OUT#  NC
  A53  NC             SBI_OUT  NC
   B8  SMB_HOST_CLK_3V3AUX_SDA  SMBDATTA  @S9S_MB_2U_LIB.S9S_MB_2U(SCH_1):SMB_HOST_CLK_3V3AUX_SDA
  A10  SMB_HOST_CLK_3V3AUX_SCL   SCLK  @S9S_MB_2U_LIB.S9S_MB_2U(SCH_1):SMB_HOST_CLK_3V3AUX_SCL
  B14  RISER3_CLK5_EN_N   OE6#  @S9S_MB_2U_LIB.S9S_MB_2U(SCH_1):RISER3_CLK5_EN_N
  B15  RISER3_CLK4_EN_N   OE5#  @S9S_MB_2U_LIB.S9S_MB_2U(SCH_1):RISER3_CLK4_EN_N
  B19  RISER2_CLK3_EN_N   OE4#  @S9S_MB_2U_LIB.S9S_MB_2U(SCH_1):RISER2_CLK3_EN_N
  A26  RISER2_CLK2_EN_N   OE3#  @S9S_MB_2U_LIB.S9S_MB_2U(SCH_1):RISER2_CLK2_EN_N
   B4  PU_CLK_PFT_LOST_N  PFT_LOST#  @S9S_MB_2U_LIB.S9S_MB_2U(SCH_1):PU_CLK_PFT_LOST_N
  B42  PU_CK440_SHFT_LD_N  SHFT_LD#  @S9S_MB_2U_LIB.S9S_MB_2U(SCH_1):PU_CK440_SHFT_LD_N
  B43  PD_CK440_SBI_DATA_IN  SBI_IN  @S9S_MB_2U_LIB.S9S_MB_2U(SCH_1):PD_CK440_SBI_DATA_IN
  A54  PD_CK440_SBI_CLK  SBI_CLK  @S9S_MB_2U_LIB.S9S_MB_2U(SCH_1):PD_CK440_SBI_CLK
  A29  NC              OE2#  NC
  B23  P3V3_AUX_CLK_GEN_VDD_CK440  VDD100M_B23  @S9S_MB_2U_LIB.S9S_MB_2U(SCH_1):P3V3_AUX_CLK_GEN_VDD_CK440
  B21  P3V3_AUX_CLK_GEN_VDD_CK440  VDD100M_B21  @S9S_MB_2U_LIB.S9S_MB_2U(SCH_1):P3V3_AUX_CLK_GEN_VDD_CK440
  A12  P3V3_AUX_CLK_GEN_VDDXTAL_CK440  VDDXTAL  @S9S_MB_2U_LIB.S9S_MB_2U(SCH_1):P3V3_AUX_CLK_GEN_VDDXTAL_CK440
   B6  P3V3_AUX_CLK_GEN_VDDPT_CK440  VDDPT  @S9S_MB_2U_LIB.S9S_MB_2U(SCH_1):P3V3_AUX_CLK_GEN_VDDPT_CK440
  B40  P3V3_AUX_CLK_GEN_VDDMXCK_CK440  VDDMXCK_B40  @S9S_MB_2U_LIB.S9S_MB_2U(SCH_1):P3V3_AUX_CLK_GEN_VDDMXCK_CK440
  B35  P3V3_AUX_CLK_GEN_VDDMXCK_CK440  VDDMXCK_B35  @S9S_MB_2U_LIB.S9S_MB_2U(SCH_1):P3V3_AUX_CLK_GEN_VDDMXCK_CK440
  B32  P3V3_AUX_CLK_GEN_VDDMXCK_CK440  VDDMXCK_B32  @S9S_MB_2U_LIB.S9S_MB_2U(SCH_1):P3V3_AUX_CLK_GEN_VDDMXCK_CK440
  B29  P3V3_AUX_CLK_GEN_VDDMXCK_CK440  VDDMXCK_B29  @S9S_MB_2U_LIB.S9S_MB_2U(SCH_1):P3V3_AUX_CLK_GEN_VDDMXCK_CK440
   B1  P3V3_AUX_CLK_GEN_VDDA25M_CK440  VDDA25M  @S9S_MB_2U_LIB.S9S_MB_2U(SCH_1):P3V3_AUX_CLK_GEN_VDDA25M_CK440
  B17  P3V3_AUX_CLK_GEN_VDDA100M_CK440  VDDA100M  @S9S_MB_2U_LIB.S9S_MB_2U(SCH_1):P3V3_AUX_CLK_GEN_VDDA100M_CK440
  A36  NC             MXCK8  NC
  A35  NC             MXCK8#  NC
  A40  NC             MXCK6  NC
  A39  NC             MXCK6#  NC
  A46  NC             MXCK3  NC
  A45  NC             MXCK3#  NC
  B12  GND            NVGND  @S9S_MB_2U_LIB.S9S_MB_2U(SCH_1):GND
  A14  GND            GNDXTAL  @S9S_MB_2U_LIB.S9S_MB_2U(SCH_1):GND
  B10  GND             GNDS  @S9S_MB_2U_LIB.S9S_MB_2U(SCH_1):GND
   C1  GND             EPAD  @S9S_MB_2U_LIB.S9S_MB_2U(SCH_1):GND
  A17  FM_PLD_CLKS_DEV_EN  PWRGD||PWRDN#  @S9S_MB_2U_LIB.S9S_MB_2U(SCH_1):FM_PLD_CLKS_DEV_EN
  B27  FM_CLK_GEN1_OE0_N   OE0#  @S9S_MB_2U_LIB.S9S_MB_2U(SCH_1):FM_CLK_GEN1_OE0_N
  A16  FM_CLK_CK440_SS_EN  SS_EN_TRI  @S9S_MB_2U_LIB.S9S_MB_2U(SCH_1):FM_CLK_CK440_SS_EN
  B38  FM_CK440_MXCK_25M_100M  MXCK_SEL_100M#  @S9S_MB_2U_LIB.S9S_MB_2U(SCH_1):FM_CK440_MXCK_25M_100M
   A1  FM_CK440Q_DEV_25M_EN  25MPG  @S9S_MB_2U_LIB.S9S_MB_2U(SCH_1):FM_CK440Q_DEV_25M_EN
  A30  EDSFF3_CLK_EN_N   OE1#  @S9S_MB_2U_LIB.S9S_MB_2U(SCH_1):EDSFF3_CLK_EN_N
   B9  CLK_CK440_SMB_ADDR1  SMB_ADR1_TRI  @S9S_MB_2U_LIB.S9S_MB_2U(SCH_1):CLK_CK440_SMB_ADDR1
  A11  CLK_CK440_SMB_ADDR0  SMB_ADR0_TRI  @S9S_MB_2U_LIB.S9S_MB_2U(SCH_1):CLK_CK440_SMB_ADDR0
  A56  CLK_25M_CK440_ISCLK_REF_DP   25M2  @S9S_MB_2U_LIB.S9S_MB_2U(SCH_1):CLK_25M_CK440_ISCLK_REF_DP
  A55  CLK_25M_CK440_ISCLK_REF_DN  25M2#  @S9S_MB_2U_LIB.S9S_MB_2U(SCH_1):CLK_25M_CK440_ISCLK_REF_DN
   A3  CLK_25M_CK440_CPU1_DP   25M1  @S9S_MB_2U_LIB.S9S_MB_2U(SCH_1):CLK_25M_CK440_CPU1_DP
   A2  CLK_25M_CK440_CPU1_DN  25M1#  @S9S_MB_2U_LIB.S9S_MB_2U(SCH_1):CLK_25M_CK440_CPU1_DN
   A5  CLK_25M_CK440_CPU0_DP   25M0  @S9S_MB_2U_LIB.S9S_MB_2U(SCH_1):CLK_25M_CK440_CPU0_DP
   A4  CLK_25M_CK440_CPU0_DN  25M0#  @S9S_MB_2U_LIB.S9S_MB_2U(SCH_1):CLK_25M_CK440_CPU0_DN
  A19  CLK_100M_PE_5_R_DP  100M6  @S9S_MB_2U_LIB.S9S_MB_2U(SCH_1):CLK_100M_PE_5_R_DP
  A18  CLK_100M_PE_5_R_DN  100M6#  @S9S_MB_2U_LIB.S9S_MB_2U(SCH_1):CLK_100M_PE_5_R_DN
  A21  CLK_100M_PE_4_R_DP  100M5  @S9S_MB_2U_LIB.S9S_MB_2U(SCH_1):CLK_100M_PE_4_R_DP
  A20  CLK_100M_PE_4_R_DN  100M5#  @S9S_MB_2U_LIB.S9S_MB_2U(SCH_1):CLK_100M_PE_4_R_DN
  A23  CLK_100M_PE_3_R_DP  100M4  @S9S_MB_2U_LIB.S9S_MB_2U(SCH_1):CLK_100M_PE_3_R_DP
  A22  CLK_100M_PE_3_R_DN  100M4#  @S9S_MB_2U_LIB.S9S_MB_2U(SCH_1):CLK_100M_PE_3_R_DN
  A25  CLK_100M_PE_2_R_DP  100M3  @S9S_MB_2U_LIB.S9S_MB_2U(SCH_1):CLK_100M_PE_2_R_DP
  A24  CLK_100M_PE_2_R_DN  100M3#  @S9S_MB_2U_LIB.S9S_MB_2U(SCH_1):CLK_100M_PE_2_R_DN
  A28  CLK_100M_PE_1_R_DP  100M2  @S9S_MB_2U_LIB.S9S_MB_2U(SCH_1):CLK_100M_PE_1_R_DP
  A27  CLK_100M_PE_1_R_DN  100M2#  @S9S_MB_2U_LIB.S9S_MB_2U(SCH_1):CLK_100M_PE_1_R_DN
  A32  CLK_100M_PE_0_R_DP  100M1  @S9S_MB_2U_LIB.S9S_MB_2U(SCH_1):CLK_100M_PE_0_R_DP
  A31  CLK_100M_PE_0_R_DN  100M1#  @S9S_MB_2U_LIB.S9S_MB_2U(SCH_1):CLK_100M_PE_0_R_DN
  A38  CLK_100M_EDSFF3_R_DP  MXCK7  @S9S_MB_2U_LIB.S9S_MB_2U(SCH_1):CLK_100M_EDSFF3_R_DP
  A37  CLK_100M_EDSFF3_R_DN  MXCK7#  @S9S_MB_2U_LIB.S9S_MB_2U(SCH_1):CLK_100M_EDSFF3_R_DN
  A42  CLK_100M_E1S_3_R_DP  MXCK5  @S9S_MB_2U_LIB.S9S_MB_2U(SCH_1):CLK_100M_E1S_3_R_DP
  A41  CLK_100M_E1S_3_R_DN  MXCK5#  @S9S_MB_2U_LIB.S9S_MB_2U(SCH_1):CLK_100M_E1S_3_R_DN
  A44  CLK_100M_E1S_2_R_DP  MXCK4  @S9S_MB_2U_LIB.S9S_MB_2U(SCH_1):CLK_100M_E1S_2_R_DP
  A43  CLK_100M_E1S_2_R_DN  MXCK4#  @S9S_MB_2U_LIB.S9S_MB_2U(SCH_1):CLK_100M_E1S_2_R_DN
  A50  CLK_100M_E1S_1_R_DP  MXCK1  @S9S_MB_2U_LIB.S9S_MB_2U(SCH_1):CLK_100M_E1S_1_R_DP
  A49  CLK_100M_E1S_1_R_DN  MXCK1#  @S9S_MB_2U_LIB.S9S_MB_2U(SCH_1):CLK_100M_E1S_1_R_DN
  A52  CLK_100M_E1S_0_R_DP  MXCK0  @S9S_MB_2U_LIB.S9S_MB_2U(SCH_1):CLK_100M_E1S_0_R_DP
  A51  CLK_100M_E1S_0_R_DN  MXCK0#  @S9S_MB_2U_LIB.S9S_MB_2U(SCH_1):CLK_100M_E1S_0_R_DN
  A34  CLK_100M_DB2000_DP  100M0  @S9S_MB_2U_LIB.S9S_MB_2U(SCH_1):CLK_100M_DB2000_DP
  A33  CLK_100M_DB2000_DN  100M0#  @S9S_MB_2U_LIB.S9S_MB_2U(SCH_1):CLK_100M_DB2000_DN
  A48  CLK_100M_CK440_PCH_EXTCLK_R_DP  MXCK2  @S9S_MB_2U_LIB.S9S_MB_2U(SCH_1):CLK_100M_CK440_PCH_EXTCLK_R_DP
  A47  CLK_100M_CK440_PCH_EXTCLK_R_DN  MXCK2#  @S9S_MB_2U_LIB.S9S_MB_2U(SCH_1):CLK_100M_CK440_PCH_EXTCLK_R_DN

IDTQS3VH257QG  I17  U14    [IDTQS3VH257QG_SMLF-IDTQS3VH257A]
   15  PD_I3C_SPD_DDR_CPU1_OE_N     E*  @S9S_MB_2U_LIB.S9S_MB_2U(SCH_1):PD_I3C_SPD_DDR_CPU1_OE_N
   16  P3V3_AUX         VCC  @S9S_MB_2U_LIB.S9S_MB_2U(SCH_1):P3V3_AUX
   14  I3C_SPD_DDREFGH_CPU1_R_SDA    I0D  @S9S_MB_2U_LIB.S9S_MB_2U(SCH_1):I3C_SPD_DDREFGH_CPU1_R_SDA
   11  I3C_SPD_DDREFGH_CPU1_R_SCL    I0C  @S9S_MB_2U_LIB.S9S_MB_2U(SCH_1):I3C_SPD_DDREFGH_CPU1_R_SCL
   12  I3C_SPD_DDREFGH_CPU1_LVC1_R_SDA     YD  @S9S_MB_2U_LIB.S9S_MB_2U(SCH_1):I3C_SPD_DDREFGH_CPU1_LVC1_R_SDA
    9  I3C_SPD_DDREFGH_CPU1_LVC1_R_SCL     YC  @S9S_MB_2U_LIB.S9S_MB_2U(SCH_1):I3C_SPD_DDREFGH_CPU1_LVC1_R_SCL
   13  I3C_SPD_DDREFGH_CPU1_BMC_SDA    I1D  @S9S_MB_2U_LIB.S9S_MB_2U(SCH_1):I3C_SPD_DDREFGH_CPU1_BMC_SDA
   10  I3C_SPD_DDREFGH_CPU1_BMC_SCL    I1C  @S9S_MB_2U_LIB.S9S_MB_2U(SCH_1):I3C_SPD_DDREFGH_CPU1_BMC_SCL
    5  I3C_SPD_DDRABCD_CPU1_R_SDA    I0B  @S9S_MB_2U_LIB.S9S_MB_2U(SCH_1):I3C_SPD_DDRABCD_CPU1_R_SDA
    2  I3C_SPD_DDRABCD_CPU1_R_SCL    I0A  @S9S_MB_2U_LIB.S9S_MB_2U(SCH_1):I3C_SPD_DDRABCD_CPU1_R_SCL
    7  I3C_SPD_DDRABCD_CPU1_LVC1_R_SDA     YB  @S9S_MB_2U_LIB.S9S_MB_2U(SCH_1):I3C_SPD_DDRABCD_CPU1_LVC1_R_SDA
    4  I3C_SPD_DDRABCD_CPU1_LVC1_R_SCL     YA  @S9S_MB_2U_LIB.S9S_MB_2U(SCH_1):I3C_SPD_DDRABCD_CPU1_LVC1_R_SCL
    6  I3C_SPD_DDRABCD_CPU1_BMC_SDA    I1B  @S9S_MB_2U_LIB.S9S_MB_2U(SCH_1):I3C_SPD_DDRABCD_CPU1_BMC_SDA
    3  I3C_SPD_DDRABCD_CPU1_BMC_SCL    I1A  @S9S_MB_2U_LIB.S9S_MB_2U(SCH_1):I3C_SPD_DDRABCD_CPU1_BMC_SCL
    8  GND              GND  @S9S_MB_2U_LIB.S9S_MB_2U(SCH_1):GND
    1  FM_SPD_REMOTE_EN      S  @S9S_MB_2U_LIB.S9S_MB_2U(SCH_1):FM_SPD_REMOTE_EN

IDTQS3VH257QG  I25  U15    [IDTQS3VH257QG_SMLF-IDTQS3VH257A]
   15  PD_I3C_SPD_DDR_CPU0_OE_N     E*  @S9S_MB_2U_LIB.S9S_MB_2U(SCH_1):PD_I3C_SPD_DDR_CPU0_OE_N
   16  P3V3_AUX         VCC  @S9S_MB_2U_LIB.S9S_MB_2U(SCH_1):P3V3_AUX
   14  I3C_SPD_DDREFGH_CPU0_R_SDA    I0D  @S9S_MB_2U_LIB.S9S_MB_2U(SCH_1):I3C_SPD_DDREFGH_CPU0_R_SDA
   11  I3C_SPD_DDREFGH_CPU0_R_SCL    I0C  @S9S_MB_2U_LIB.S9S_MB_2U(SCH_1):I3C_SPD_DDREFGH_CPU0_R_SCL
   12  I3C_SPD_DDREFGH_CPU0_LVC1_R_SDA     YD  @S9S_MB_2U_LIB.S9S_MB_2U(SCH_1):I3C_SPD_DDREFGH_CPU0_LVC1_R_SDA
    9  I3C_SPD_DDREFGH_CPU0_LVC1_R_SCL     YC  @S9S_MB_2U_LIB.S9S_MB_2U(SCH_1):I3C_SPD_DDREFGH_CPU0_LVC1_R_SCL
   13  I3C_SPD_DDREFGH_CPU0_BMC_SDA    I1D  @S9S_MB_2U_LIB.S9S_MB_2U(SCH_1):I3C_SPD_DDREFGH_CPU0_BMC_SDA
   10  I3C_SPD_DDREFGH_CPU0_BMC_SCL    I1C  @S9S_MB_2U_LIB.S9S_MB_2U(SCH_1):I3C_SPD_DDREFGH_CPU0_BMC_SCL
    5  I3C_SPD_DDRABCD_CPU0_R_SDA    I0B  @S9S_MB_2U_LIB.S9S_MB_2U(SCH_1):I3C_SPD_DDRABCD_CPU0_R_SDA
    2  I3C_SPD_DDRABCD_CPU0_R_SCL    I0A  @S9S_MB_2U_LIB.S9S_MB_2U(SCH_1):I3C_SPD_DDRABCD_CPU0_R_SCL
    7  I3C_SPD_DDRABCD_CPU0_LVC1_R_SDA     YB  @S9S_MB_2U_LIB.S9S_MB_2U(SCH_1):I3C_SPD_DDRABCD_CPU0_LVC1_R_SDA
    4  I3C_SPD_DDRABCD_CPU0_LVC1_R_SCL     YA  @S9S_MB_2U_LIB.S9S_MB_2U(SCH_1):I3C_SPD_DDRABCD_CPU0_LVC1_R_SCL
    6  I3C_SPD_DDRABCD_CPU0_BMC_SDA    I1B  @S9S_MB_2U_LIB.S9S_MB_2U(SCH_1):I3C_SPD_DDRABCD_CPU0_BMC_SDA
    3  I3C_SPD_DDRABCD_CPU0_BMC_SCL    I1A  @S9S_MB_2U_LIB.S9S_MB_2U(SCH_1):I3C_SPD_DDRABCD_CPU0_BMC_SCL
    8  GND              GND  @S9S_MB_2U_LIB.S9S_MB_2U(SCH_1):GND
    1  FM_SPD_REMOTE_EN      S  @S9S_MB_2U_LIB.S9S_MB_2U(SCH_1):FM_SPD_REMOTE_EN

NC7SZ66M5X  I88  U16    [NC7SZ66M5X_SMLF-NC7SZ66M5X,NC7A]
    5  P3V3_AUX         VCC  @S9S_MB_2U_LIB.S9S_MB_2U(SCH_1):P3V3_AUX
    2  JTAG_MUX_CPU1_GTL_TDI      B  @S9S_MB_2U_LIB.S9S_MB_2U(SCH_1):JTAG_MUX_CPU1_GTL_TDI
    1  JTAG_CPU0_MUX_GTL_TDO      A  @S9S_MB_2U_LIB.S9S_MB_2U(SCH_1):JTAG_CPU0_MUX_GTL_TDO
    3  GND              GND  @S9S_MB_2U_LIB.S9S_MB_2U(SCH_1):GND
    4  FM_CPU_EN_R       OE  @S9S_MB_2U_LIB.S9S_MB_2U(SCH_1):FM_CPU_EN_R

74CBTLV3126PW  I80  U17    [74CBTLV3126PW-74CBTLV3126PW,SMA]
    8  NC                3B  NC
   13  PWRGD_PVNN_MAIN_CPU0    4OE  @S9S_MB_2U_LIB.S9S_MB_2U(SCH_1):PWRGD_PVNN_MAIN_CPU0
   10  PWRGD_PVNN_MAIN_CPU0    3OE  @S9S_MB_2U_LIB.S9S_MB_2U(SCH_1):PWRGD_PVNN_MAIN_CPU0
    4  PWRGD_PVNN_MAIN_CPU0    2OE  @S9S_MB_2U_LIB.S9S_MB_2U(SCH_1):PWRGD_PVNN_MAIN_CPU0
    1  PWRGD_PVNN_MAIN_CPU0    1OE  @S9S_MB_2U_LIB.S9S_MB_2U(SCH_1):PWRGD_PVNN_MAIN_CPU0
    9  PD_74CB_A9        3A  @S9S_MB_2U_LIB.S9S_MB_2U(SCH_1):PD_74CB_A9
   14  P3V3_AUX         VCC  @S9S_MB_2U_LIB.S9S_MB_2U(SCH_1):P3V3_AUX
    6  JTAG_QS_MUX_GTL_TDI     2B  @S9S_MB_2U_LIB.S9S_MB_2U(SCH_1):JTAG_QS_MUX_GTL_TDI
   11  JTAG_MUX_QS_GTL_TDO     4B  @S9S_MB_2U_LIB.S9S_MB_2U(SCH_1):JTAG_MUX_QS_GTL_TDO
    2  JTAG_DBP_TMS      1A  @S9S_MB_2U_LIB.S9S_MB_2U(SCH_1):JTAG_DBP_TMS
   12  JTAG_DBP_TDO      4A  @S9S_MB_2U_LIB.S9S_MB_2U(SCH_1):JTAG_DBP_TDO
    5  JTAG_DBP_TDI      2A  @S9S_MB_2U_LIB.S9S_MB_2U(SCH_1):JTAG_DBP_TDI
    3  JTAG_DBP_CPU_QS_GTL_TMS     1B  @S9S_MB_2U_LIB.S9S_MB_2U(SCH_1):JTAG_DBP_CPU_QS_GTL_TMS
    7  GND              GND  @S9S_MB_2U_LIB.S9S_MB_2U(SCH_1):GND

74CBTLV3126PW  I129  U18    [74CBTLV3126PW-74CBTLV3126PW,SMA]
   13  PWRGD_PVNN_MAIN_CPU0    4OE  @S9S_MB_2U_LIB.S9S_MB_2U(SCH_1):PWRGD_PVNN_MAIN_CPU0
   10  PWRGD_PVNN_MAIN_CPU0    3OE  @S9S_MB_2U_LIB.S9S_MB_2U(SCH_1):PWRGD_PVNN_MAIN_CPU0
    4  PWRGD_PVNN_MAIN_CPU0    2OE  @S9S_MB_2U_LIB.S9S_MB_2U(SCH_1):PWRGD_PVNN_MAIN_CPU0
    1  PWRGD_PVNN_MAIN_CPU0    1OE  @S9S_MB_2U_LIB.S9S_MB_2U(SCH_1):PWRGD_PVNN_MAIN_CPU0
   14  P3V3_AUX         VCC  @S9S_MB_2U_LIB.S9S_MB_2U(SCH_1):P3V3_AUX
   12  JTAG_DBP_PREQ_N     4A  @S9S_MB_2U_LIB.S9S_MB_2U(SCH_1):JTAG_DBP_PREQ_N
    9  JTAG_DBP_PRDY_N     3A  @S9S_MB_2U_LIB.S9S_MB_2U(SCH_1):JTAG_DBP_PRDY_N
    2  JTAG_DBP_CPU_HOOK9_MBP3_GTL_N     1A  @S9S_MB_2U_LIB.S9S_MB_2U(SCH_1):JTAG_DBP_CPU_HOOK9_MBP3_GTL_N
    5  JTAG_DBP_CPU_HOOK8_MBP2_GTL_N     2A  @S9S_MB_2U_LIB.S9S_MB_2U(SCH_1):JTAG_DBP_CPU_HOOK8_MBP2_GTL_N
   11  H_CPU_PREQ_QS_GTL_N     4B  @S9S_MB_2U_LIB.S9S_MB_2U(SCH_1):H_CPU_PREQ_QS_GTL_N
    8  H_CPU_PRDY_QS_GTL_N     3B  @S9S_MB_2U_LIB.S9S_MB_2U(SCH_1):H_CPU_PRDY_QS_GTL_N
    7  GND              GND  @S9S_MB_2U_LIB.S9S_MB_2U(SCH_1):GND
    3  DBP_CPU_HOOK9_MBP3_GTL_QS_N     1B  @S9S_MB_2U_LIB.S9S_MB_2U(SCH_1):DBP_CPU_HOOK9_MBP3_GTL_QS_N
    6  DBP_CPU_HOOK8_MBP2_GTL_QS_N     2B  @S9S_MB_2U_LIB.S9S_MB_2U(SCH_1):DBP_CPU_HOOK8_MBP2_GTL_QS_N

MOSFET_N  I34  U19    [MOSFET_N_SMLF-BSS138K,BSS138K,A]
    S  GND            SOURCE  @S9S_MB_2U_LIB.S9S_MB_2U(SCH_1):GND
    D  FM_PSU_THROTTLE_N  DRAIN  @S9S_MB_2U_LIB.S9S_MB_2U(SCH_1):FM_PSU_THROTTLE_N
    G  FM_PSU_THROTTLE_L   GATE  @S9S_MB_2U_LIB.S9S_MB_2U(SCH_1):FM_PSU_THROTTLE_L

NC7SB3157  I58  U21    [NC7SB3157_SMLF-NC7SB3157P6X,NCA]
    5  P3V3_AUX         VCC  @S9S_MB_2U_LIB.S9S_MB_2U(SCH_1):P3V3_AUX
    4  JTAG_QS_MUX_GTL_TDI      A  @S9S_MB_2U_LIB.S9S_MB_2U(SCH_1):JTAG_QS_MUX_GTL_TDI
    1  JTAG_MUX_CPU1_GTL_TDI     B1  @S9S_MB_2U_LIB.S9S_MB_2U(SCH_1):JTAG_MUX_CPU1_GTL_TDI
    3  JTAG_MUX_CPU0_GTL_TDI     B0  @S9S_MB_2U_LIB.S9S_MB_2U(SCH_1):JTAG_MUX_CPU0_GTL_TDI
    2  GND              GND  @S9S_MB_2U_LIB.S9S_MB_2U(SCH_1):GND
    6  FM_CPU0_SKTOCC_N      S  @S9S_MB_2U_LIB.S9S_MB_2U(SCH_1):FM_CPU0_SKTOCC_N

NC7SB3157  I71  U22    [NC7SB3157_SMLF-NC7SB3157P6X,NCA]
    5  P3V3_AUX         VCC  @S9S_MB_2U_LIB.S9S_MB_2U(SCH_1):P3V3_AUX
    4  JTAG_MUX_QS_GTL_TDO      A  @S9S_MB_2U_LIB.S9S_MB_2U(SCH_1):JTAG_MUX_QS_GTL_TDO
    3  JTAG_CPU1_MUX_GTL_TDO     B0  @S9S_MB_2U_LIB.S9S_MB_2U(SCH_1):JTAG_CPU1_MUX_GTL_TDO
    1  JTAG_CPU0_MUX_GTL_TDO     B1  @S9S_MB_2U_LIB.S9S_MB_2U(SCH_1):JTAG_CPU0_MUX_GTL_TDO
    2  GND              GND  @S9S_MB_2U_LIB.S9S_MB_2U(SCH_1):GND
    6  FM_CPU1_SKTOCC_N      S  @S9S_MB_2U_LIB.S9S_MB_2U(SCH_1):FM_CPU1_SKTOCC_N

74LVC1G02GW  I96  U23    [74LVC1G02GW_SMLF-74LVC1G02GW,IA]
    5  P3V3_AUX         VCC  @S9S_MB_2U_LIB.S9S_MB_2U(SCH_1):P3V3_AUX
    3  GND              GND  @S9S_MB_2U_LIB.S9S_MB_2U(SCH_1):GND
    4  FM_CPU_EN          Y  @S9S_MB_2U_LIB.S9S_MB_2U(SCH_1):FM_CPU_EN
    1  FM_CPU1_SKTOCC_N      B  @S9S_MB_2U_LIB.S9S_MB_2U(SCH_1):FM_CPU1_SKTOCC_N
    2  FM_CPU0_SKTOCC_N      A  @S9S_MB_2U_LIB.S9S_MB_2U(SCH_1):FM_CPU0_SKTOCC_N

PCA9548APW  I60  U24    [PCA9548APW-PCA9548APW,SMLF,IC,A]
   23  SMB_PCIE2_3V3AUX_SDA    SDA  @S9S_MB_2U_LIB.S9S_MB_2U(SCH_1):SMB_PCIE2_3V3AUX_SDA
   22  SMB_PCIE2_3V3AUX_SCL    SCL  @S9S_MB_2U_LIB.S9S_MB_2U(SCH_1):SMB_PCIE2_3V3AUX_SCL
   19  SMB_EDSFF_3V3AUX_SDA_R8    SD7  @S9S_MB_2U_LIB.S9S_MB_2U(SCH_1):SMB_EDSFF_3V3AUX_SDA_R8
   20  SMB_EDSFF_3V3AUX_SCL_R8    SC7  @S9S_MB_2U_LIB.S9S_MB_2U(SCH_1):SMB_EDSFF_3V3AUX_SCL_R8
   17  SMB_EDSFF4B_3V3AUX_SDA_R1    SD6  @S9S_MB_2U_LIB.S9S_MB_2U(SCH_1):SMB_EDSFF4B_3V3AUX_SDA_R1
   18  SMB_EDSFF4B_3V3AUX_SCL_R1    SC6  @S9S_MB_2U_LIB.S9S_MB_2U(SCH_1):SMB_EDSFF4B_3V3AUX_SCL_R1
   15  SMB_EDSFF4A_3V3AUX_SDA_R1    SD5  @S9S_MB_2U_LIB.S9S_MB_2U(SCH_1):SMB_EDSFF4A_3V3AUX_SDA_R1
   16  SMB_EDSFF4A_3V3AUX_SCL_R1    SC5  @S9S_MB_2U_LIB.S9S_MB_2U(SCH_1):SMB_EDSFF4A_3V3AUX_SCL_R1
   13  SMB_EDSFF3_3V3AUX_SDA_R1    SD4  @S9S_MB_2U_LIB.S9S_MB_2U(SCH_1):SMB_EDSFF3_3V3AUX_SDA_R1
   14  SMB_EDSFF3_3V3AUX_SCL_R1    SC4  @S9S_MB_2U_LIB.S9S_MB_2U(SCH_1):SMB_EDSFF3_3V3AUX_SCL_R1
   10  SMB_EDSFF2B_3V3AUX_SDA_R1    SD3  @S9S_MB_2U_LIB.S9S_MB_2U(SCH_1):SMB_EDSFF2B_3V3AUX_SDA_R1
   11  SMB_EDSFF2B_3V3AUX_SCL_R1    SC3  @S9S_MB_2U_LIB.S9S_MB_2U(SCH_1):SMB_EDSFF2B_3V3AUX_SCL_R1
    8  SMB_EDSFF2A_3V3AUX_SDA_R1    SD2  @S9S_MB_2U_LIB.S9S_MB_2U(SCH_1):SMB_EDSFF2A_3V3AUX_SDA_R1
    9  SMB_EDSFF2A_3V3AUX_SCL_R1    SC2  @S9S_MB_2U_LIB.S9S_MB_2U(SCH_1):SMB_EDSFF2A_3V3AUX_SCL_R1
    6  SMB_EDSFF1B_3V3AUX_SDA_R1    SD1  @S9S_MB_2U_LIB.S9S_MB_2U(SCH_1):SMB_EDSFF1B_3V3AUX_SDA_R1
    7  SMB_EDSFF1B_3V3AUX_SCL_R1    SC1  @S9S_MB_2U_LIB.S9S_MB_2U(SCH_1):SMB_EDSFF1B_3V3AUX_SCL_R1
    4  SMB_EDSFF1A_3V3AUX_SDA_R1    SD0  @S9S_MB_2U_LIB.S9S_MB_2U(SCH_1):SMB_EDSFF1A_3V3AUX_SDA_R1
    5  SMB_EDSFF1A_3V3AUX_SCL_R1    SC0  @S9S_MB_2U_LIB.S9S_MB_2U(SCH_1):SMB_EDSFF1A_3V3AUX_SCL_R1
    3  PU_RST_SMB_EDSFF_N  RESET#  @S9S_MB_2U_LIB.S9S_MB_2U(SCH_1):PU_RST_SMB_EDSFF_N
   21  PCA9548_PCIE2_ADDR2     A2  @S9S_MB_2U_LIB.S9S_MB_2U(SCH_1):PCA9548_PCIE2_ADDR2
    2  PCA9548_PCIE2_ADDR1     A1  @S9S_MB_2U_LIB.S9S_MB_2U(SCH_1):PCA9548_PCIE2_ADDR1
    1  PCA9548_PCIE2_ADDR0     A0  @S9S_MB_2U_LIB.S9S_MB_2U(SCH_1):PCA9548_PCIE2_ADDR0
   24  P3V3_AUX         VDD  @S9S_MB_2U_LIB.S9S_MB_2U(SCH_1):P3V3_AUX
   12  GND              VSS  @S9S_MB_2U_LIB.S9S_MB_2U(SCH_1):GND

TPS2553DBVR1  I24  U27    [TPS2553DBVR1-TPS2553DBVR-1,SMLA]
    4  USB_OC2_INT_N  FAULT_N  @S9S_MB_2U_LIB.S9S_MB_2U(SCH_1):USB_OC2_INT_N
    3  PU_USB_INT_P5V_EN_N     EN  @S9S_MB_2U_LIB.S9S_MB_2U(SCH_1):PU_USB_INT_P5V_EN_N
    5  PD_USB_INT_ILIM   ILIM  @S9S_MB_2U_LIB.S9S_MB_2U(SCH_1):PD_USB_INT_ILIM
    6  P5V_USB_INT      OUT  @S9S_MB_2U_LIB.S9S_MB_2U(SCH_1):P5V_USB_INT
    1  P5V               IN  @S9S_MB_2U_LIB.S9S_MB_2U(SCH_1):P5V
    2  GND              GND  @S9S_MB_2U_LIB.S9S_MB_2U(SCH_1):GND

PCA9617ADP  I39  U28    [PCA9617ADP-PCA9617ADP,SMLF,IC,A]
    5  NC                EN  NC
    6  SMB_PEHPCPU0_LVC3_SDA   SDAB  @S9S_MB_2U_LIB.S9S_MB_2U(SCH_1):SMB_PEHPCPU0_LVC3_SDA
    7  SMB_PEHPCPU0_LVC3_SCL   SCLB  @S9S_MB_2U_LIB.S9S_MB_2U(SCH_1):SMB_PEHPCPU0_LVC3_SCL
    3  SMB_PEHPCPU0_GTL_R_SDA   SDAA  @S9S_MB_2U_LIB.S9S_MB_2U(SCH_1):SMB_PEHPCPU0_GTL_R_SDA
    2  SMB_PEHPCPU0_GTL_R_SCL   SCLA  @S9S_MB_2U_LIB.S9S_MB_2U(SCH_1):SMB_PEHPCPU0_GTL_R_SCL
    1  PVNN_TERM_CPU0   VCCA  @S9S_MB_2U_LIB.S9S_MB_2U(SCH_1):PVNN_TERM_CPU0
    8  P3V3_AUX        VCCB  @S9S_MB_2U_LIB.S9S_MB_2U(SCH_1):P3V3_AUX
    4  GND              GND  @S9S_MB_2U_LIB.S9S_MB_2U(SCH_1):GND

PCA9617ADP  I43  U29    [PCA9617ADP-PCA9617ADP,SMLF,IC,A]
    5  NC                EN  NC
    6  SMB_PEHPCPU1_LVC3_SDA   SDAB  @S9S_MB_2U_LIB.S9S_MB_2U(SCH_1):SMB_PEHPCPU1_LVC3_SDA
    7  SMB_PEHPCPU1_LVC3_SCL   SCLB  @S9S_MB_2U_LIB.S9S_MB_2U(SCH_1):SMB_PEHPCPU1_LVC3_SCL
    3  SMB_PEHPCPU1_GTL_R_SDA   SDAA  @S9S_MB_2U_LIB.S9S_MB_2U(SCH_1):SMB_PEHPCPU1_GTL_R_SDA
    2  SMB_PEHPCPU1_GTL_R_SCL   SCLA  @S9S_MB_2U_LIB.S9S_MB_2U(SCH_1):SMB_PEHPCPU1_GTL_R_SCL
    1  PVNN_TERM_CPU1   VCCA  @S9S_MB_2U_LIB.S9S_MB_2U(SCH_1):PVNN_TERM_CPU1
    8  P3V3_AUX        VCCB  @S9S_MB_2U_LIB.S9S_MB_2U(SCH_1):P3V3_AUX
    4  GND              GND  @S9S_MB_2U_LIB.S9S_MB_2U(SCH_1):GND

PCA9617ADP  I28  U30    [PCA9617ADP-PCA9617ADP,SMLF,IC,A]
    5  NC                EN  NC
    3  SMB_S3M_CPU0_R_SDA   SDAA  @S9S_MB_2U_LIB.S9S_MB_2U(SCH_1):SMB_S3M_CPU0_R_SDA
    2  SMB_S3M_CPU0_R_SCL   SCLA  @S9S_MB_2U_LIB.S9S_MB_2U(SCH_1):SMB_S3M_CPU0_R_SCL
    6  SMB_S3M_CPU0_3V3AUX_SDA   SDAB  @S9S_MB_2U_LIB.S9S_MB_2U(SCH_1):SMB_S3M_CPU0_3V3AUX_SDA
    7  SMB_S3M_CPU0_3V3AUX_SCL   SCLB  @S9S_MB_2U_LIB.S9S_MB_2U(SCH_1):SMB_S3M_CPU0_3V3AUX_SCL
    1  PVNN_TERM_CPU0   VCCA  @S9S_MB_2U_LIB.S9S_MB_2U(SCH_1):PVNN_TERM_CPU0
    8  P3V3_AUX        VCCB  @S9S_MB_2U_LIB.S9S_MB_2U(SCH_1):P3V3_AUX
    4  GND              GND  @S9S_MB_2U_LIB.S9S_MB_2U(SCH_1):GND

PCA9617ADP  I37  U31    [PCA9617ADP-PCA9617ADP,SMLF,IC,A]
    5  NC                EN  NC
    3  SMB_S3M_CPU1_R_SDA   SDAA  @S9S_MB_2U_LIB.S9S_MB_2U(SCH_1):SMB_S3M_CPU1_R_SDA
    2  SMB_S3M_CPU1_R_SCL   SCLA  @S9S_MB_2U_LIB.S9S_MB_2U(SCH_1):SMB_S3M_CPU1_R_SCL
    6  SMB_S3M_CPU1_3V3AUX_SDA   SDAB  @S9S_MB_2U_LIB.S9S_MB_2U(SCH_1):SMB_S3M_CPU1_3V3AUX_SDA
    7  SMB_S3M_CPU1_3V3AUX_SCL   SCLB  @S9S_MB_2U_LIB.S9S_MB_2U(SCH_1):SMB_S3M_CPU1_3V3AUX_SCL
    1  PVNN_TERM_CPU1   VCCA  @S9S_MB_2U_LIB.S9S_MB_2U(SCH_1):PVNN_TERM_CPU1
    8  P3V3_AUX        VCCB  @S9S_MB_2U_LIB.S9S_MB_2U(SCH_1):P3V3_AUX
    4  GND              GND  @S9S_MB_2U_LIB.S9S_MB_2U(SCH_1):GND

PCA9546APWR  I179  U36    [PCA9546APWR-PCA9546APWR,SMLF,IA]
   11  SMB_PCIE0_3V3AUX_SDA_R3    SD3  @S9S_MB_2U_LIB.S9S_MB_2U(SCH_1):SMB_PCIE0_3V3AUX_SDA_R3
    9  SMB_PCIE0_3V3AUX_SDA_R2    SD2  @S9S_MB_2U_LIB.S9S_MB_2U(SCH_1):SMB_PCIE0_3V3AUX_SDA_R2
    6  SMB_PCIE0_3V3AUX_SDA_R1    SD1  @S9S_MB_2U_LIB.S9S_MB_2U(SCH_1):SMB_PCIE0_3V3AUX_SDA_R1
    4  SMB_PCIE0_3V3AUX_SDA_R0    SD0  @S9S_MB_2U_LIB.S9S_MB_2U(SCH_1):SMB_PCIE0_3V3AUX_SDA_R0
   15  SMB_PCIE0_3V3AUX_SDA_R    SDA  @S9S_MB_2U_LIB.S9S_MB_2U(SCH_1):SMB_PCIE0_3V3AUX_SDA_R
   12  SMB_PCIE0_3V3AUX_SCL_R3    SC3  @S9S_MB_2U_LIB.S9S_MB_2U(SCH_1):SMB_PCIE0_3V3AUX_SCL_R3
   10  SMB_PCIE0_3V3AUX_SCL_R2    SC2  @S9S_MB_2U_LIB.S9S_MB_2U(SCH_1):SMB_PCIE0_3V3AUX_SCL_R2
    7  SMB_PCIE0_3V3AUX_SCL_R1    SC1  @S9S_MB_2U_LIB.S9S_MB_2U(SCH_1):SMB_PCIE0_3V3AUX_SCL_R1
    5  SMB_PCIE0_3V3AUX_SCL_R0    SC0  @S9S_MB_2U_LIB.S9S_MB_2U(SCH_1):SMB_PCIE0_3V3AUX_SCL_R0
   14  SMB_PCIE0_3V3AUX_SCL_R    SCL  @S9S_MB_2U_LIB.S9S_MB_2U(SCH_1):SMB_PCIE0_3V3AUX_SCL_R
    3  PU_RST_SMB_PCIE3_N  RESET#  @S9S_MB_2U_LIB.S9S_MB_2U(SCH_1):PU_RST_SMB_PCIE3_N
   13  PCA9546_PCIE0_ADDR2     A2  @S9S_MB_2U_LIB.S9S_MB_2U(SCH_1):PCA9546_PCIE0_ADDR2
    2  PCA9546_PCIE0_ADDR1     A1  @S9S_MB_2U_LIB.S9S_MB_2U(SCH_1):PCA9546_PCIE0_ADDR1
    1  PCA9546_PCIE0_ADDR0     A0  @S9S_MB_2U_LIB.S9S_MB_2U(SCH_1):PCA9546_PCIE0_ADDR0
   16  P3V3_AUX         VCC  @S9S_MB_2U_LIB.S9S_MB_2U(SCH_1):P3V3_AUX
    8  GND              GND  @S9S_MB_2U_LIB.S9S_MB_2U(SCH_1):GND

9QXL2001BNHGI8  I119  U38    [9QXL2001BNHGI8-9QXL2001BNHGI8,A]
   L4  SMB_HOST_DB2000_3V3AUX_SDA  SMBDAT  @S9S_MB_2U_LIB.S9S_MB_2U(SCH_1):SMB_HOST_DB2000_3V3AUX_SDA
   L5  SMB_HOST_DB2000_3V3AUX_SCL  SMBCLK  @S9S_MB_2U_LIB.S9S_MB_2U(SCH_1):SMB_HOST_DB2000_3V3AUX_SCL
   B8  PD_DB2000_SMB_SA1  ^VSADR1_TRI  @S9S_MB_2U_LIB.S9S_MB_2U(SCH_1):PD_DB2000_SMB_SA1
   B4  PD_DB2000_SMB_SA0  ^VSADR0_TRI  @S9S_MB_2U_LIB.S9S_MB_2U(SCH_1):PD_DB2000_SMB_SA0
   H2  P3V3_DB2000_VDDR  VDDR3.3  @S9S_MB_2U_LIB.S9S_MB_2U(SCH_1):P3V3_DB2000_VDDR
   B6  P3V3_DB2000_VDDA  VDDA3.3  @S9S_MB_2U_LIB.S9S_MB_2U(SCH_1):P3V3_DB2000_VDDA
  L11  P3V3_DB2000_VDD  VDDO3.3_L11  @S9S_MB_2U_LIB.S9S_MB_2U(SCH_1):P3V3_DB2000_VDD
   L2  P3V3_DB2000_VDD  VDDO3.3_L2  @S9S_MB_2U_LIB.S9S_MB_2U(SCH_1):P3V3_DB2000_VDD
  B11  P3V3_DB2000_VDD  VDDO3.3_B11  @S9S_MB_2U_LIB.S9S_MB_2U(SCH_1):P3V3_DB2000_VDD
   B2  P3V3_DB2000_VDD  VDDO3.3_B2  @S9S_MB_2U_LIB.S9S_MB_2U(SCH_1):P3V3_DB2000_VDD
  F11  NC               NC9  NC
   F2  NC               NC8  NC
  D11  NC               NC7  NC
   D2  NC               NC6  NC
   C2  NC               NC5  NC
   B9  NC               NC4  NC
   B7  NC               NC3  NC
   B5  NC               NC2  NC
   L9  NC              NC18  NC
   L3  NC              NC17  NC
   L7  NC              NC16  NC
   L6  NC              NC15  NC
   K2  NC              NC14  NC
  J11  NC              NC13  NC
   J2  NC              NC12  NC
  G11  NC              NC11  NC
   G2  NC              NC10  NC
   B3  NC               NC1  NC
   TH  GND             EPAD  @S9S_MB_2U_LIB.S9S_MB_2U(SCH_1):GND
   E2  FM_DB2000_VSBEN  VSBEN  @S9S_MB_2U_LIB.S9S_MB_2U(SCH_1):FM_DB2000_VSBEN
   M6  FM_DB2000_DEV_EN  VCKPWRGD_PD#  @S9S_MB_2U_LIB.S9S_MB_2U(SCH_1):FM_DB2000_DEV_EN
  C11  FM_DB2000_8_OE_N  VOE11#  @S9S_MB_2U_LIB.S9S_MB_2U(SCH_1):FM_DB2000_8_OE_N
  E11  FM_DB2000_8_OE_N  VOE10#||SHFT_LD#  @S9S_MB_2U_LIB.S9S_MB_2U(SCH_1):FM_DB2000_8_OE_N
  E12  FM_DB2000_8_OE_N  VOE9#  @S9S_MB_2U_LIB.S9S_MB_2U(SCH_1):FM_DB2000_8_OE_N
  H11  FM_DB2000_8_OE_N  VOE8#  @S9S_MB_2U_LIB.S9S_MB_2U(SCH_1):FM_DB2000_8_OE_N
  K11  FM_DB2000_1_OE_N  VOE7#  @S9S_MB_2U_LIB.S9S_MB_2U(SCH_1):FM_DB2000_1_OE_N
  L10  FM_DB2000_1_OE_N  VOE6#||CLK  @S9S_MB_2U_LIB.S9S_MB_2U(SCH_1):FM_DB2000_1_OE_N
   L8  FM_DB2000_1_OE_N  VOE5#||DATA  @S9S_MB_2U_LIB.S9S_MB_2U(SCH_1):FM_DB2000_1_OE_N
  B10  FM_DB2000_12_OE_N  VOE12#  @S9S_MB_2U_LIB.S9S_MB_2U(SCH_1):FM_DB2000_12_OE_N
  B12  CLK_100M_OCP_SFF_3_R_DP  DIF11  @S9S_MB_2U_LIB.S9S_MB_2U(SCH_1):CLK_100M_OCP_SFF_3_R_DP
  A12  CLK_100M_OCP_SFF_3_R_DN  DIF11#  @S9S_MB_2U_LIB.S9S_MB_2U(SCH_1):CLK_100M_OCP_SFF_3_R_DN
  D12  CLK_100M_OCP_SFF_2_R_DP  DIF10  @S9S_MB_2U_LIB.S9S_MB_2U(SCH_1):CLK_100M_OCP_SFF_2_R_DP
  C12  CLK_100M_OCP_SFF_2_R_DN  DIF10#  @S9S_MB_2U_LIB.S9S_MB_2U(SCH_1):CLK_100M_OCP_SFF_2_R_DN
  G12  CLK_100M_OCP_SFF_1_R_DP   DIF9  @S9S_MB_2U_LIB.S9S_MB_2U(SCH_1):CLK_100M_OCP_SFF_1_R_DP
  F12  CLK_100M_OCP_SFF_1_R_DN  DIF9#  @S9S_MB_2U_LIB.S9S_MB_2U(SCH_1):CLK_100M_OCP_SFF_1_R_DN
  J12  CLK_100M_OCP_SFF_0_R_DP   DIF8  @S9S_MB_2U_LIB.S9S_MB_2U(SCH_1):CLK_100M_OCP_SFF_0_R_DP
  H12  CLK_100M_OCP_SFF_0_R_DN  DIF8#  @S9S_MB_2U_LIB.S9S_MB_2U(SCH_1):CLK_100M_OCP_SFF_0_R_DN
   E1  CLK_100M_EDSFF4B_R_DP  DIF19  @S9S_MB_2U_LIB.S9S_MB_2U(SCH_1):CLK_100M_EDSFF4B_R_DP
   F1  CLK_100M_EDSFF4B_R_DN  DIF19#  @S9S_MB_2U_LIB.S9S_MB_2U(SCH_1):CLK_100M_EDSFF4B_R_DN
   C1  CLK_100M_EDSFF4A_R_DP  DIF18  @S9S_MB_2U_LIB.S9S_MB_2U(SCH_1):CLK_100M_EDSFF4A_R_DP
   D1  CLK_100M_EDSFF4A_R_DN  DIF18#  @S9S_MB_2U_LIB.S9S_MB_2U(SCH_1):CLK_100M_EDSFF4A_R_DN
   A1  CLK_100M_EDSFF2B_R_DP  DIF17  @S9S_MB_2U_LIB.S9S_MB_2U(SCH_1):CLK_100M_EDSFF2B_R_DP
   B1  CLK_100M_EDSFF2B_R_DN  DIF17#  @S9S_MB_2U_LIB.S9S_MB_2U(SCH_1):CLK_100M_EDSFF2B_R_DN
   A3  CLK_100M_EDSFF2A_R_DP  DIF16  @S9S_MB_2U_LIB.S9S_MB_2U(SCH_1):CLK_100M_EDSFF2A_R_DP
   A2  CLK_100M_EDSFF2A_R_DN  DIF16#  @S9S_MB_2U_LIB.S9S_MB_2U(SCH_1):CLK_100M_EDSFF2A_R_DN
   A7  CLK_100M_EDSFF1B_R_DP  DIF14  @S9S_MB_2U_LIB.S9S_MB_2U(SCH_1):CLK_100M_EDSFF1B_R_DP
   A6  CLK_100M_EDSFF1B_R_DN  DIF14#  @S9S_MB_2U_LIB.S9S_MB_2U(SCH_1):CLK_100M_EDSFF1B_R_DN
   A5  CLK_100M_EDSFF1B_1_R_DP  DIF15  @S9S_MB_2U_LIB.S9S_MB_2U(SCH_1):CLK_100M_EDSFF1B_1_R_DP
   A4  CLK_100M_EDSFF1B_1_R_DN  DIF15#  @S9S_MB_2U_LIB.S9S_MB_2U(SCH_1):CLK_100M_EDSFF1B_1_R_DN
  A11  CLK_100M_EDSFF1A_R_DP  DIF12  @S9S_MB_2U_LIB.S9S_MB_2U(SCH_1):CLK_100M_EDSFF1A_R_DP
  A10  CLK_100M_EDSFF1A_R_DN  DIF12#  @S9S_MB_2U_LIB.S9S_MB_2U(SCH_1):CLK_100M_EDSFF1A_R_DN
   A9  CLK_100M_EDSFF1A_1_R_DP  DIF13  @S9S_MB_2U_LIB.S9S_MB_2U(SCH_1):CLK_100M_EDSFF1A_1_R_DP
   A8  CLK_100M_EDSFF1A_1_R_DN  DIF13#  @S9S_MB_2U_LIB.S9S_MB_2U(SCH_1):CLK_100M_EDSFF1A_1_R_DN
   G1  CLK_100M_DB2000_DP  DIF_IN  @S9S_MB_2U_LIB.S9S_MB_2U(SCH_1):CLK_100M_DB2000_DP
   H1  CLK_100M_DB2000_DN  DIF_IN#  @S9S_MB_2U_LIB.S9S_MB_2U(SCH_1):CLK_100M_DB2000_DN
  L12  CLK_100M_DB2000_CPU1_BCLK3_DP   DIF7  @S9S_MB_2U_LIB.S9S_MB_2U(SCH_1):CLK_100M_DB2000_CPU1_BCLK3_DP
  K12  CLK_100M_DB2000_CPU1_BCLK3_DN  DIF7#  @S9S_MB_2U_LIB.S9S_MB_2U(SCH_1):CLK_100M_DB2000_CPU1_BCLK3_DN
  M11  CLK_100M_DB2000_CPU1_BCLK2_DP   DIF6  @S9S_MB_2U_LIB.S9S_MB_2U(SCH_1):CLK_100M_DB2000_CPU1_BCLK2_DP
  M12  CLK_100M_DB2000_CPU1_BCLK2_DN  DIF6#  @S9S_MB_2U_LIB.S9S_MB_2U(SCH_1):CLK_100M_DB2000_CPU1_BCLK2_DN
   M9  CLK_100M_DB2000_CPU1_BCLK1_DP   DIF5  @S9S_MB_2U_LIB.S9S_MB_2U(SCH_1):CLK_100M_DB2000_CPU1_BCLK1_DP
  M10  CLK_100M_DB2000_CPU1_BCLK1_DN  DIF5#  @S9S_MB_2U_LIB.S9S_MB_2U(SCH_1):CLK_100M_DB2000_CPU1_BCLK1_DN
   M7  CLK_100M_DB2000_CPU1_BCLK0_DP   DIF4  @S9S_MB_2U_LIB.S9S_MB_2U(SCH_1):CLK_100M_DB2000_CPU1_BCLK0_DP
   M8  CLK_100M_DB2000_CPU1_BCLK0_DN  DIF4#  @S9S_MB_2U_LIB.S9S_MB_2U(SCH_1):CLK_100M_DB2000_CPU1_BCLK0_DN
   M4  CLK_100M_DB2000_CPU0_BCLK3_DP   DIF3  @S9S_MB_2U_LIB.S9S_MB_2U(SCH_1):CLK_100M_DB2000_CPU0_BCLK3_DP
   M5  CLK_100M_DB2000_CPU0_BCLK3_DN  DIF3#  @S9S_MB_2U_LIB.S9S_MB_2U(SCH_1):CLK_100M_DB2000_CPU0_BCLK3_DN
   M2  CLK_100M_DB2000_CPU0_BCLK2_DP   DIF2  @S9S_MB_2U_LIB.S9S_MB_2U(SCH_1):CLK_100M_DB2000_CPU0_BCLK2_DP
   M3  CLK_100M_DB2000_CPU0_BCLK2_DN  DIF2#  @S9S_MB_2U_LIB.S9S_MB_2U(SCH_1):CLK_100M_DB2000_CPU0_BCLK2_DN
   L1  CLK_100M_DB2000_CPU0_BCLK1_DP   DIF1  @S9S_MB_2U_LIB.S9S_MB_2U(SCH_1):CLK_100M_DB2000_CPU0_BCLK1_DP
   M1  CLK_100M_DB2000_CPU0_BCLK1_DN  DIF1#  @S9S_MB_2U_LIB.S9S_MB_2U(SCH_1):CLK_100M_DB2000_CPU0_BCLK1_DN
   J1  CLK_100M_DB2000_CPU0_BCLK0_DP   DIF0  @S9S_MB_2U_LIB.S9S_MB_2U(SCH_1):CLK_100M_DB2000_CPU0_BCLK0_DP
   K1  CLK_100M_DB2000_CPU0_BCLK0_DN  DIF0#  @S9S_MB_2U_LIB.S9S_MB_2U(SCH_1):CLK_100M_DB2000_CPU0_BCLK0_DN

TPS259520DSGR  I42  U40    [TPS259520DSGR-TPS259520DSGR,SMA]
    7  P3V3_E1S_0_ILM    ILM  @S9S_MB_2U_LIB.S9S_MB_2U(SCH_1):P3V3_E1S_0_ILM
    6  P3V3_E1S_0_FLT_N   FLT#  @S9S_MB_2U_LIB.S9S_MB_2U(SCH_1):P3V3_E1S_0_FLT_N
    1  P3V3_E1S_0_DVDT   DVDT  @S9S_MB_2U_LIB.S9S_MB_2U(SCH_1):P3V3_E1S_0_DVDT
    5  P3V3_E1S_0       OUT  @S9S_MB_2U_LIB.S9S_MB_2U(SCH_1):P3V3_E1S_0
    4  P3V3_AUX         IN2  @S9S_MB_2U_LIB.S9S_MB_2U(SCH_1):P3V3_AUX
    3  P3V3_AUX         IN1  @S9S_MB_2U_LIB.S9S_MB_2U(SCH_1):P3V3_AUX
   TH  GND            TH_GND  @S9S_MB_2U_LIB.S9S_MB_2U(SCH_1):GND
    8  GND              GND  @S9S_MB_2U_LIB.S9S_MB_2U(SCH_1):GND
    2  FM_P3V3_E1S_0_EN  EN||UVLO  @S9S_MB_2U_LIB.S9S_MB_2U(SCH_1):FM_P3V3_E1S_0_EN

MOSFET_N  I177  U49    [MOSFET_N_SMLF-BSS138K,BSS138K,A]
    G  HP_LVC3_OCP_V3_1_PRSNT2_N   GATE  @S9S_MB_2U_LIB.S9S_MB_2U(SCH_1):HP_LVC3_OCP_V3_1_PRSNT2_N
    D  HP_LVC3_OCP_V3_1_PRSNT2  DRAIN  @S9S_MB_2U_LIB.S9S_MB_2U(SCH_1):HP_LVC3_OCP_V3_1_PRSNT2
    S  GND            SOURCE  @S9S_MB_2U_LIB.S9S_MB_2U(SCH_1):GND

SN74LVC1G08DBVR  I175  U50    [SN74LVC1G08DBVR_SMLF-SN74LVC1GA]
    5  P3V3_AUX         VCC  @S9S_MB_2U_LIB.S9S_MB_2U(SCH_1):P3V3_AUX
    1  HP_OCP_V3_1_EN      B  @S9S_MB_2U_LIB.S9S_MB_2U(SCH_1):HP_OCP_V3_1_EN
    2  HP_LVC3_OCP_V3_1_PRSNT2      A  @S9S_MB_2U_LIB.S9S_MB_2U(SCH_1):HP_LVC3_OCP_V3_1_PRSNT2
    4  HP_LVC3_OCP_V3_1_EN      Y  @S9S_MB_2U_LIB.S9S_MB_2U(SCH_1):HP_LVC3_OCP_V3_1_EN
    3  GND              GND  @S9S_MB_2U_LIB.S9S_MB_2U(SCH_1):GND

PCA9555PW  I125  U51    [PCA9555PW_SMLF-PCA9555PW,IC,TMA]
   20  NC               P17  NC
   19  NC               P16  NC
   18  NC               P15  NC
   17  NC               P14  NC
   16  NC               P13  NC
   15  NC               P12  NC
   14  NC               P11  NC
   13  NC               P10  NC
   11  NC               P07  NC
   10  NC               P06  NC
    5  NC               P01  NC
    4  NC               P00  NC
   23  SMB_PEHPCPU0_LVC3_R_SDA    SDA  @S9S_MB_2U_LIB.S9S_MB_2U(SCH_1):SMB_PEHPCPU0_LVC3_R_SDA
   22  SMB_PEHPCPU0_LVC3_R_SCL    SCL  @S9S_MB_2U_LIB.S9S_MB_2U(SCH_1):SMB_PEHPCPU0_LVC3_R_SCL
    3  PD_SMB_OCP1_HP_ADD2     A2  @S9S_MB_2U_LIB.S9S_MB_2U(SCH_1):PD_SMB_OCP1_HP_ADD2
    2  PD_SMB_OCP1_HP_ADD1     A1  @S9S_MB_2U_LIB.S9S_MB_2U(SCH_1):PD_SMB_OCP1_HP_ADD1
   21  PD_SMB_OCP1_HP_ADD0     A0  @S9S_MB_2U_LIB.S9S_MB_2U(SCH_1):PD_SMB_OCP1_HP_ADD0
   24  P3V3_AUX         VDD  @S9S_MB_2U_LIB.S9S_MB_2U(SCH_1):P3V3_AUX
    6  HP_OCP_V3_1_EN    P02  @S9S_MB_2U_LIB.S9S_MB_2U(SCH_1):HP_OCP_V3_1_EN
    8  HP_LVC3_OCP_V3_1_PRSNT2_N    P04  @S9S_MB_2U_LIB.S9S_MB_2U(SCH_1):HP_LVC3_OCP_V3_1_PRSNT2_N
    9  HP_LVC3_OCP_V3_1_FAULT_N    P05  @S9S_MB_2U_LIB.S9S_MB_2U(SCH_1):HP_LVC3_OCP_V3_1_FAULT_N
    7  HP_LVC3_OCP_V3_1_ATTN_OUT_SW_N    P03  @S9S_MB_2U_LIB.S9S_MB_2U(SCH_1):HP_LVC3_OCP_V3_1_ATTN_OUT_SW_N
   12  GND              VSS  @S9S_MB_2U_LIB.S9S_MB_2U(SCH_1):GND
    1  FM_SMB_CPU0_ALERT   INT*  @S9S_MB_2U_LIB.S9S_MB_2U(SCH_1):FM_SMB_CPU0_ALERT

APX80929SAG7  I161  U52    [APX80929SAG7-APX809-29SAG-7,SMA]
    3  P3V3_AUX         VCC  @S9S_MB_2U_LIB.S9S_MB_2U(SCH_1):P3V3_AUX
    2  HP_LVC3_OCP_V3_1_PWRGD  RESET_L  @S9S_MB_2U_LIB.S9S_MB_2U(SCH_1):HP_LVC3_OCP_V3_1_PWRGD
    1  GND              GND  @S9S_MB_2U_LIB.S9S_MB_2U(SCH_1):GND

SN74LVC1G08DBVR  I150  U53    [SN74LVC1G08DBVR_SMLF-SN74LVC1GA]
    2  RST_OCP_V3_1_N      A  @S9S_MB_2U_LIB.S9S_MB_2U(SCH_1):RST_OCP_V3_1_N
    4  RST_HP_OCP_V3_1_N      Y  @S9S_MB_2U_LIB.S9S_MB_2U(SCH_1):RST_HP_OCP_V3_1_N
    5  P3V3_AUX         VCC  @S9S_MB_2U_LIB.S9S_MB_2U(SCH_1):P3V3_AUX
    1  HP_LVC3_OCP_V3_1_PWRGD      B  @S9S_MB_2U_LIB.S9S_MB_2U(SCH_1):HP_LVC3_OCP_V3_1_PWRGD
    3  GND              GND  @S9S_MB_2U_LIB.S9S_MB_2U(SCH_1):GND

74LVC1G07GV  I165  U54    [74LVC1G07GV-74LVC1G07GV,SMLF,IA]
    5  PGPPA_AUX        VCC  @S9S_MB_2U_LIB.S9S_MB_2U(SCH_1):PGPPA_AUX
    1  NC               NC1  NC
    4  M2_SSD0_CLKREQ_LV_EN_N      Y  @S9S_MB_2U_LIB.S9S_MB_2U(SCH_1):M2_SSD0_CLKREQ_LV_EN_N
    2  M2_SSD0_CLKREQ_EN_N      A  @S9S_MB_2U_LIB.S9S_MB_2U(SCH_1):M2_SSD0_CLKREQ_EN_N
    3  GND              GND  @S9S_MB_2U_LIB.S9S_MB_2U(SCH_1):GND

TPS259520DSGR  I350  U56    [TPS259520DSGR-TPS259520DSGR,SMA]
    5  P3V3_OCP_SFF     OUT  @S9S_MB_2U_LIB.S9S_MB_2U(SCH_1):P3V3_OCP_SFF
    7  P3V3_OCP_ILM1    ILM  @S9S_MB_2U_LIB.S9S_MB_2U(SCH_1):P3V3_OCP_ILM1
    1  P3V3_OCP_DVDT_1   DVDT  @S9S_MB_2U_LIB.S9S_MB_2U(SCH_1):P3V3_OCP_DVDT_1
    4  P3V3_AUX         IN2  @S9S_MB_2U_LIB.S9S_MB_2U(SCH_1):P3V3_AUX
    3  P3V3_AUX         IN1  @S9S_MB_2U_LIB.S9S_MB_2U(SCH_1):P3V3_AUX
    6  HP_LVC3_OCP_V3_1_FAULT_N   FLT#  @S9S_MB_2U_LIB.S9S_MB_2U(SCH_1):HP_LVC3_OCP_V3_1_FAULT_N
    2  HP_LVC3_OCP_V3_1_EN  EN||UVLO  @S9S_MB_2U_LIB.S9S_MB_2U(SCH_1):HP_LVC3_OCP_V3_1_EN
   TH  GND            TH_GND  @S9S_MB_2U_LIB.S9S_MB_2U(SCH_1):GND
    8  GND              GND  @S9S_MB_2U_LIB.S9S_MB_2U(SCH_1):GND

TPS259824ONRGER  I377  U57    [TPS259824ONRGER-TPS259824ONRGEA]
   24  P12V_OCP_SFF   OUT_8  @S9S_MB_2U_LIB.S9S_MB_2U(SCH_1):P12V_OCP_SFF
   23  P12V_OCP_SFF   OUT_7  @S9S_MB_2U_LIB.S9S_MB_2U(SCH_1):P12V_OCP_SFF
   22  P12V_OCP_SFF   OUT_6  @S9S_MB_2U_LIB.S9S_MB_2U(SCH_1):P12V_OCP_SFF
   21  P12V_OCP_SFF   OUT_5  @S9S_MB_2U_LIB.S9S_MB_2U(SCH_1):P12V_OCP_SFF
   20  P12V_OCP_SFF   OUT_4  @S9S_MB_2U_LIB.S9S_MB_2U(SCH_1):P12V_OCP_SFF
   19  P12V_OCP_SFF   OUT_3  @S9S_MB_2U_LIB.S9S_MB_2U(SCH_1):P12V_OCP_SFF
   18  P12V_OCP_SFF   OUT_2  @S9S_MB_2U_LIB.S9S_MB_2U(SCH_1):P12V_OCP_SFF
   17  P12V_OCP_SFF   OUT_1  @S9S_MB_2U_LIB.S9S_MB_2U(SCH_1):P12V_OCP_SFF
   10  P12V_OCP_RETRY1  RETRY_DLY  @S9S_MB_2U_LIB.S9S_MB_2U(SCH_1):P12V_OCP_RETRY1
   11  P12V_OCP_NRETRY1  NRETRY  @S9S_MB_2U_LIB.S9S_MB_2U(SCH_1):P12V_OCP_NRETRY1
   12  P12V_OCP_LDSTRT11  LDSTRT  @S9S_MB_2U_LIB.S9S_MB_2U(SCH_1):P12V_OCP_LDSTRT11
    7  P12V_OCP_ITIMER_1  ITIMER  @S9S_MB_2U_LIB.S9S_MB_2U(SCH_1):P12V_OCP_ITIMER_1
    9  P12V_OCP_IMON_1   IMON  @S9S_MB_2U_LIB.S9S_MB_2U(SCH_1):P12V_OCP_IMON_1
    8  P12V_OCP_ILIM1   ILIM  @S9S_MB_2U_LIB.S9S_MB_2U(SCH_1):P12V_OCP_ILIM1
   15  P12V_OCP_DVDT_1   DVDT  @S9S_MB_2U_LIB.S9S_MB_2U(SCH_1):P12V_OCP_DVDT_1
   25  P12V_AUX       IN_TH1  @S9S_MB_2U_LIB.S9S_MB_2U(SCH_1):P12V_AUX
   16  P12V_AUX        IN_4  @S9S_MB_2U_LIB.S9S_MB_2U(SCH_1):P12V_AUX
    3  P12V_AUX        IN_3  @S9S_MB_2U_LIB.S9S_MB_2U(SCH_1):P12V_AUX
    2  P12V_AUX        IN_2  @S9S_MB_2U_LIB.S9S_MB_2U(SCH_1):P12V_AUX
    1  P12V_AUX        IN_1  @S9S_MB_2U_LIB.S9S_MB_2U(SCH_1):P12V_AUX
   13  HP_LVC3_OCP_V3_1_HSC_PWRGD     PG  @S9S_MB_2U_LIB.S9S_MB_2U(SCH_1):HP_LVC3_OCP_V3_1_HSC_PWRGD
    6  HP_LVC3_OCP_V3_1_EN  EN||UVLO  @S9S_MB_2U_LIB.S9S_MB_2U(SCH_1):HP_LVC3_OCP_V3_1_EN
   26  GND            GND_TH2  @S9S_MB_2U_LIB.S9S_MB_2U(SCH_1):GND
   14  GND            GND_3  @S9S_MB_2U_LIB.S9S_MB_2U(SCH_1):GND
    5  GND            GND_2  @S9S_MB_2U_LIB.S9S_MB_2U(SCH_1):GND
    4  GND            GND_1  @S9S_MB_2U_LIB.S9S_MB_2U(SCH_1):GND

SN74LVC2G07DCKR  I397  U58    [SN74LVC2G07DCKR_SMLF-SN74LVC2GA]
    5  P3V3_AUX         VCC  @S9S_MB_2U_LIB.S9S_MB_2U(SCH_1):P3V3_AUX
    3  OCP_SFF_PRSNT1_R_N     2A  @S9S_MB_2U_LIB.S9S_MB_2U(SCH_1):OCP_SFF_PRSNT1_R_N
    1  OCP_SFF_PRSNT0_R_N     1A  @S9S_MB_2U_LIB.S9S_MB_2U(SCH_1):OCP_SFF_PRSNT0_R_N
    4  HP_LVC3_OCP_V3_1_PRSNT2_N_R     2Y  @S9S_MB_2U_LIB.S9S_MB_2U(SCH_1):HP_LVC3_OCP_V3_1_PRSNT2_N_R
    6  HP_LVC3_OCP_V3_1_PRSNT2_N_R     1Y  @S9S_MB_2U_LIB.S9S_MB_2U(SCH_1):HP_LVC3_OCP_V3_1_PRSNT2_N_R
    2  GND              GND  @S9S_MB_2U_LIB.S9S_MB_2U(SCH_1):GND

SN74LVC2G07DCKR  I400  U59    [SN74LVC2G07DCKR_SMLF-SN74LVC2GA]
    5  P3V3_AUX         VCC  @S9S_MB_2U_LIB.S9S_MB_2U(SCH_1):P3V3_AUX
    3  OCP_SFF_PRSNT3_R_N     2A  @S9S_MB_2U_LIB.S9S_MB_2U(SCH_1):OCP_SFF_PRSNT3_R_N
    1  OCP_SFF_PRSNT2_R_N     1A  @S9S_MB_2U_LIB.S9S_MB_2U(SCH_1):OCP_SFF_PRSNT2_R_N
    4  HP_LVC3_OCP_V3_1_PRSNT2_N_R     2Y  @S9S_MB_2U_LIB.S9S_MB_2U(SCH_1):HP_LVC3_OCP_V3_1_PRSNT2_N_R
    6  HP_LVC3_OCP_V3_1_PRSNT2_N_R     1Y  @S9S_MB_2U_LIB.S9S_MB_2U(SCH_1):HP_LVC3_OCP_V3_1_PRSNT2_N_R
    2  GND              GND  @S9S_MB_2U_LIB.S9S_MB_2U(SCH_1):GND

NC7SB3157  I34  U60    [NC7SB3157_SMLF-NC7SB3157P6X,NCA]
    5  PGPPA_AUX        VCC  @S9S_MB_2U_LIB.S9S_MB_2U(SCH_1):PGPPA_AUX
    3  IRQ_LPC_SERIRQ_ESPI_CS1_N     B0  @S9S_MB_2U_LIB.S9S_MB_2U(SCH_1):IRQ_LPC_SERIRQ_ESPI_CS1_N
    1  IRQ_LPC_PIRQA_N_ESPI_ALERT0_R_N     B1  @S9S_MB_2U_LIB.S9S_MB_2U(SCH_1):IRQ_LPC_PIRQA_N_ESPI_ALERT0_R_N
    4  IRQ_ESPI_LPC_SERIRQ_ALERT_N      A  @S9S_MB_2U_LIB.S9S_MB_2U(SCH_1):IRQ_ESPI_LPC_SERIRQ_ALERT_N
    2  GND              GND  @S9S_MB_2U_LIB.S9S_MB_2U(SCH_1):GND
    6  FM_ESPI_PLD_EN      S  @S9S_MB_2U_LIB.S9S_MB_2U(SCH_1):FM_ESPI_PLD_EN

NC7SB3157  I39  U61    [NC7SB3157_SMLF-NC7SB3157P6X,NCA]
    3  RST_PLTRST_B_MUX_N     B0  @S9S_MB_2U_LIB.S9S_MB_2U(SCH_1):RST_PLTRST_B_MUX_N
    1  RST_ESPI_RESET_N     B1  @S9S_MB_2U_LIB.S9S_MB_2U(SCH_1):RST_ESPI_RESET_N
    5  PGPPA_AUX        VCC  @S9S_MB_2U_LIB.S9S_MB_2U(SCH_1):PGPPA_AUX
    2  GND              GND  @S9S_MB_2U_LIB.S9S_MB_2U(SCH_1):GND
    6  FM_ESPI_PLD_EN      S  @S9S_MB_2U_LIB.S9S_MB_2U(SCH_1):FM_ESPI_PLD_EN
    4  ESPI_BMC_LPC_RST_N      A  @S9S_MB_2U_LIB.S9S_MB_2U(SCH_1):ESPI_BMC_LPC_RST_N

BAS70057F  I64  U62    [BAS70057F-BAS70-05-7-F,SMLF,ICA]
    1  P3V_BAT_R          B  @S9S_MB_2U_LIB.S9S_MB_2U(SCH_1):P3V_BAT_R
    3  P3V3_RTC_AUX       C  @S9S_MB_2U_LIB.S9S_MB_2U(SCH_1):P3V3_RTC_AUX
    2  P3V3_AUX           A  @S9S_MB_2U_LIB.S9S_MB_2U(SCH_1):P3V3_AUX

TMP75AIDR  I1   U63    [TMP75AIDR-TMP75AIDR,SMLF,IC,ALA]
    3  NC             ALERT  NC
    5  TMP75_1_ADDR2     A2  @S9S_MB_2U_LIB.S9S_MB_2U(SCH_1):TMP75_1_ADDR2
    6  TMP75_1_ADDR1     A1  @S9S_MB_2U_LIB.S9S_MB_2U(SCH_1):TMP75_1_ADDR1
    7  TMP75_1_ADDR0     A0  @S9S_MB_2U_LIB.S9S_MB_2U(SCH_1):TMP75_1_ADDR0
    1  SMB_TMP75_1_3V3AUX_SDA_R    SDA  @S9S_MB_2U_LIB.S9S_MB_2U(SCH_1):SMB_TMP75_1_3V3AUX_SDA_R
    2  SMB_TMP75_1_3V3AUX_SCL_R    SCL  @S9S_MB_2U_LIB.S9S_MB_2U(SCH_1):SMB_TMP75_1_3V3AUX_SCL_R
    8  P3V3_AUX         VCC  @S9S_MB_2U_LIB.S9S_MB_2U(SCH_1):P3V3_AUX
    4  GND              GND  @S9S_MB_2U_LIB.S9S_MB_2U(SCH_1):GND

M24128BWDW6TP  I35  U64    [M24128BWDW6TP-M24128-BWDW6TP,SA]
    5  SMB_FRU_3V3AUX_SDA_R    SDA  @S9S_MB_2U_LIB.S9S_MB_2U(SCH_1):SMB_FRU_3V3AUX_SDA_R
    6  SMB_FRU_3V3AUX_SCL_R    SCL  @S9S_MB_2U_LIB.S9S_MB_2U(SCH_1):SMB_FRU_3V3AUX_SCL_R
    7  PD_MB_FRU_WP     WC#  @S9S_MB_2U_LIB.S9S_MB_2U(SCH_1):PD_MB_FRU_WP
    8  P3V3_AUX         VCC  @S9S_MB_2U_LIB.S9S_MB_2U(SCH_1):P3V3_AUX
    3  MB_FRU_ADDR2      E2  @S9S_MB_2U_LIB.S9S_MB_2U(SCH_1):MB_FRU_ADDR2
    2  MB_FRU_ADDR1      E1  @S9S_MB_2U_LIB.S9S_MB_2U(SCH_1):MB_FRU_ADDR1
    1  MB_FRU_ADDR0      E0  @S9S_MB_2U_LIB.S9S_MB_2U(SCH_1):MB_FRU_ADDR0
    4  GND              VSS  @S9S_MB_2U_LIB.S9S_MB_2U(SCH_1):GND

TMP75AIDR  I84  U65    [TMP75AIDR-TMP75AIDR,SMLF,IC,ALA]
    3  NC             ALERT  NC
    5  TMP75_2_ADDR2     A2  @S9S_MB_2U_LIB.S9S_MB_2U(SCH_1):TMP75_2_ADDR2
    6  TMP75_2_ADDR1     A1  @S9S_MB_2U_LIB.S9S_MB_2U(SCH_1):TMP75_2_ADDR1
    7  TMP75_2_ADDR0     A0  @S9S_MB_2U_LIB.S9S_MB_2U(SCH_1):TMP75_2_ADDR0
    1  SMB_TMP75_2_3V3AUX_SDA_R    SDA  @S9S_MB_2U_LIB.S9S_MB_2U(SCH_1):SMB_TMP75_2_3V3AUX_SDA_R
    2  SMB_TMP75_2_3V3AUX_SCL_R    SCL  @S9S_MB_2U_LIB.S9S_MB_2U(SCH_1):SMB_TMP75_2_3V3AUX_SCL_R
    8  P3V3_AUX         VCC  @S9S_MB_2U_LIB.S9S_MB_2U(SCH_1):P3V3_AUX
    4  GND              GND  @S9S_MB_2U_LIB.S9S_MB_2U(SCH_1):GND

74HC1G126GW  I53  U66    [74HC1G126GW-74HC1G126GW,SMLF,IA]
    5  P3V3_AUX           5  @S9S_MB_2U_LIB.S9S_MB_2U(SCH_1):P3V3_AUX
    1  OCP_SFF_AUX_PWR_EN_R1      1  @S9S_MB_2U_LIB.S9S_MB_2U(SCH_1):OCP_SFF_AUX_PWR_EN_R1
    3  GND              GND  @S9S_MB_2U_LIB.S9S_MB_2U(SCH_1):GND
    2  FM_OCP_SFF_PWR_GOOD      2  @S9S_MB_2U_LIB.S9S_MB_2U(SCH_1):FM_OCP_SFF_PWR_GOOD
    4  FB_BMC_ISOLATE      4  @S9S_MB_2U_LIB.S9S_MB_2U(SCH_1):FB_BMC_ISOLATE

74CBTLV3126PW  I1   U67    [74CBTLV3126PW-74CBTLV3126PW,SMA]
   14  P3V3_AUX         VCC  @S9S_MB_2U_LIB.S9S_MB_2U(SCH_1):P3V3_AUX
   11  OCP_SFF_RBT_ARB_IN     4B  @S9S_MB_2U_LIB.S9S_MB_2U(SCH_1):OCP_SFF_RBT_ARB_IN
   12  OCP_SFF_RBT_ARB_IN     4A  @S9S_MB_2U_LIB.S9S_MB_2U(SCH_1):OCP_SFF_RBT_ARB_IN
    3  NCSI_OCP_SFF_RXD1     1B  @S9S_MB_2U_LIB.S9S_MB_2U(SCH_1):NCSI_OCP_SFF_RXD1
    6  NCSI_OCP_SFF_RXD0     2B  @S9S_MB_2U_LIB.S9S_MB_2U(SCH_1):NCSI_OCP_SFF_RXD0
    8  NCSI_OCP_SFF_CRS_DV     3B  @S9S_MB_2U_LIB.S9S_MB_2U(SCH_1):NCSI_OCP_SFF_CRS_DV
    2  NCSI_BMC_RXD1_R     1A  @S9S_MB_2U_LIB.S9S_MB_2U(SCH_1):NCSI_BMC_RXD1_R
    5  NCSI_BMC_RXD0_R     2A  @S9S_MB_2U_LIB.S9S_MB_2U(SCH_1):NCSI_BMC_RXD0_R
    9  NCSI_BMC_CRS_DV_R     3A  @S9S_MB_2U_LIB.S9S_MB_2U(SCH_1):NCSI_BMC_CRS_DV_R
    7  GND              GND  @S9S_MB_2U_LIB.S9S_MB_2U(SCH_1):GND
   13  FB_BMC_ISOLATE    4OE  @S9S_MB_2U_LIB.S9S_MB_2U(SCH_1):FB_BMC_ISOLATE
   10  FB_BMC_ISOLATE    3OE  @S9S_MB_2U_LIB.S9S_MB_2U(SCH_1):FB_BMC_ISOLATE
    4  FB_BMC_ISOLATE    2OE  @S9S_MB_2U_LIB.S9S_MB_2U(SCH_1):FB_BMC_ISOLATE
    1  FB_BMC_ISOLATE    1OE  @S9S_MB_2U_LIB.S9S_MB_2U(SCH_1):FB_BMC_ISOLATE

74CBTLV3126PW  I2   U68    [74CBTLV3126PW-74CBTLV3126PW,SMA]
   14  P3V3_AUX         VCC  @S9S_MB_2U_LIB.S9S_MB_2U(SCH_1):P3V3_AUX
   11  OCP_SFF_RBT_ARB_OUT     4B  @S9S_MB_2U_LIB.S9S_MB_2U(SCH_1):OCP_SFF_RBT_ARB_OUT
   12  OCP_SFF_RBT_ARB_OUT     4A  @S9S_MB_2U_LIB.S9S_MB_2U(SCH_1):OCP_SFF_RBT_ARB_OUT
    8  NCSI_OCP_SFF_TX_EN     3B  @S9S_MB_2U_LIB.S9S_MB_2U(SCH_1):NCSI_OCP_SFF_TX_EN
    3  NCSI_OCP_SFF_TXD1     1B  @S9S_MB_2U_LIB.S9S_MB_2U(SCH_1):NCSI_OCP_SFF_TXD1
    6  NCSI_OCP_SFF_TXD0     2B  @S9S_MB_2U_LIB.S9S_MB_2U(SCH_1):NCSI_OCP_SFF_TXD0
    9  NCSI_BMC_TX_EN_R     3A  @S9S_MB_2U_LIB.S9S_MB_2U(SCH_1):NCSI_BMC_TX_EN_R
    2  NCSI_BMC_TXD1_R     1A  @S9S_MB_2U_LIB.S9S_MB_2U(SCH_1):NCSI_BMC_TXD1_R
    5  NCSI_BMC_TXD0_R     2A  @S9S_MB_2U_LIB.S9S_MB_2U(SCH_1):NCSI_BMC_TXD0_R
    7  GND              GND  @S9S_MB_2U_LIB.S9S_MB_2U(SCH_1):GND
   13  FB_BMC_ISOLATE    4OE  @S9S_MB_2U_LIB.S9S_MB_2U(SCH_1):FB_BMC_ISOLATE
   10  FB_BMC_ISOLATE    3OE  @S9S_MB_2U_LIB.S9S_MB_2U(SCH_1):FB_BMC_ISOLATE
    4  FB_BMC_ISOLATE    2OE  @S9S_MB_2U_LIB.S9S_MB_2U(SCH_1):FB_BMC_ISOLATE
    1  FB_BMC_ISOLATE    1OE  @S9S_MB_2U_LIB.S9S_MB_2U(SCH_1):FB_BMC_ISOLATE

MOSFET_N  I19  U70    [MOSFET_N_SMLF-BSS138K,BSS138K,A]
    S  GND            SOURCE  @S9S_MB_2U_LIB.S9S_MB_2U(SCH_1):GND
    D  FM_PLD_CLKS_OE_R_N  DRAIN  @S9S_MB_2U_LIB.S9S_MB_2U(SCH_1):FM_PLD_CLKS_OE_R_N
    G  FM_PLD_CLKS_DEV_EN   GATE  @S9S_MB_2U_LIB.S9S_MB_2U(SCH_1):FM_PLD_CLKS_DEV_EN

MOSFET_N  I50  U73    [MOSFET_N_SMLF-BSS138K,BSS138K,B]
    S  SH_PVPP_HBM_CPU0_N  SOURCE  @S9S_MB_2U_LIB.S9S_MB_2U(SCH_1):SH_PVPP_HBM_CPU0_N
    D  FM_HBM_VPP_SEL_CPU0_D  DRAIN  @S9S_MB_2U_LIB.S9S_MB_2U(SCH_1):FM_HBM_VPP_SEL_CPU0_D
    G  FM_HBM2_HBM3_VPP_SEL   GATE  @S9S_MB_2U_LIB.S9S_MB_2U(SCH_1):FM_HBM2_HBM3_VPP_SEL

MOSFET_N  I50  U74    [MOSFET_N_SMLF-BSS138K,BSS138K,A]
    S  SH_PVPP_HBM_CPU1_N  SOURCE  @S9S_MB_2U_LIB.S9S_MB_2U(SCH_1):SH_PVPP_HBM_CPU1_N
    D  FM_HBM_VPP_SEL_CPU1_D  DRAIN  @S9S_MB_2U_LIB.S9S_MB_2U(SCH_1):FM_HBM_VPP_SEL_CPU1_D
    G  FM_HBM2_HBM3_VPP_SEL   GATE  @S9S_MB_2U_LIB.S9S_MB_2U(SCH_1):FM_HBM2_HBM3_VPP_SEL

SN74LVC1G17DCKR  I1   U75    [SN74LVC1G17DCKR-SN74LVC1G17DCKA]
    4  RST_OCP_V3_1_BUF_N      Y  @S9S_MB_2U_LIB.S9S_MB_2U(SCH_1):RST_OCP_V3_1_BUF_N
    2  RST_HP_OCP_V3_1_N      A  @S9S_MB_2U_LIB.S9S_MB_2U(SCH_1):RST_HP_OCP_V3_1_N
    5  P3V3_AUX         VCC  @S9S_MB_2U_LIB.S9S_MB_2U(SCH_1):P3V3_AUX
    1  NC                NC  NC
    3  GND              GND  @S9S_MB_2U_LIB.S9S_MB_2U(SCH_1):GND

74CBTLV3126PW  I105  U77    [74CBTLV3126PW-74CBTLV3126PW,SMB]
   13  NC               4OE  NC
   11  NC                4B  NC
   12  NC                4A  NC
   14  P3V3_AUX         VCC  @S9S_MB_2U_LIB.S9S_MB_2U(SCH_1):P3V3_AUX
    3  OCP_SFF_ISO_BIF2_EN     1B  @S9S_MB_2U_LIB.S9S_MB_2U(SCH_1):OCP_SFF_ISO_BIF2_EN
    6  OCP_SFF_ISO_BIF1_EN     2B  @S9S_MB_2U_LIB.S9S_MB_2U(SCH_1):OCP_SFF_ISO_BIF1_EN
    8  OCP_SFF_ISO_BIF0_EN     3B  @S9S_MB_2U_LIB.S9S_MB_2U(SCH_1):OCP_SFF_ISO_BIF0_EN
    2  OCP_SFF_BIF2_N     1A  @S9S_MB_2U_LIB.S9S_MB_2U(SCH_1):OCP_SFF_BIF2_N
    5  OCP_SFF_BIF1_N     2A  @S9S_MB_2U_LIB.S9S_MB_2U(SCH_1):OCP_SFF_BIF1_N
    9  OCP_SFF_BIF0_N     3A  @S9S_MB_2U_LIB.S9S_MB_2U(SCH_1):OCP_SFF_BIF0_N
   10  OCP_SFF_AUX_PWR_EN_R2    3OE  @S9S_MB_2U_LIB.S9S_MB_2U(SCH_1):OCP_SFF_AUX_PWR_EN_R2
    4  OCP_SFF_AUX_PWR_EN_R2    2OE  @S9S_MB_2U_LIB.S9S_MB_2U(SCH_1):OCP_SFF_AUX_PWR_EN_R2
    1  OCP_SFF_AUX_PWR_EN_R2    1OE  @S9S_MB_2U_LIB.S9S_MB_2U(SCH_1):OCP_SFF_AUX_PWR_EN_R2
    7  GND              GND  @S9S_MB_2U_LIB.S9S_MB_2U(SCH_1):GND

SLG55221120010VTR  I62  U79    [SLG55221120010VTR-SLG55221-120A]
    7  VR_P3V3_EN_D_R  G1/G2  @S9S_MB_2U_LIB.S9S_MB_2U(SCH_1):VR_P3V3_EN_D_R
    2  PWRGD_P5V         ON  @S9S_MB_2U_LIB.S9S_MB_2U(SCH_1):PWRGD_P5V
    8  PWRGD_P3V3_R      PG  @S9S_MB_2U_LIB.S9S_MB_2U(SCH_1):PWRGD_P3V3_R
    1  P5V_AUX          VCC  @S9S_MB_2U_LIB.S9S_MB_2U(SCH_1):P5V_AUX
    5  P3V3_AUX           D  @S9S_MB_2U_LIB.S9S_MB_2U(SCH_1):P3V3_AUX
    6  P3V3           S/DIS1  @S9S_MB_2U_LIB.S9S_MB_2U(SCH_1):P3V3
    3  P3V3            DIS2  @S9S_MB_2U_LIB.S9S_MB_2U(SCH_1):P3V3
   TH  GND               TH  @S9S_MB_2U_LIB.S9S_MB_2U(SCH_1):GND
    4  GND              GND  @S9S_MB_2U_LIB.S9S_MB_2U(SCH_1):GND

MP5981GLUZ  I66  U81    [MP5981GLUZ-MP5981GLU-Z,SMLF,ICA]
   21  VDD3            VDD3  @S9S_MB_2U_LIB.S9S_MB_2U(SCH_1):VDD3
   18  NC             VTEMP  NC
   22  TP_MP5981_1_IMON   IMON  @S9S_MB_2U_LIB.S9S_MB_2U(SCH_1):TP_MP5981_1_IMON
    5  PU_MP5981_1_GOK    GOK  @S9S_MB_2U_LIB.S9S_MB_2U(SCH_1):PU_MP5981_1_GOK
    3  PU_MP5981_1_D_OC   D_OC  @S9S_MB_2U_LIB.S9S_MB_2U(SCH_1):PU_MP5981_1_D_OC
    8  PD_MP5981_1_MODE   MODE  @S9S_MB_2U_LIB.S9S_MB_2U(SCH_1):PD_MP5981_1_MODE
   32  P12V_FRONT_CPU  VOUT_32  @S9S_MB_2U_LIB.S9S_MB_2U(SCH_1):P12V_FRONT_CPU
   31  P12V_FRONT_CPU  VOUT_31  @S9S_MB_2U_LIB.S9S_MB_2U(SCH_1):P12V_FRONT_CPU
   30  P12V_FRONT_CPU  VOUT_30  @S9S_MB_2U_LIB.S9S_MB_2U(SCH_1):P12V_FRONT_CPU
   29  P12V_FRONT_CPU  VOUT_29  @S9S_MB_2U_LIB.S9S_MB_2U(SCH_1):P12V_FRONT_CPU
   28  P12V_FRONT_CPU  VOUT_28  @S9S_MB_2U_LIB.S9S_MB_2U(SCH_1):P12V_FRONT_CPU
   27  P12V_FRONT_CPU  VOUT_27  @S9S_MB_2U_LIB.S9S_MB_2U(SCH_1):P12V_FRONT_CPU
   26  P12V_FRONT_CPU  VOUT_26  @S9S_MB_2U_LIB.S9S_MB_2U(SCH_1):P12V_FRONT_CPU
   25  P12V_FRONT_CPU  VOUT_25  @S9S_MB_2U_LIB.S9S_MB_2U(SCH_1):P12V_FRONT_CPU
    2  P12V_FRONT_CPU  VOUT_2  @S9S_MB_2U_LIB.S9S_MB_2U(SCH_1):P12V_FRONT_CPU
    1  P12V_FRONT_CPU  VOUT_1  @S9S_MB_2U_LIB.S9S_MB_2U(SCH_1):P12V_FRONT_CPU
   16  P12V_AUX       VIN_16  @S9S_MB_2U_LIB.S9S_MB_2U(SCH_1):P12V_AUX
   15  P12V_AUX       VIN_15  @S9S_MB_2U_LIB.S9S_MB_2U(SCH_1):P12V_AUX
   14  P12V_AUX       VIN_14  @S9S_MB_2U_LIB.S9S_MB_2U(SCH_1):P12V_AUX
   13  P12V_AUX       VIN_13  @S9S_MB_2U_LIB.S9S_MB_2U(SCH_1):P12V_AUX
   12  P12V_AUX       VIN_12  @S9S_MB_2U_LIB.S9S_MB_2U(SCH_1):P12V_AUX
   11  P12V_AUX       VIN_11  @S9S_MB_2U_LIB.S9S_MB_2U(SCH_1):P12V_AUX
   10  P12V_AUX       VIN_10  @S9S_MB_2U_LIB.S9S_MB_2U(SCH_1):P12V_AUX
    9  P12V_AUX       VIN_9  @S9S_MB_2U_LIB.S9S_MB_2U(SCH_1):P12V_AUX
   19  MPS5981_1_SS      SS  @S9S_MB_2U_LIB.S9S_MB_2U(SCH_1):MPS5981_1_SS
    4  MP5981_1_ON_PD  ON||PD  @S9S_MB_2U_LIB.S9S_MB_2U(SCH_1):MP5981_1_ON_PD
   23  MP5981_1_CS       CS  @S9S_MB_2U_LIB.S9S_MB_2U(SCH_1):MP5981_1_CS
   24  MP5981_1_CLREF  CLREF  @S9S_MB_2U_LIB.S9S_MB_2U(SCH_1):MP5981_1_CLREF
   TH  GND            VIN_TH  @S9S_MB_2U_LIB.S9S_MB_2U(SCH_1):GND
   17  GND              NC3  @S9S_MB_2U_LIB.S9S_MB_2U(SCH_1):GND
    7  GND              NC2  @S9S_MB_2U_LIB.S9S_MB_2U(SCH_1):GND
    6  GND              NC1  @S9S_MB_2U_LIB.S9S_MB_2U(SCH_1):GND
   20  GND              GND  @S9S_MB_2U_LIB.S9S_MB_2U(SCH_1):GND

74LVC1G126GW  I35  U82    [74LVC1G126GW_SMLF-74LVC1G126GWA]
    1  PU_OCP_SFF_WAKE_OE     OE  @S9S_MB_2U_LIB.S9S_MB_2U(SCH_1):PU_OCP_SFF_WAKE_OE
    5  P3V3_AUX         VCC  @S9S_MB_2U_LIB.S9S_MB_2U(SCH_1):P3V3_AUX
    4  OCP_SFF_WAKE_BUFF_N      Y  @S9S_MB_2U_LIB.S9S_MB_2U(SCH_1):OCP_SFF_WAKE_BUFF_N
    2  IRQ_LVC3_OCP_SFF_WAKE_N      A  @S9S_MB_2U_LIB.S9S_MB_2U(SCH_1):IRQ_LVC3_OCP_SFF_WAKE_N
    3  GND              GND  @S9S_MB_2U_LIB.S9S_MB_2U(SCH_1):GND

GTL2014PW  I45  U83    [GTL2014PW-GTL2014PW,SMLF,IC,ALA]
   10  NC                A2  NC
   13  NC                A0  NC
    1  PU_GTL2014_BMC_JTAG_DIR_2    DIR  @S9S_MB_2U_LIB.S9S_MB_2U(SCH_1):PU_GTL2014_BMC_JTAG_DIR_2
    5  PD_JTAG_DBP_B2     B2  @S9S_MB_2U_LIB.S9S_MB_2U(SCH_1):PD_JTAG_DBP_B2
    2  PD_JTAG_DBP_B0     B0  @S9S_MB_2U_LIB.S9S_MB_2U(SCH_1):PD_JTAG_DBP_B0
    4  PD_GTL2014_BMC_JTAG_VREF_2   VREF  @S9S_MB_2U_LIB.S9S_MB_2U(SCH_1):PD_GTL2014_BMC_JTAG_VREF_2
   14  P3V3_AUX         VCC  @S9S_MB_2U_LIB.S9S_MB_2U(SCH_1):P3V3_AUX
    3  JTAG_DBP_PRDY_R_N     B1  @S9S_MB_2U_LIB.S9S_MB_2U(SCH_1):JTAG_DBP_PRDY_R_N
    6  JTAG_DBP_FB_TDO     B3  @S9S_MB_2U_LIB.S9S_MB_2U(SCH_1):JTAG_DBP_FB_TDO
   12  JTAG_DBP_BMC_PRDY_R1_N     A1  @S9S_MB_2U_LIB.S9S_MB_2U(SCH_1):JTAG_DBP_BMC_PRDY_R1_N
    9  JTAG_BMC_DBP_TDO_R     A3  @S9S_MB_2U_LIB.S9S_MB_2U(SCH_1):JTAG_BMC_DBP_TDO_R
   11  GND            GND_2  @S9S_MB_2U_LIB.S9S_MB_2U(SCH_1):GND
    8  GND            GND_1  @S9S_MB_2U_LIB.S9S_MB_2U(SCH_1):GND
    7  GND            GND_0  @S9S_MB_2U_LIB.S9S_MB_2U(SCH_1):GND

GTL2014PW  I18  U84    [GTL2014PW-GTL2014PW,SMLF,IC,ALA]
    1  PU_GTL2014_BMC_JTAG_DIR_1    DIR  @S9S_MB_2U_LIB.S9S_MB_2U(SCH_1):PU_GTL2014_BMC_JTAG_DIR_1
    4  PD_GTL2014_BMC_JTAG_VREF_1   VREF  @S9S_MB_2U_LIB.S9S_MB_2U(SCH_1):PD_GTL2014_BMC_JTAG_VREF_1
   14  P3V3_AUX         VCC  @S9S_MB_2U_LIB.S9S_MB_2U(SCH_1):P3V3_AUX
    2  JTAG_DBP_PREQ_R_N     B0  @S9S_MB_2U_LIB.S9S_MB_2U(SCH_1):JTAG_DBP_PREQ_R_N
    6  JTAG_DBP_FB_TMS     B3  @S9S_MB_2U_LIB.S9S_MB_2U(SCH_1):JTAG_DBP_FB_TMS
    5  JTAG_DBP_FB_TDI     B2  @S9S_MB_2U_LIB.S9S_MB_2U(SCH_1):JTAG_DBP_FB_TDI
   13  JTAG_DBP_BMC_PREQ_R1_N     A0  @S9S_MB_2U_LIB.S9S_MB_2U(SCH_1):JTAG_DBP_BMC_PREQ_R1_N
    9  JTAG_BMC_DBP_TMS_R     A3  @S9S_MB_2U_LIB.S9S_MB_2U(SCH_1):JTAG_BMC_DBP_TMS_R
   10  JTAG_BMC_DBP_TDI_R     A2  @S9S_MB_2U_LIB.S9S_MB_2U(SCH_1):JTAG_BMC_DBP_TDI_R
   11  GND            GND_2  @S9S_MB_2U_LIB.S9S_MB_2U(SCH_1):GND
    8  GND            GND_1  @S9S_MB_2U_LIB.S9S_MB_2U(SCH_1):GND
    7  GND            GND_0  @S9S_MB_2U_LIB.S9S_MB_2U(SCH_1):GND
    3  FM_CPU_FBRK_DEBUG_N     B1  @S9S_MB_2U_LIB.S9S_MB_2U(SCH_1):FM_CPU_FBRK_DEBUG_N
   12  FM_BMC_CPU_FBRK_OUT_N     A1  @S9S_MB_2U_LIB.S9S_MB_2U(SCH_1):FM_BMC_CPU_FBRK_OUT_N

NC7SB3157  I109  U85    [NC7SB3157_SMLF-NC7SB3157P6X,NCA]
    5  P3V3_AUX         VCC  @S9S_MB_2U_LIB.S9S_MB_2U(SCH_1):P3V3_AUX
    1  JTAG_BMC_PCH_TCK     B1  @S9S_MB_2U_LIB.S9S_MB_2U(SCH_1):JTAG_BMC_PCH_TCK
    4  JTAG_BMC_DBP_TCK      A  @S9S_MB_2U_LIB.S9S_MB_2U(SCH_1):JTAG_BMC_DBP_TCK
    3  JTAG_BMC_CPU_TCK     B0  @S9S_MB_2U_LIB.S9S_MB_2U(SCH_1):JTAG_BMC_CPU_TCK
    2  GND              GND  @S9S_MB_2U_LIB.S9S_MB_2U(SCH_1):GND
    6  FM_JTAG_TCK_MUX_SEL      S  @S9S_MB_2U_LIB.S9S_MB_2U(SCH_1):FM_JTAG_TCK_MUX_SEL

74CBTLV3126PW  I84  U86    [74CBTLV3126PW-74CBTLV3126PW,SMA]
   11  NC                4B  NC
    3  NC                1B  NC
   13  PD_JTAG_BMC_NTRST_N    4OE  @S9S_MB_2U_LIB.S9S_MB_2U(SCH_1):PD_JTAG_BMC_NTRST_N
    1  PD_JTAG_BMC_NTRST_N    1OE  @S9S_MB_2U_LIB.S9S_MB_2U(SCH_1):PD_JTAG_BMC_NTRST_N
   14  P3V3_AUX         VCC  @S9S_MB_2U_LIB.S9S_MB_2U(SCH_1):P3V3_AUX
    8  JTAG_DBP_TCK_PCH_R     3B  @S9S_MB_2U_LIB.S9S_MB_2U(SCH_1):JTAG_DBP_TCK_PCH_R
    6  JTAG_DBP_CPU_GTL_TCK_R1     2B  @S9S_MB_2U_LIB.S9S_MB_2U(SCH_1):JTAG_DBP_CPU_GTL_TCK_R1
   10  JTAG_BMC_PCH_TCK    3OE  @S9S_MB_2U_LIB.S9S_MB_2U(SCH_1):JTAG_BMC_PCH_TCK
    4  JTAG_BMC_CPU_TCK    2OE  @S9S_MB_2U_LIB.S9S_MB_2U(SCH_1):JTAG_BMC_CPU_TCK
    7  GND              GND  @S9S_MB_2U_LIB.S9S_MB_2U(SCH_1):GND
   12  FM_BMC_EN_DET     4A  @S9S_MB_2U_LIB.S9S_MB_2U(SCH_1):FM_BMC_EN_DET
    9  FM_BMC_EN_DET     3A  @S9S_MB_2U_LIB.S9S_MB_2U(SCH_1):FM_BMC_EN_DET
    5  FM_BMC_EN_DET     2A  @S9S_MB_2U_LIB.S9S_MB_2U(SCH_1):FM_BMC_EN_DET
    2  FM_BMC_EN_DET     1A  @S9S_MB_2U_LIB.S9S_MB_2U(SCH_1):FM_BMC_EN_DET

MOSFET_N  I96  U87    [MOSFET_N_SMLF-BSS138K,BSS138K,A]
    D  P1V05_PCH_AUX  DRAIN  @S9S_MB_2U_LIB.S9S_MB_2U(SCH_1):P1V05_PCH_AUX
    G  FM_REMOTE_DEBUG_DET_R   GATE  @S9S_MB_2U_LIB.S9S_MB_2U(SCH_1):FM_REMOTE_DEBUG_DET_R
    S  FM_BMC_EN_DET  SOURCE  @S9S_MB_2U_LIB.S9S_MB_2U(SCH_1):FM_BMC_EN_DET

MOSFET_N  I236  U89    [MOSFET_N_SMLF-BSS138K,BSS138K,A]
    S  GND            SOURCE  @S9S_MB_2U_LIB.S9S_MB_2U(SCH_1):GND
    D  FM_PLD_HEARTBEAT_LVC3_D  DRAIN  @S9S_MB_2U_LIB.S9S_MB_2U(SCH_1):FM_PLD_HEARTBEAT_LVC3_D
    G  FM_PLD_HEARTBEAT_LVC3   GATE  @S9S_MB_2U_LIB.S9S_MB_2U(SCH_1):FM_PLD_HEARTBEAT_LVC3

PI6CV304LE  I46  U90    [PI6CV304LE-PI6CV304LE,SMLF,IC,A]
    8  NC                Y3  NC
    7  NC                Y2  NC
    6  P3V3_AUX         VDD  @S9S_MB_2U_LIB.S9S_MB_2U(SCH_1):P3V3_AUX
    4  GND              GND  @S9S_MB_2U_LIB.S9S_MB_2U(SCH_1):GND
    1  CLK_50M_RMII_R  CLK_IN  @S9S_MB_2U_LIB.S9S_MB_2U(SCH_1):CLK_50M_RMII_R
    5  CLK_50M_NCSI_OCP_1     Y1  @S9S_MB_2U_LIB.S9S_MB_2U(SCH_1):CLK_50M_NCSI_OCP_1
    2  CLK_50M_EN        OE  @S9S_MB_2U_LIB.S9S_MB_2U(SCH_1):CLK_50M_EN
    3  CLK_50M_BMC_MAC_R     Y0  @S9S_MB_2U_LIB.S9S_MB_2U(SCH_1):CLK_50M_BMC_MAC_R

ADM1086AKSZREEL7  I1   U94    [ADM1086AKSZREEL7-ADM1086AKSZ-RA]
    4  PWRGD_DSW_PWROK_R1  ENOUT  @S9S_MB_2U_LIB.S9S_MB_2U(SCH_1):PWRGD_DSW_PWROK_R1
    6  P3V3_AUX         VCC  @S9S_MB_2U_LIB.S9S_MB_2U(SCH_1):P3V3_AUX
    2  GND              GND  @S9S_MB_2U_LIB.S9S_MB_2U(SCH_1):GND
    5  FM_COMP_P3V3_STBY_CEXT   CEXT  @S9S_MB_2U_LIB.S9S_MB_2U(SCH_1):FM_COMP_P3V3_STBY_CEXT
    3  FM_COMP_P3V3_AUX_VIN    VIN  @S9S_MB_2U_LIB.S9S_MB_2U(SCH_1):FM_COMP_P3V3_AUX_VIN
    1  FM_COMP_P3V3_AUX_ENIN   ENIN  @S9S_MB_2U_LIB.S9S_MB_2U(SCH_1):FM_COMP_P3V3_AUX_ENIN

SN74LVC1G07DCKR  I41  U95    [SN74LVC1G07DCKR-SN74LVC1G07DCKA]
    4  PWRGD_DSW_PWROK_R2      Y  @S9S_MB_2U_LIB.S9S_MB_2U(SCH_1):PWRGD_DSW_PWROK_R2
    2  PWRGD_DSW_PWROK_R1      A  @S9S_MB_2U_LIB.S9S_MB_2U(SCH_1):PWRGD_DSW_PWROK_R1
    5  P3V3_AUX         VCC  @S9S_MB_2U_LIB.S9S_MB_2U(SCH_1):P3V3_AUX
    1  NC               NC1  NC
    3  GND              GND  @S9S_MB_2U_LIB.S9S_MB_2U(SCH_1):GND

TS3A24157RSER  I68  U96    [TS3A24157RSER-TS3A24157RSER,SMA]
   10  P3V3_AUX          V+  @S9S_MB_2U_LIB.S9S_MB_2U(SCH_1):P3V3_AUX
    6  JTAG_BMC_TDO    COM2  @S9S_MB_2U_LIB.S9S_MB_2U(SCH_1):JTAG_BMC_TDO
    9  JTAG_BMC_TDI    COM1  @S9S_MB_2U_LIB.S9S_MB_2U(SCH_1):JTAG_BMC_TDI
    3  JTAG_BMC_PLD_TDO    NC2  @S9S_MB_2U_LIB.S9S_MB_2U(SCH_1):JTAG_BMC_PLD_TDO
    1  JTAG_BMC_PLD_TDI    NC1  @S9S_MB_2U_LIB.S9S_MB_2U(SCH_1):JTAG_BMC_PLD_TDI
    4  JTAG_BMC_DBP_TDO    NO2  @S9S_MB_2U_LIB.S9S_MB_2U(SCH_1):JTAG_BMC_DBP_TDO
    2  JTAG_BMC_DBP_TDI    NO1  @S9S_MB_2U_LIB.S9S_MB_2U(SCH_1):JTAG_BMC_DBP_TDI
    5  GND              GND  @S9S_MB_2U_LIB.S9S_MB_2U(SCH_1):GND
    7  FM_JTAG_BMC_MUX_SEL    IN2  @S9S_MB_2U_LIB.S9S_MB_2U(SCH_1):FM_JTAG_BMC_MUX_SEL
    8  FM_JTAG_BMC_MUX_SEL    IN1  @S9S_MB_2U_LIB.S9S_MB_2U(SCH_1):FM_JTAG_BMC_MUX_SEL

TS3A24157RSER  I38  U97    [TS3A24157RSER-TS3A24157RSER,SMA]
   10  P3V3_AUX          V+  @S9S_MB_2U_LIB.S9S_MB_2U(SCH_1):P3V3_AUX
    9  JTAG_BMC_TMS    COM1  @S9S_MB_2U_LIB.S9S_MB_2U(SCH_1):JTAG_BMC_TMS
    6  JTAG_BMC_TCK    COM2  @S9S_MB_2U_LIB.S9S_MB_2U(SCH_1):JTAG_BMC_TCK
    1  JTAG_BMC_PLD_TMS    NC1  @S9S_MB_2U_LIB.S9S_MB_2U(SCH_1):JTAG_BMC_PLD_TMS
    3  JTAG_BMC_PLD_TCK    NC2  @S9S_MB_2U_LIB.S9S_MB_2U(SCH_1):JTAG_BMC_PLD_TCK
    2  JTAG_BMC_DBP_TMS    NO1  @S9S_MB_2U_LIB.S9S_MB_2U(SCH_1):JTAG_BMC_DBP_TMS
    4  JTAG_BMC_DBP_TCK    NO2  @S9S_MB_2U_LIB.S9S_MB_2U(SCH_1):JTAG_BMC_DBP_TCK
    5  GND              GND  @S9S_MB_2U_LIB.S9S_MB_2U(SCH_1):GND
    7  FM_JTAG_BMC_MUX_SEL    IN2  @S9S_MB_2U_LIB.S9S_MB_2U(SCH_1):FM_JTAG_BMC_MUX_SEL
    8  FM_JTAG_BMC_MUX_SEL    IN1  @S9S_MB_2U_LIB.S9S_MB_2U(SCH_1):FM_JTAG_BMC_MUX_SEL

PCA9306DCTR  I27  U98    [PCA9306DCTR-PCA9306DCTR,SMLF,IA]
    5  SMB_SENSOR_M2_P0_3V3AUX_SDA   SDA2  @S9S_MB_2U_LIB.S9S_MB_2U(SCH_1):SMB_SENSOR_M2_P0_3V3AUX_SDA
    6  SMB_SENSOR_M2_P0_3V3AUX_SCL   SCL2  @S9S_MB_2U_LIB.S9S_MB_2U(SCH_1):SMB_SENSOR_M2_P0_3V3AUX_SCL
    8  SMB_PCIE_M2_EN     EN  @S9S_MB_2U_LIB.S9S_MB_2U(SCH_1):SMB_PCIE_M2_EN
    4  SMB_M2_P0_1V8AUX_SDA   SDA1  @S9S_MB_2U_LIB.S9S_MB_2U(SCH_1):SMB_M2_P0_1V8AUX_SDA
    3  SMB_M2_P0_1V8AUX_SCL   SCL1  @S9S_MB_2U_LIB.S9S_MB_2U(SCH_1):SMB_M2_P0_1V8AUX_SCL
    7  P3V3_AUX       VREF2  @S9S_MB_2U_LIB.S9S_MB_2U(SCH_1):P3V3_AUX
    2  P1V8_PCH_AUX   VREF1  @S9S_MB_2U_LIB.S9S_MB_2U(SCH_1):P1V8_PCH_AUX
    1  GND              GND  @S9S_MB_2U_LIB.S9S_MB_2U(SCH_1):GND

RT9818C44GV  I70  U99    [RT9818C44GV-RT9818C-44GV,SMLF,A]
    1  PWRGD_P5V      RESET#  @S9S_MB_2U_LIB.S9S_MB_2U(SCH_1):PWRGD_P5V
    3  P5V              VDD  @S9S_MB_2U_LIB.S9S_MB_2U(SCH_1):P5V
    2  GND              GND  @S9S_MB_2U_LIB.S9S_MB_2U(SCH_1):GND

SN74LVC1G17DCKR  I205  U101   [SN74LVC1G17DCKR-SN74LVC1G17DCKA]
    5  PGPPA_AUX        VCC  @S9S_MB_2U_LIB.S9S_MB_2U(SCH_1):PGPPA_AUX
    1  NC                NC  NC
    4  IRQ_BMC_PCH_NMI_R1      Y  @S9S_MB_2U_LIB.S9S_MB_2U(SCH_1):IRQ_BMC_PCH_NMI_R1
    2  IRQ_BMC_PCH_NMI_R      A  @S9S_MB_2U_LIB.S9S_MB_2U(SCH_1):IRQ_BMC_PCH_NMI_R
    3  GND              GND  @S9S_MB_2U_LIB.S9S_MB_2U(SCH_1):GND

MAX9634FEUKT  I17  U102   [MAX9634FEUKT-MAX9634FEUK+T,SMLA]
    3  NC               OUT  NC
    5  P12V_S3_AUX_CPU0_NVDIMM_ISENS_1    RS+  @S9S_MB_2U_LIB.S9S_MB_2U(SCH_1):P12V_S3_AUX_CPU0_NVDIMM_ISENSE_P
    4  P12V_S3_AUX_CPU0_NVDIMM_ISENSE_    RS-  @S9S_MB_2U_LIB.S9S_MB_2U(SCH_1):P12V_S3_AUX_CPU0_NVDIMM_ISENSE_N
    2  GND             GND1  @S9S_MB_2U_LIB.S9S_MB_2U(SCH_1):GND
    1  GND             GND0  @S9S_MB_2U_LIB.S9S_MB_2U(SCH_1):GND

MAX9634FEUKT  I12  U103   [MAX9634FEUKT-MAX9634FEUK+T,SMLA]
    3  NC               OUT  NC
    5  P12V_S3_AUX_CPU1_NVDIMM_ISENS_1    RS+  @S9S_MB_2U_LIB.S9S_MB_2U(SCH_1):P12V_S3_AUX_CPU1_NVDIMM_ISENSE_P
    4  P12V_S3_AUX_CPU1_NVDIMM_ISENSE_    RS-  @S9S_MB_2U_LIB.S9S_MB_2U(SCH_1):P12V_S3_AUX_CPU1_NVDIMM_ISENSE_N
    2  GND             GND1  @S9S_MB_2U_LIB.S9S_MB_2U(SCH_1):GND
    1  GND             GND0  @S9S_MB_2U_LIB.S9S_MB_2U(SCH_1):GND

74LVC1G07GV  I63  U104   [74LVC1G07GV-74LVC1G07GV,SMLF,IA]
    5  P3V3_AUX         VCC  @S9S_MB_2U_LIB.S9S_MB_2U(SCH_1):P3V3_AUX
    4  OCP_SFF_PWRBRK_BUFF_N      Y  @S9S_MB_2U_LIB.S9S_MB_2U(SCH_1):OCP_SFF_PWRBRK_BUFF_N
    1  NC               NC1  NC
    3  GND              GND  @S9S_MB_2U_LIB.S9S_MB_2U(SCH_1):GND
    2  FM_SYS_THROTTLE_R_N      A  @S9S_MB_2U_LIB.S9S_MB_2U(SCH_1):FM_SYS_THROTTLE_R_N

ADS1015IDGSR  I1   U105   [ADS1015IDGSR-ADS1015IDGSR,SMLFA]
    2  VOL_SEN_ALERT  ALRET_RDY  @S9S_MB_2U_LIB.S9S_MB_2U(SCH_1):VOL_SEN_ALERT
    1  VOL_SEN_ADDR    ADDR  @S9S_MB_2U_LIB.S9S_MB_2U(SCH_1):VOL_SEN_ADDR
    9  SMB_SEN_3V3AUX_SDA    SDA  @S9S_MB_2U_LIB.S9S_MB_2U(SCH_1):SMB_SEN_3V3AUX_SDA
   10  SMB_SEN_3V3AUX_SCL    SCL  @S9S_MB_2U_LIB.S9S_MB_2U(SCH_1):SMB_SEN_3V3AUX_SCL
    5  P3V3_SENSE      AIN1  @S9S_MB_2U_LIB.S9S_MB_2U(SCH_1):P3V3_SENSE
    6  P3V3_RTC_AUX_SENSE   AIN2  @S9S_MB_2U_LIB.S9S_MB_2U(SCH_1):P3V3_RTC_AUX_SENSE
    4  P3V3_AUX_SENSE   AIN0  @S9S_MB_2U_LIB.S9S_MB_2U(SCH_1):P3V3_AUX_SENSE
    8  P3V3_AUX         VDD  @S9S_MB_2U_LIB.S9S_MB_2U(SCH_1):P3V3_AUX
    7  P12V_AUX_SENSE   AIN3  @S9S_MB_2U_LIB.S9S_MB_2U(SCH_1):P12V_AUX_SENSE
    3  GND              GND  @S9S_MB_2U_LIB.S9S_MB_2U(SCH_1):GND

MP5981GLUZ  I113  U107   [MP5981GLUZ-MP5981GLU-Z,SMLF,ICA]
   21  VDD3            VDD3  @S9S_MB_2U_LIB.S9S_MB_2U(SCH_1):VDD3
   18  NC             VTEMP  NC
   22  TP_MP5981_0_IMON   IMON  @S9S_MB_2U_LIB.S9S_MB_2U(SCH_1):TP_MP5981_0_IMON
    5  PU_MP5981_0_GOK    GOK  @S9S_MB_2U_LIB.S9S_MB_2U(SCH_1):PU_MP5981_0_GOK
    3  PU_MP5981_0_D_OC   D_OC  @S9S_MB_2U_LIB.S9S_MB_2U(SCH_1):PU_MP5981_0_D_OC
    8  PD_MP5981_0_MODE   MODE  @S9S_MB_2U_LIB.S9S_MB_2U(SCH_1):PD_MP5981_0_MODE
   32  P12V_REAR_CPU  VOUT_32  @S9S_MB_2U_LIB.S9S_MB_2U(SCH_1):P12V_REAR_CPU
   31  P12V_REAR_CPU  VOUT_31  @S9S_MB_2U_LIB.S9S_MB_2U(SCH_1):P12V_REAR_CPU
   30  P12V_REAR_CPU  VOUT_30  @S9S_MB_2U_LIB.S9S_MB_2U(SCH_1):P12V_REAR_CPU
   29  P12V_REAR_CPU  VOUT_29  @S9S_MB_2U_LIB.S9S_MB_2U(SCH_1):P12V_REAR_CPU
   28  P12V_REAR_CPU  VOUT_28  @S9S_MB_2U_LIB.S9S_MB_2U(SCH_1):P12V_REAR_CPU
   27  P12V_REAR_CPU  VOUT_27  @S9S_MB_2U_LIB.S9S_MB_2U(SCH_1):P12V_REAR_CPU
   26  P12V_REAR_CPU  VOUT_26  @S9S_MB_2U_LIB.S9S_MB_2U(SCH_1):P12V_REAR_CPU
   25  P12V_REAR_CPU  VOUT_25  @S9S_MB_2U_LIB.S9S_MB_2U(SCH_1):P12V_REAR_CPU
    2  P12V_REAR_CPU  VOUT_2  @S9S_MB_2U_LIB.S9S_MB_2U(SCH_1):P12V_REAR_CPU
    1  P12V_REAR_CPU  VOUT_1  @S9S_MB_2U_LIB.S9S_MB_2U(SCH_1):P12V_REAR_CPU
   16  P12V_AUX       VIN_16  @S9S_MB_2U_LIB.S9S_MB_2U(SCH_1):P12V_AUX
   15  P12V_AUX       VIN_15  @S9S_MB_2U_LIB.S9S_MB_2U(SCH_1):P12V_AUX
   14  P12V_AUX       VIN_14  @S9S_MB_2U_LIB.S9S_MB_2U(SCH_1):P12V_AUX
   13  P12V_AUX       VIN_13  @S9S_MB_2U_LIB.S9S_MB_2U(SCH_1):P12V_AUX
   12  P12V_AUX       VIN_12  @S9S_MB_2U_LIB.S9S_MB_2U(SCH_1):P12V_AUX
   11  P12V_AUX       VIN_11  @S9S_MB_2U_LIB.S9S_MB_2U(SCH_1):P12V_AUX
   10  P12V_AUX       VIN_10  @S9S_MB_2U_LIB.S9S_MB_2U(SCH_1):P12V_AUX
    9  P12V_AUX       VIN_9  @S9S_MB_2U_LIB.S9S_MB_2U(SCH_1):P12V_AUX
   19  MPS5981_SS        SS  @S9S_MB_2U_LIB.S9S_MB_2U(SCH_1):MPS5981_SS
    4  MP5981_0_ON_PD  ON||PD  @S9S_MB_2U_LIB.S9S_MB_2U(SCH_1):MP5981_0_ON_PD
   23  MP5981_0_CS       CS  @S9S_MB_2U_LIB.S9S_MB_2U(SCH_1):MP5981_0_CS
   24  MP5981_0_CLREF  CLREF  @S9S_MB_2U_LIB.S9S_MB_2U(SCH_1):MP5981_0_CLREF
   TH  GND            VIN_TH  @S9S_MB_2U_LIB.S9S_MB_2U(SCH_1):GND
   17  GND              NC3  @S9S_MB_2U_LIB.S9S_MB_2U(SCH_1):GND
    7  GND              NC2  @S9S_MB_2U_LIB.S9S_MB_2U(SCH_1):GND
    6  GND              NC1  @S9S_MB_2U_LIB.S9S_MB_2U(SCH_1):GND
   20  GND              GND  @S9S_MB_2U_LIB.S9S_MB_2U(SCH_1):GND

TPS3897PDRYR  I37  U117   [TPS3897PDRYR-TPS3897PDRYR,SMLFA]
    4  PWRGD_DSW_PWROK_R1  SENSE_OUT  @S9S_MB_2U_LIB.S9S_MB_2U(SCH_1):PWRGD_DSW_PWROK_R1
    6  P3V3_AUX         VCC  @S9S_MB_2U_LIB.S9S_MB_2U(SCH_1):P3V3_AUX
    2  GND              GND  @S9S_MB_2U_LIB.S9S_MB_2U(SCH_1):GND
    5  FM_COMP_P3V3_STBY_CEXT     CT  @S9S_MB_2U_LIB.S9S_MB_2U(SCH_1):FM_COMP_P3V3_STBY_CEXT
    3  FM_COMP_P3V3_AUX_VIN  SENSE  @S9S_MB_2U_LIB.S9S_MB_2U(SCH_1):FM_COMP_P3V3_AUX_VIN
    1  FM_COMP_P3V3_AUX_ENIN  ENABLE  @S9S_MB_2U_LIB.S9S_MB_2U(SCH_1):FM_COMP_P3V3_AUX_ENIN

MAX11607EUAT  I48  U121   [MAX11607EUAT-MAX11607EUA+T,SMLA]
    6  SMB_SEN_3V3AUX_SDA    SDA  @S9S_MB_2U_LIB.S9S_MB_2U(SCH_1):SMB_SEN_3V3AUX_SDA
    5  SMB_SEN_3V3AUX_SCL    SCL  @S9S_MB_2U_LIB.S9S_MB_2U(SCH_1):SMB_SEN_3V3AUX_SCL
    2  P3V3_SENSE      AIN1  @S9S_MB_2U_LIB.S9S_MB_2U(SCH_1):P3V3_SENSE
    3  P3V3_RTC_AUX_SENSE   AIN2  @S9S_MB_2U_LIB.S9S_MB_2U(SCH_1):P3V3_RTC_AUX_SENSE
    1  P3V3_AUX_SENSE   AIN0  @S9S_MB_2U_LIB.S9S_MB_2U(SCH_1):P3V3_AUX_SENSE
    8  P3V3_AUX         VDD  @S9S_MB_2U_LIB.S9S_MB_2U(SCH_1):P3V3_AUX
    4  P12V_AUX_SENSE  AIN3||REF  @S9S_MB_2U_LIB.S9S_MB_2U(SCH_1):P12V_AUX_SENSE
    7  GND              GND  @S9S_MB_2U_LIB.S9S_MB_2U(SCH_1):GND

10M04SAU324I7G  I165  U122   [10M04SAU324I7G-10M04SAU324I7G,A]
   E3  GND            REFGND  @S9S_MB_2U_LIB.S9S_MB_2U(SCH_1):GND
   A1  GND            GND_32  @S9S_MB_2U_LIB.S9S_MB_2U(SCH_1):GND
  A18  GND            GND_31  @S9S_MB_2U_LIB.S9S_MB_2U(SCH_1):GND
  B10  GND            GND_30  @S9S_MB_2U_LIB.S9S_MB_2U(SCH_1):GND
  B15  GND            GND_29  @S9S_MB_2U_LIB.S9S_MB_2U(SCH_1):GND
   B6  GND            GND_28  @S9S_MB_2U_LIB.S9S_MB_2U(SCH_1):GND
   D3  GND            GND_27  @S9S_MB_2U_LIB.S9S_MB_2U(SCH_1):GND
  E10  GND            GND_26  @S9S_MB_2U_LIB.S9S_MB_2U(SCH_1):GND
  E13  GND            GND_25  @S9S_MB_2U_LIB.S9S_MB_2U(SCH_1):GND
   E6  GND            GND_24  @S9S_MB_2U_LIB.S9S_MB_2U(SCH_1):GND
  F17  GND            GND_23  @S9S_MB_2U_LIB.S9S_MB_2U(SCH_1):GND
   F8  GND            GND_22  @S9S_MB_2U_LIB.S9S_MB_2U(SCH_1):GND
   G2  GND            GND_21  @S9S_MB_2U_LIB.S9S_MB_2U(SCH_1):GND
   G4  GND            GND_20  @S9S_MB_2U_LIB.S9S_MB_2U(SCH_1):GND
  H14  GND            GND_19  @S9S_MB_2U_LIB.S9S_MB_2U(SCH_1):GND
  J10  GND            GND_18  @S9S_MB_2U_LIB.S9S_MB_2U(SCH_1):GND
  J17  GND            GND_17  @S9S_MB_2U_LIB.S9S_MB_2U(SCH_1):GND
  K13  GND            GND_16  @S9S_MB_2U_LIB.S9S_MB_2U(SCH_1):GND
   K6  GND            GND_15  @S9S_MB_2U_LIB.S9S_MB_2U(SCH_1):GND
   K9  GND            GND_14  @S9S_MB_2U_LIB.S9S_MB_2U(SCH_1):GND
   L4  GND            GND_13  @S9S_MB_2U_LIB.S9S_MB_2U(SCH_1):GND
  M14  GND            GND_12  @S9S_MB_2U_LIB.S9S_MB_2U(SCH_1):GND
  N10  GND            GND_11  @S9S_MB_2U_LIB.S9S_MB_2U(SCH_1):GND
  N12  GND            GND_10  @S9S_MB_2U_LIB.S9S_MB_2U(SCH_1):GND
  N17  GND            GND_9  @S9S_MB_2U_LIB.S9S_MB_2U(SCH_1):GND
   N2  GND            GND_8  @S9S_MB_2U_LIB.S9S_MB_2U(SCH_1):GND
   N5  GND            GND_7  @S9S_MB_2U_LIB.S9S_MB_2U(SCH_1):GND
   R7  GND            GND_6  @S9S_MB_2U_LIB.S9S_MB_2U(SCH_1):GND
  U10  GND            GND_5  @S9S_MB_2U_LIB.S9S_MB_2U(SCH_1):GND
  U14  GND            GND_4  @S9S_MB_2U_LIB.S9S_MB_2U(SCH_1):GND
   U4  GND            GND_3  @S9S_MB_2U_LIB.S9S_MB_2U(SCH_1):GND
   V1  GND            GND_2  @S9S_MB_2U_LIB.S9S_MB_2U(SCH_1):GND
  V18  GND            GND_1  @S9S_MB_2U_LIB.S9S_MB_2U(SCH_1):GND

10M04SAU324I7G  I164  U122   [10M04SAU324I7G-10M04SAU324I7G,A]
   N9  PVCCIO_PLDIO5  VCCIO3_4  @S9S_MB_2U_LIB.S9S_MB_2U(SCH_1):PVCCIO_PLDIO5
   P7  PVCCIO_PLDIO5  VCCIO3_3  @S9S_MB_2U_LIB.S9S_MB_2U(SCH_1):PVCCIO_PLDIO5
   P8  PVCCIO_PLDIO5  VCCIO3_2  @S9S_MB_2U_LIB.S9S_MB_2U(SCH_1):PVCCIO_PLDIO5
   P9  PVCCIO_PLDIO5  VCCIO3_1  @S9S_MB_2U_LIB.S9S_MB_2U(SCH_1):PVCCIO_PLDIO5
  P11  PVCCIO_PLDIO2  VCCIO4_2  @S9S_MB_2U_LIB.S9S_MB_2U(SCH_1):PVCCIO_PLDIO2
  P12  PVCCIO_PLDIO2  VCCIO4_1  @S9S_MB_2U_LIB.S9S_MB_2U(SCH_1):PVCCIO_PLDIO2
  P13  PVCCA_AUX_PLD  VCCA4_P13  @S9S_MB_2U_LIB.S9S_MB_2U(SCH_1):PVCCA_AUX_PLD
   F6  PVCCA_AUX_PLD  VCCA3_F6  @S9S_MB_2U_LIB.S9S_MB_2U(SCH_1):PVCCA_AUX_PLD
   F4  PVCCA_AUX_PLD  VCCA3_F4  @S9S_MB_2U_LIB.S9S_MB_2U(SCH_1):PVCCA_AUX_PLD
  F14  PVCCA_AUX_PLD  VCCA2_F14  @S9S_MB_2U_LIB.S9S_MB_2U(SCH_1):PVCCA_AUX_PLD
   M6  PVCCA_AUX_PLD  VCCA1_M6  @S9S_MB_2U_LIB.S9S_MB_2U(SCH_1):PVCCA_AUX_PLD
   F3  P3V3_AUX_DPLD_ADC_VREF  ADC_VREF  @S9S_MB_2U_LIB.S9S_MB_2U(SCH_1):P3V3_AUX_DPLD_ADC_VREF
   E7  P3V3_AUX       VCCIO8_4  @S9S_MB_2U_LIB.S9S_MB_2U(SCH_1):P3V3_AUX
   E8  P3V3_AUX       VCCIO8_3  @S9S_MB_2U_LIB.S9S_MB_2U(SCH_1):P3V3_AUX
   E9  P3V3_AUX       VCCIO8_2  @S9S_MB_2U_LIB.S9S_MB_2U(SCH_1):P3V3_AUX
   F9  P3V3_AUX       VCCIO8_1  @S9S_MB_2U_LIB.S9S_MB_2U(SCH_1):P3V3_AUX
  D11  P3V3_AUX       VCCIO7_3  @S9S_MB_2U_LIB.S9S_MB_2U(SCH_1):P3V3_AUX
  E11  P3V3_AUX       VCCIO7_2  @S9S_MB_2U_LIB.S9S_MB_2U(SCH_1):P3V3_AUX
  E12  P3V3_AUX       VCCIO7_1  @S9S_MB_2U_LIB.S9S_MB_2U(SCH_1):P3V3_AUX
  G13  P3V3_AUX       VCCIO6_5  @S9S_MB_2U_LIB.S9S_MB_2U(SCH_1):P3V3_AUX
  G14  P3V3_AUX       VCCIO6_4  @S9S_MB_2U_LIB.S9S_MB_2U(SCH_1):P3V3_AUX
  H13  P3V3_AUX       VCCIO6_3  @S9S_MB_2U_LIB.S9S_MB_2U(SCH_1):P3V3_AUX
  J13  P3V3_AUX       VCCIO6_2  @S9S_MB_2U_LIB.S9S_MB_2U(SCH_1):P3V3_AUX
  J14  P3V3_AUX       VCCIO6_1  @S9S_MB_2U_LIB.S9S_MB_2U(SCH_1):P3V3_AUX
  K14  P3V3_AUX       VCCIO5_4  @S9S_MB_2U_LIB.S9S_MB_2U(SCH_1):P3V3_AUX
  L13  P3V3_AUX       VCCIO5_3  @S9S_MB_2U_LIB.S9S_MB_2U(SCH_1):P3V3_AUX
  L14  P3V3_AUX       VCCIO5_2  @S9S_MB_2U_LIB.S9S_MB_2U(SCH_1):P3V3_AUX
  M13  P3V3_AUX       VCCIO5_1  @S9S_MB_2U_LIB.S9S_MB_2U(SCH_1):P3V3_AUX
   L5  P3V3_AUX       VCCIO2_3  @S9S_MB_2U_LIB.S9S_MB_2U(SCH_1):P3V3_AUX
   L6  P3V3_AUX       VCCIO2_2  @S9S_MB_2U_LIB.S9S_MB_2U(SCH_1):P3V3_AUX
   M5  P3V3_AUX       VCCIO2_1  @S9S_MB_2U_LIB.S9S_MB_2U(SCH_1):P3V3_AUX
   J5  P3V3_AUX       VCCIO1B_2  @S9S_MB_2U_LIB.S9S_MB_2U(SCH_1):P3V3_AUX
   K5  P3V3_AUX       VCCIO1B_1  @S9S_MB_2U_LIB.S9S_MB_2U(SCH_1):P3V3_AUX
   G5  P3V3_AUX       VCCIO1A_2  @S9S_MB_2U_LIB.S9S_MB_2U(SCH_1):P3V3_AUX
   H5  P3V3_AUX       VCCIO1A_1  @S9S_MB_2U_LIB.S9S_MB_2U(SCH_1):P3V3_AUX
   C3  P3V3_AUX       VCC_ONE_7  @S9S_MB_2U_LIB.S9S_MB_2U(SCH_1):P3V3_AUX
  F13  P3V3_AUX       VCC_ONE_6  @S9S_MB_2U_LIB.S9S_MB_2U(SCH_1):P3V3_AUX
   N6  P3V3_AUX       VCC_ONE_5  @S9S_MB_2U_LIB.S9S_MB_2U(SCH_1):P3V3_AUX
  H10  P3V3_AUX       VCC_ONE_4  @S9S_MB_2U_LIB.S9S_MB_2U(SCH_1):P3V3_AUX
   J9  P3V3_AUX       VCC_ONE_3  @S9S_MB_2U_LIB.S9S_MB_2U(SCH_1):P3V3_AUX
  K10  P3V3_AUX       VCC_ONE_2  @S9S_MB_2U_LIB.S9S_MB_2U(SCH_1):P3V3_AUX
   L9  P3V3_AUX       VCC_ONE_1  @S9S_MB_2U_LIB.S9S_MB_2U(SCH_1):P3V3_AUX

10M04SAU324I7G  I139  U122   [10M04SAU324I7G-10M04SAU324I7G,A]
  K12  RST_RSMRST_PLD_R_N  DIFFIO_RX_R14P||CLK2P  @S9S_MB_2U_LIB.S9S_MB_2U(SCH_1):RST_RSMRST_PLD_R_N
  K11  RST_PLTRST_PLD_N  DIFFIO_RX_R14N||CLK2N  @S9S_MB_2U_LIB.S9S_MB_2U(SCH_1):RST_PLTRST_PLD_N
  T11  RST_PLD_CPU0_DRAM_AB_N  IO_4||VREFB4N0  @S9S_MB_2U_LIB.S9S_MB_2U(SCH_1):RST_PLD_CPU0_DRAM_AB_N
   U6  RST_CPU0_LVC1_R_N  IO_3||VREFB3N0  @S9S_MB_2U_LIB.S9S_MB_2U(SCH_1):RST_CPU0_LVC1_R_N
  H12  PWRGD_SYS_PWROK_R  DIFFIO_RX_R26N||DPCLK2  @S9S_MB_2U_LIB.S9S_MB_2U(SCH_1):PWRGD_SYS_PWROK_R
   R1  PWRGD_PVCCIN_CPU1  IO_2||VREFB2N0  @S9S_MB_2U_LIB.S9S_MB_2U(SCH_1):PWRGD_PVCCIN_CPU1
   N3  PWRGD_PVCCINFAON_CPU0  DIFFIO_RX_L22P||DPCLK1  @S9S_MB_2U_LIB.S9S_MB_2U(SCH_1):PWRGD_PVCCINFAON_CPU0
   L8  PWRGD_PVCCFA_EHV_FIVRA_CPU1  DIFFIO_RX_L20P||CLK1P  @S9S_MB_2U_LIB.S9S_MB_2U(SCH_1):PWRGD_PVCCFA_EHV_FIVRA_CPU1
   K8  PWRGD_PVCCFA_EHV_CPU1  DIFFIO_RX_L20N||CLK1N  @S9S_MB_2U_LIB.S9S_MB_2U(SCH_1):PWRGD_PVCCFA_EHV_CPU1
   M4  PWRGD_PVCCFA_EHV_CPU0  DIFFIO_RX_L22N||DPCLK0  @S9S_MB_2U_LIB.S9S_MB_2U(SCH_1):PWRGD_PVCCFA_EHV_CPU0
   M3  PWRGD_PVCCD_HV_CPU1  DIFFIO_RX_L18P||CLK0P  @S9S_MB_2U_LIB.S9S_MB_2U(SCH_1):PWRGD_PVCCD_HV_CPU1
  H11  PWRGD_PCH_PWROK_R  DIFFIO_RX_R26P||DPCLK3  @S9S_MB_2U_LIB.S9S_MB_2U(SCH_1):PWRGD_PCH_PWROK_R
   P4  PWRGD_P1V8_PCH_AUX_PLD  DIFFIO_RX_L27P||PLL_L_CLKOUTP  @S9S_MB_2U_LIB.S9S_MB_2U(SCH_1):PWRGD_P1V8_PCH_AUX_PLD
   N4  PWRGD_P1V05_PCH_AUX  DIFFIO_RX_L27N||PLL_L_CLKOUTN  @S9S_MB_2U_LIB.S9S_MB_2U(SCH_1):PWRGD_P1V05_PCH_AUX
   G8  PU_MAIN_FPGA_STATUS_N  DIFFIO_RX_T24P||NSTATUS  @S9S_MB_2U_LIB.S9S_MB_2U(SCH_1):PU_MAIN_FPGA_STATUS_N
   H9  PU_MAIN_FPGA_CONFIG_N  NCONFIG  @S9S_MB_2U_LIB.S9S_MB_2U(SCH_1):PU_MAIN_FPGA_CONFIG_N
   H8  PU_MAIN_FPGA_CONFIG_DONE  DIFFIO_RX_T24N||CONF_DONE  @S9S_MB_2U_LIB.S9S_MB_2U(SCH_1):PU_MAIN_FPGA_CONFIG_DONE
  N13  PD_MAIN_FPGA_N13   NC_1  @S9S_MB_2U_LIB.S9S_MB_2U(SCH_1):PD_MAIN_FPGA_N13
   F7  PD_MAIN_FPGA_F7   NC_2  @S9S_MB_2U_LIB.S9S_MB_2U(SCH_1):PD_MAIN_FPGA_F7
   G9  PD_MAIN_FPGA_CONFIG_SEL  CONFIG_SEL  @S9S_MB_2U_LIB.S9S_MB_2U(SCH_1):PD_MAIN_FPGA_CONFIG_SEL
   J7  JTAG_PLD_TMS_R  TMS||DIFFIO_RX_L11N  @S9S_MB_2U_LIB.S9S_MB_2U(SCH_1):JTAG_PLD_TMS_R
   H4  JTAG_PLD_TDO_R  TDO||DIFFIO_RX_L12P  @S9S_MB_2U_LIB.S9S_MB_2U(SCH_1):JTAG_PLD_TDO_R
   H3  JTAG_PLD_TDI_R  TDI||DIFFIO_RX_L12N  @S9S_MB_2U_LIB.S9S_MB_2U(SCH_1):JTAG_PLD_TDI_R
   J8  JTAG_PLD_TCK_R  TCK||DIFFIO_RX_L11P  @S9S_MB_2U_LIB.S9S_MB_2U(SCH_1):JTAG_PLD_TCK_R
   H7  JTAG_PLD_JTAGEN  JTAGEN||DIFFIO_RX_L9P  @S9S_MB_2U_LIB.S9S_MB_2U(SCH_1):JTAG_PLD_JTAGEN
   D8  JTAG_DBP_BMC_PREQ_R_N  DIFFIO_RX_T18P||DEV_OE  @S9S_MB_2U_LIB.S9S_MB_2U(SCH_1):JTAG_DBP_BMC_PREQ_R_N
  P17  IRQ_PCH_SCI_WHEA_R_N  IO_5||VREFB5N0  @S9S_MB_2U_LIB.S9S_MB_2U(SCH_1):IRQ_PCH_SCI_WHEA_R_N
   E2  FP_DPLD_ANAIN1  ANAIN1  @S9S_MB_2U_LIB.S9S_MB_2U(SCH_1):FP_DPLD_ANAIN1
  L17  FM_SLPS3_PLD_N  DIFFIO_RX_R16P||CLK3P  @S9S_MB_2U_LIB.S9S_MB_2U(SCH_1):FM_SLPS3_PLD_N
   C4  FM_PVPP_HBM_CPU0_EN  DIFFIO_RX_T22N||CRC_ERROR  @S9S_MB_2U_LIB.S9S_MB_2U(SCH_1):FM_PVPP_HBM_CPU0_EN
  A16  FM_PVNN_MAIN_CPU0_EN  IO_7||VREFB7N0  @S9S_MB_2U_LIB.S9S_MB_2U(SCH_1):FM_PVNN_MAIN_CPU0_EN
   B8  FM_PCHHOT_R_N  DIFFIO_RX_T16N||DEV_CLRN  @S9S_MB_2U_LIB.S9S_MB_2U(SCH_1):FM_PCHHOT_R_N
   J3  FM_OCP_SFF_PWR_GOOD_R  IO_1B||VREFB1N0  @S9S_MB_2U_LIB.S9S_MB_2U(SCH_1):FM_OCP_SFF_PWR_GOOD_R
   B7  NC             IO_8||VREFB8N0  NC
  K17  FM_CPU1_PROC_ID0  DIFFIO_RX_R16N||CLK3N  @S9S_MB_2U_LIB.S9S_MB_2U(SCH_1):FM_CPU1_PROC_ID0
  F18  FM_CPU0_PKGID2  IO_6||VREFB6N0  @S9S_MB_2U_LIB.S9S_MB_2U(SCH_1):FM_CPU0_PKGID2
   L3  CLK_25M_OSC_MAIN_FPGA  DIFFIO_RX_L18N||CLK0N  @S9S_MB_2U_LIB.S9S_MB_2U(SCH_1):CLK_25M_OSC_MAIN_FPGA

10M04SAU324I7G  I155  U122   [10M04SAU324I7G-10M04SAU324I7G,A]
  B13  VOL_SEN_ALERT_R  DIFFIO_RX_T7N  @S9S_MB_2U_LIB.S9S_MB_2U(SCH_1):VOL_SEN_ALERT_R
   B9  USB_OC1_REAR_N  DIFFIO_RX_T16P  @S9S_MB_2U_LIB.S9S_MB_2U(SCH_1):USB_OC1_REAR_N
   V9  NC             DIFFIO_TX_RX_B12N  NC
   U9  NC             DIFFIO_TX_RX_B12P  NC
  F12  SMB_SML1_PMBUS_3V3AUX_PLD_SDA  DIFFIO_RX_T8N  @S9S_MB_2U_LIB.S9S_MB_2U(SCH_1):SMB_SML1_PMBUS_3V3AUX_PLD_SDA
  F11  SMB_SML1_PMBUS_3V3AUX_PLD_SCL  DIFFIO_RX_T8P  @S9S_MB_2U_LIB.S9S_MB_2U(SCH_1):SMB_SML1_PMBUS_3V3AUX_PLD_SCL
   N8  SMB_S3M_CPU1_LVC1_SDA  DIFFIO_TX_RX_B9P  @S9S_MB_2U_LIB.S9S_MB_2U(SCH_1):SMB_S3M_CPU1_LVC1_SDA
   N7  SMB_S3M_CPU1_LVC1_SCL  DIFFIO_TX_RX_B9N  @S9S_MB_2U_LIB.S9S_MB_2U(SCH_1):SMB_S3M_CPU1_LVC1_SCL
   R9  SMB_S3M_CPU0_LVC1_SDA  DIFFIO_TX_RX_B10P  @S9S_MB_2U_LIB.S9S_MB_2U(SCH_1):SMB_S3M_CPU0_LVC1_SDA
   R8  SMB_S3M_CPU0_LVC1_SCL  DIFFIO_TX_RX_B10N  @S9S_MB_2U_LIB.S9S_MB_2U(SCH_1):SMB_S3M_CPU0_LVC1_SCL
  B17  SMB_PCIE_3V3AUX_B_SDA  DIFFIO_RX_T2P  @S9S_MB_2U_LIB.S9S_MB_2U(SCH_1):SMB_PCIE_3V3AUX_B_SDA
  B16  SMB_PCIE_3V3AUX_B_SCL  DIFFIO_RX_T2N  @S9S_MB_2U_LIB.S9S_MB_2U(SCH_1):SMB_PCIE_3V3AUX_B_SCL
  M16  SGPIO_DEBUG_PLD_LD_N  DIFFIO_RX_R6N  @S9S_MB_2U_LIB.S9S_MB_2U(SCH_1):SGPIO_DEBUG_PLD_LD_N
  M12  SGPIO_DEBUG_PLD_DOUT  DIFFIO_RX_R3P  @S9S_MB_2U_LIB.S9S_MB_2U(SCH_1):SGPIO_DEBUG_PLD_DOUT
  M15  SGPIO_DEBUG_PLD_DIN  DIFFIO_RX_R5N  @S9S_MB_2U_LIB.S9S_MB_2U(SCH_1):SGPIO_DEBUG_PLD_DIN
  M11  SGPIO_DEBUG_PLD_CLK  DIFFIO_RX_R3N  @S9S_MB_2U_LIB.S9S_MB_2U(SCH_1):SGPIO_DEBUG_PLD_CLK
  U16  RST_PLD_CPU1_DRAM_CD_N  DIFFIO_TX_RX_B27N  @S9S_MB_2U_LIB.S9S_MB_2U(SCH_1):RST_PLD_CPU1_DRAM_CD_N
  T12  RST_PLD_CPU0_DRAM_EF_N   IO_4  @S9S_MB_2U_LIB.S9S_MB_2U(SCH_1):RST_PLD_CPU0_DRAM_EF_N
  R11  RST_PLD_CPU0_DRAM_CD_N  DIFFIO_TX_RX_B21P  @S9S_MB_2U_LIB.S9S_MB_2U(SCH_1):RST_PLD_CPU0_DRAM_CD_N
  T18  RST_PFR_OVR_SRTC_R  DIFFIO_RX_R4N  @S9S_MB_2U_LIB.S9S_MB_2U(SCH_1):RST_PFR_OVR_SRTC_R
  T17  RST_PFR_OVR_RTC_R  DIFFIO_RX_R9P  @S9S_MB_2U_LIB.S9S_MB_2U(SCH_1):RST_PFR_OVR_RTC_R
   A6  NC             DIFFIO_RX_T19P  NC
  C17  RST_MB_STBY_R_N  DIFFIO_RX_R34N  @S9S_MB_2U_LIB.S9S_MB_2U(SCH_1):RST_MB_STBY_R_N
   M9  RST_CPU1_LVC1_R_N  DIFFIO_TX_RX_B14P  @S9S_MB_2U_LIB.S9S_MB_2U(SCH_1):RST_CPU1_LVC1_R_N
  R10  RST_CPU1_DRAM_GH_PLD_N  DIFFIO_TX_RX_B21N  @S9S_MB_2U_LIB.S9S_MB_2U(SCH_1):RST_CPU1_DRAM_GH_PLD_N
  T15  RST_CPU1_DRAM_EF_PLD_N  DIFFIO_TX_RX_B25P  @S9S_MB_2U_LIB.S9S_MB_2U(SCH_1):RST_CPU1_DRAM_EF_PLD_N
  R14  RST_CPU1_DRAM_CD_PLD_N  DIFFIO_TX_RX_B25N  @S9S_MB_2U_LIB.S9S_MB_2U(SCH_1):RST_CPU1_DRAM_CD_PLD_N
  R12  RST_CPU0_DRAM_GH_PLD_N  DIFFIO_TX_RX_B23N  @S9S_MB_2U_LIB.S9S_MB_2U(SCH_1):RST_CPU0_DRAM_GH_PLD_N
  R13  RST_CPU0_DRAM_CD_PLD_N  DIFFIO_TX_RX_B23P  @S9S_MB_2U_LIB.S9S_MB_2U(SCH_1):RST_CPU0_DRAM_CD_PLD_N
   R2  PWRGD_PVCCINFAON_CPU1   IO_2  @S9S_MB_2U_LIB.S9S_MB_2U(SCH_1):PWRGD_PVCCINFAON_CPU1
  N16  PWRGD_PLT_AUX_CPU1_LVT3_R  DIFFIO_RX_R6P  @S9S_MB_2U_LIB.S9S_MB_2U(SCH_1):PWRGD_PLT_AUX_CPU1_LVT3_R
  N15  PWRGD_PLT_AUX_CPU0_LVT3_R  DIFFIO_RX_R5P  @S9S_MB_2U_LIB.S9S_MB_2U(SCH_1):PWRGD_PLT_AUX_CPU0_LVT3_R
  U17  PWRGD_DRAMPWRGD_CPU1_CD_R_LVC1  DIFFIO_TX_RX_B27P  @S9S_MB_2U_LIB.S9S_MB_2U(SCH_1):PWRGD_DRAMPWRGD_CPU1_CD_R_LVC1
  L10  PWRGD_DRAMPWRGD_CPU0_GH_R_LVC1  DIFFIO_TX_RX_B20P  @S9S_MB_2U_LIB.S9S_MB_2U(SCH_1):PWRGD_DRAMPWRGD_CPU0_GH_R_LVC1
  N11  PWRGD_DRAMPWRGD_CPU0_EF_R_LVC1  DIFFIO_TX_RX_B18P  @S9S_MB_2U_LIB.S9S_MB_2U(SCH_1):PWRGD_DRAMPWRGD_CPU0_EF_R_LVC1
  M10  PWRGD_DRAMPWRGD_CPU0_CD_R_LVC1  DIFFIO_TX_RX_B20N  @S9S_MB_2U_LIB.S9S_MB_2U(SCH_1):PWRGD_DRAMPWRGD_CPU0_CD_R_LVC1
  P10  PWRGD_DRAMPWRGD_CPU0_AB_R_LVC1  DIFFIO_TX_RX_B18N  @S9S_MB_2U_LIB.S9S_MB_2U(SCH_1):PWRGD_DRAMPWRGD_CPU0_AB_R_LVC1
   R4  PWRGD_CPU1_LVC1_R  DIFFIO_TX_RX_B1N  @S9S_MB_2U_LIB.S9S_MB_2U(SCH_1):PWRGD_CPU1_LVC1_R
  F10  PCIE_M2_SSD0_PRSNT_N  DIFFIO_RX_T14P  @S9S_MB_2U_LIB.S9S_MB_2U(SCH_1):PCIE_M2_SSD0_PRSNT_N
   D7  JTAG_DBP_BMC_PRDY_R_N  DIFFIO_RX_T18N  @S9S_MB_2U_LIB.S9S_MB_2U(SCH_1):JTAG_DBP_BMC_PRDY_R_N
   B4  NC             DIFFIO_RX_T23N  NC
  P16  IRQ_TPM_SPI_N   IO_5  @S9S_MB_2U_LIB.S9S_MB_2U(SCH_1):IRQ_TPM_SPI_N
  B12  IRQ_PVCCD_CPU1_VRHOT_LVC3_N  DIFFIO_RX_T9N  @S9S_MB_2U_LIB.S9S_MB_2U(SCH_1):IRQ_PVCCD_CPU1_VRHOT_LVC3_N
  B11  IRQ_PVCCD_CPU0_VRHOT_LVC3_N  DIFFIO_RX_T10N  @S9S_MB_2U_LIB.S9S_MB_2U(SCH_1):IRQ_PVCCD_CPU0_VRHOT_LVC3_N
  D12  IRQ_PDB_R_N    DIFFIO_RX_T3P  @S9S_MB_2U_LIB.S9S_MB_2U(SCH_1):IRQ_PDB_R_N
   B3  NC             DIFFIO_RX_T25N  NC
  P15  IRQ_BMC_PCH_NMI_R  DIFFIO_RX_R7N  @S9S_MB_2U_LIB.S9S_MB_2U(SCH_1):IRQ_BMC_PCH_NMI_R
   R5  H_CPU_NMI_LVC1_R_N  DIFFIO_TX_RX_B5N  @S9S_MB_2U_LIB.S9S_MB_2U(SCH_1):H_CPU_NMI_LVC1_R_N
   T6  H_CPU_ERR0_LVC1_N  DIFFIO_TX_RX_B7P  @S9S_MB_2U_LIB.S9S_MB_2U(SCH_1):H_CPU_ERR0_LVC1_N
   T5  H_CPU_CATERR_LVC1_R_N  DIFFIO_TX_RX_B7N  @S9S_MB_2U_LIB.S9S_MB_2U(SCH_1):H_CPU_CATERR_LVC1_R_N
   P6  H_CPU1_THERMTRIP_LVC1_N  DIFFIO_TX_RX_B3N  @S9S_MB_2U_LIB.S9S_MB_2U(SCH_1):H_CPU1_THERMTRIP_LVC1_N
   P5  H_CPU1_PROCHOT_LVC1_R_N  DIFFIO_TX_RX_B3P  @S9S_MB_2U_LIB.S9S_MB_2U(SCH_1):H_CPU1_PROCHOT_LVC1_R_N
   M8  H_CPU1_MON_FAIL_PLD_LVC1_N  DIFFIO_TX_RX_B14N  @S9S_MB_2U_LIB.S9S_MB_2U(SCH_1):H_CPU1_MON_FAIL_PLD_LVC1_N
   V6  H_CPU1_MEMHOT_IN_LVC1_R_N   IO_3  @S9S_MB_2U_LIB.S9S_MB_2U(SCH_1):H_CPU1_MEMHOT_IN_LVC1_R_N
  T10  H_CPU0_THERMTRIP_LVC1_N  DIFFIO_TX_RX_B16P  @S9S_MB_2U_LIB.S9S_MB_2U(SCH_1):H_CPU0_THERMTRIP_LVC1_N
   R6  H_CPU0_PROCHOT_LVC1_R_N  DIFFIO_TX_RX_B5P  @S9S_MB_2U_LIB.S9S_MB_2U(SCH_1):H_CPU0_PROCHOT_LVC1_R_N
   T9  H_CPU0_MEMHOT_OUT_LVC1_N  DIFFIO_TX_RX_B16N  @S9S_MB_2U_LIB.S9S_MB_2U(SCH_1):H_CPU0_MEMHOT_OUT_LVC1_N
  G10  FM_UV_ADR_TRIGGER_N  DIFFIO_RX_T14N  @S9S_MB_2U_LIB.S9S_MB_2U(SCH_1):FM_UV_ADR_TRIGGER_N
  E18  FM_THROTTLE_R_N   IO_6  @S9S_MB_2U_LIB.S9S_MB_2U(SCH_1):FM_THROTTLE_R_N
   T4  FM_THERMTRIP_DLY_LVC1_R_N  DIFFIO_TX_RX_B1P  @S9S_MB_2U_LIB.S9S_MB_2U(SCH_1):FM_THERMTRIP_DLY_LVC1_R_N
   A7  FM_SPD_REMOTE_EN_R   IO_8  @S9S_MB_2U_LIB.S9S_MB_2U(SCH_1):FM_SPD_REMOTE_EN_R
  E15  FM_RST_PERST_BIT2  DIFFIO_RX_R33P  @S9S_MB_2U_LIB.S9S_MB_2U(SCH_1):FM_RST_PERST_BIT2
  B14  FM_RISER2_JTAG_SEL_PLD_N  DIFFIO_RX_T7P  @S9S_MB_2U_LIB.S9S_MB_2U(SCH_1):FM_RISER2_JTAG_SEL_PLD_N
   C5  FM_PVPP_HBM_CPU1_EN  DIFFIO_RX_T22P  @S9S_MB_2U_LIB.S9S_MB_2U(SCH_1):FM_PVPP_HBM_CPU1_EN
  C16  FM_PVNN_MAIN_CPU1_EN  DIFFIO_RX_T4P  @S9S_MB_2U_LIB.S9S_MB_2U(SCH_1):FM_PVNN_MAIN_CPU1_EN
  C11  FM_PVCCIN_CPU1_R_EN  DIFFIO_RX_T10P  @S9S_MB_2U_LIB.S9S_MB_2U(SCH_1):FM_PVCCIN_CPU1_R_EN
  A11  FM_PVCCIN_CPU0_R_EN  DIFFIO_RX_T13P  @S9S_MB_2U_LIB.S9S_MB_2U(SCH_1):FM_PVCCIN_CPU0_R_EN
  C12  FM_PVCCINFAON_CPU1_R_EN  DIFFIO_RX_T9P  @S9S_MB_2U_LIB.S9S_MB_2U(SCH_1):FM_PVCCINFAON_CPU1_R_EN
  A12  FM_PVCCINFAON_CPU0_R_EN  DIFFIO_RX_T11N  @S9S_MB_2U_LIB.S9S_MB_2U(SCH_1):FM_PVCCINFAON_CPU0_R_EN
  C15  FM_PVCCFA_EHV_FIVRA_CPU1_R_EN  DIFFIO_RX_T4N  @S9S_MB_2U_LIB.S9S_MB_2U(SCH_1):FM_PVCCFA_EHV_FIVRA_CPU1_R_EN
  A15  FM_PVCCFA_EHV_FIVRA_CPU0_R_EN  DIFFIO_RX_T5P  @S9S_MB_2U_LIB.S9S_MB_2U(SCH_1):FM_PVCCFA_EHV_FIVRA_CPU0_R_EN
  C13  FM_PVCCFA_EHV_CPU1_R_EN  DIFFIO_RX_T6N  @S9S_MB_2U_LIB.S9S_MB_2U(SCH_1):FM_PVCCFA_EHV_CPU1_R_EN
  A13  FM_PVCCFA_EHV_CPU0_R_EN  DIFFIO_RX_T11P  @S9S_MB_2U_LIB.S9S_MB_2U(SCH_1):FM_PVCCFA_EHV_CPU0_R_EN
  C14  FM_PVCCD_HV_CPU1_EN  DIFFIO_RX_T6P  @S9S_MB_2U_LIB.S9S_MB_2U(SCH_1):FM_PVCCD_HV_CPU1_EN
  A14  FM_PVCCD_HV_CPU0_EN  DIFFIO_RX_T5N  @S9S_MB_2U_LIB.S9S_MB_2U(SCH_1):FM_PVCCD_HV_CPU0_EN
  A10  FM_PS_PWROK_DLY_SEL  DIFFIO_RX_T13N  @S9S_MB_2U_LIB.S9S_MB_2U(SCH_1):FM_PS_PWROK_DLY_SEL
   D6  FM_PLD_REV_N   DIFFIO_RX_T26P  @S9S_MB_2U_LIB.S9S_MB_2U(SCH_1):FM_PLD_REV_N
   D5  FM_PLD_HEARTBEAT_LVC3  DIFFIO_RX_T26N  @S9S_MB_2U_LIB.S9S_MB_2U(SCH_1):FM_PLD_HEARTBEAT_LVC3
   A9  FM_PLD_CLK_25M_R_EN  DIFFIO_RX_T15P  @S9S_MB_2U_LIB.S9S_MB_2U(SCH_1):FM_PLD_CLK_25M_R_EN
   A8  FM_PLD_CLKS_DEV_R_EN  DIFFIO_RX_T15N  @S9S_MB_2U_LIB.S9S_MB_2U(SCH_1):FM_PLD_CLKS_DEV_R_EN
   J4  FM_PCH_PLD_GLB_RST_WARN_N  IO_1B  @S9S_MB_2U_LIB.S9S_MB_2U(SCH_1):FM_PCH_PLD_GLB_RST_WARN_N
   C8  FM_PCH_P1V8_AUX_EN  DIFFIO_RX_T21P  @S9S_MB_2U_LIB.S9S_MB_2U(SCH_1):FM_PCH_P1V8_AUX_EN
  E14  FM_PCH_CRASHLOG_TRIG_R_N  DIFFIO_RX_T1P  @S9S_MB_2U_LIB.S9S_MB_2U(SCH_1):FM_PCH_CRASHLOG_TRIG_R_N
  U18  FM_PCH_BMC_THERMTRIP_N  DIFFIO_RX_R4P  @S9S_MB_2U_LIB.S9S_MB_2U(SCH_1):FM_PCH_BMC_THERMTRIP_N
   C6  FM_P5V_EN      DIFFIO_RX_T20P  @S9S_MB_2U_LIB.S9S_MB_2U(SCH_1):FM_P5V_EN
   C9  FM_P1V05_PCH_AUX_EN  DIFFIO_RX_T17N  @S9S_MB_2U_LIB.S9S_MB_2U(SCH_1):FM_P1V05_PCH_AUX_EN
   B5  NC             DIFFIO_RX_T20N  NC
  R17  FM_ME_AUTHN_FAIL  DIFFIO_RX_R9N  @S9S_MB_2U_LIB.S9S_MB_2U(SCH_1):FM_ME_AUTHN_FAIL
   A3  FM_JTAG_TCK_MUX_SEL  DIFFIO_RX_T25P  @S9S_MB_2U_LIB.S9S_MB_2U(SCH_1):FM_JTAG_TCK_MUX_SEL
   A2  FM_JTAG_BMC_PLD_MUX_SEL  DIFFIO_RX_T27P  @S9S_MB_2U_LIB.S9S_MB_2U(SCH_1):FM_JTAG_BMC_PLD_MUX_SEL
  C10  FM_HBM2_HBM3_VPP_SEL  DIFFIO_RX_T17P  @S9S_MB_2U_LIB.S9S_MB_2U(SCH_1):FM_HBM2_HBM3_VPP_SEL
   B2  FM_FORCE_PWRON_LVC3  DIFFIO_RX_T27N  @S9S_MB_2U_LIB.S9S_MB_2U(SCH_1):FM_FORCE_PWRON_LVC3
   A5  FM_ESPI_PLD_R_EN  DIFFIO_RX_T19N  @S9S_MB_2U_LIB.S9S_MB_2U(SCH_1):FM_ESPI_PLD_R_EN
  D14  FM_DIS_PS_PWROK_DLY  DIFFIO_RX_T1N  @S9S_MB_2U_LIB.S9S_MB_2U(SCH_1):FM_DIS_PS_PWROK_DLY
  R15  FM_CPU_RMCA_CATERR_LVT3_R_N  DIFFIO_RX_R7P  @S9S_MB_2U_LIB.S9S_MB_2U(SCH_1):FM_CPU_RMCA_CATERR_LVT3_R_N
  D15  FM_CPU1_PKGID2  DIFFIO_RX_R33N  @S9S_MB_2U_LIB.S9S_MB_2U(SCH_1):FM_CPU1_PKGID2
  D17  FM_CPU1_PKGID0  DIFFIO_RX_R34P  @S9S_MB_2U_LIB.S9S_MB_2U(SCH_1):FM_CPU1_PKGID0
  D10  FM_BMC_RSTBTN_OUT_N  DIFFIO_RX_T12P  @S9S_MB_2U_LIB.S9S_MB_2U(SCH_1):FM_BMC_RSTBTN_OUT_N
  D13  FM_BMC_READY_R_PLD_N  DIFFIO_RX_T3N  @S9S_MB_2U_LIB.S9S_MB_2U(SCH_1):FM_BMC_READY_R_PLD_N
   A4  FM_BMC_DBP_PRESENT_R_N  DIFFIO_RX_T23P  @S9S_MB_2U_LIB.S9S_MB_2U(SCH_1):FM_BMC_DBP_PRESENT_R_N
   D9  FM_BIOS_POST_CMPLT_BMC_N  DIFFIO_RX_T12N  @S9S_MB_2U_LIB.S9S_MB_2U(SCH_1):FM_BIOS_POST_CMPLT_BMC_N
   C7  FM_AUX_SW_EN   DIFFIO_RX_T21N  @S9S_MB_2U_LIB.S9S_MB_2U(SCH_1):FM_AUX_SW_EN
  A17  FM_ADR_MODE1_R   IO_7  @S9S_MB_2U_LIB.S9S_MB_2U(SCH_1):FM_ADR_MODE1_R
  L12  FM_ADR_MODE0_R  DIFFIO_RX_R8P  @S9S_MB_2U_LIB.S9S_MB_2U(SCH_1):FM_ADR_MODE0_R
  L11  FM_ADR_ACK_R   DIFFIO_RX_R8N  @S9S_MB_2U_LIB.S9S_MB_2U(SCH_1):FM_ADR_ACK_R

10M04SAU324I7G  I93  U122   [10M04SAU324I7G-10M04SAU324I7G,A]
   H2  VIRTUAL_RESEAT_FPGA_R_N  DIFFIO_RX_L10N  @S9S_MB_2U_LIB.S9S_MB_2U(SCH_1):VIRTUAL_RESEAT_FPGA_R_N
   G7  VIRTUAL_RESEAT  DIFFIO_RX_L9N  @S9S_MB_2U_LIB.S9S_MB_2U(SCH_1):VIRTUAL_RESEAT
  V12  NC             DIFFIO_RX_B17N  NC
  V11  NC             DIFFIO_RX_B15P  NC
  V10  NC             DIFFIO_RX_B15N  NC
   U8  NC             DIFFIO_RX_B13N  NC
  C18  NC             DIFFIO_RX_R32P  NC
   J1  SMB_PLD_3V3AUX_SDA_R  DIFFIO_RX_L13P  @S9S_MB_2U_LIB.S9S_MB_2U(SCH_1):SMB_PLD_3V3AUX_SDA_R
   J2  SMB_PLD_3V3AUX_SCL_R  DIFFIO_RX_L13N  @S9S_MB_2U_LIB.S9S_MB_2U(SCH_1):SMB_PLD_3V3AUX_SCL_R
   K1  NC             DIFFIO_RX_L15P  NC
   K2  NC             DIFFIO_RX_L15N  NC
  B18  SGPIO_BMC_LD_N  DIFFIO_RX_R32N  @S9S_MB_2U_LIB.S9S_MB_2U(SCH_1):SGPIO_BMC_LD_N
  M17  SGPIO_BMC_DOUT  DIFFIO_RX_R15P  @S9S_MB_2U_LIB.S9S_MB_2U(SCH_1):SGPIO_BMC_DOUT
  J11  SGPIO_BMC_DIN_R  DIFFIO_RX_R20P  @S9S_MB_2U_LIB.S9S_MB_2U(SCH_1):SGPIO_BMC_DIN_R
  J12  SGPIO_BMC_CLK  DIFFIO_RX_R20N  @S9S_MB_2U_LIB.S9S_MB_2U(SCH_1):SGPIO_BMC_CLK
  M18  RST_SGPIO_RESET_N_R  DIFFIO_RX_R13N  @S9S_MB_2U_LIB.S9S_MB_2U(SCH_1):RST_SGPIO_RESET_N_R
  H18  RST_PLTRST_PLD_B_N  DIFFIO_RX_R18P  @S9S_MB_2U_LIB.S9S_MB_2U(SCH_1):RST_PLTRST_PLD_B_N
  V16  RST_PLD_CPU1_DRAM_GH_N  DIFFIO_RX_B28N  @S9S_MB_2U_LIB.S9S_MB_2U(SCH_1):RST_PLD_CPU1_DRAM_GH_N
  V14  RST_PLD_CPU1_DRAM_EF_N  DIFFIO_RX_B22P  @S9S_MB_2U_LIB.S9S_MB_2U(SCH_1):RST_PLD_CPU1_DRAM_EF_N
  V15  RST_PLD_CPU1_DRAM_AB_N  DIFFIO_RX_B26N  @S9S_MB_2U_LIB.S9S_MB_2U(SCH_1):RST_PLD_CPU1_DRAM_AB_N
  V13  RST_PLD_CPU0_DRAM_GH_N  DIFFIO_RX_B22N  @S9S_MB_2U_LIB.S9S_MB_2U(SCH_1):RST_PLD_CPU0_DRAM_GH_N
  H17  RST_PCIE_PCH_DEV_PERST_N  DIFFIO_RX_R19P  @S9S_MB_2U_LIB.S9S_MB_2U(SCH_1):RST_PCIE_PCH_DEV_PERST_N
  H16  RST_PCIE_CPU1_DEV_PERST_N  DIFFIO_RX_R23N  @S9S_MB_2U_LIB.S9S_MB_2U(SCH_1):RST_PCIE_CPU1_DEV_PERST_N
  H15  RST_PCIE_CPU0_DEV_PERST_N  DIFFIO_RX_R22N  @S9S_MB_2U_LIB.S9S_MB_2U(SCH_1):RST_PCIE_CPU0_DEV_PERST_N
  T13  RST_CPU1_DRAM_AB_PLD_N  DIFFIO_RX_B24N  @S9S_MB_2U_LIB.S9S_MB_2U(SCH_1):RST_CPU1_DRAM_AB_PLD_N
  T14  RST_CPU0_DRAM_EF_PLD_N  DIFFIO_RX_B24P  @S9S_MB_2U_LIB.S9S_MB_2U(SCH_1):RST_CPU0_DRAM_EF_PLD_N
  U12  RST_CPU0_DRAM_AB_PLD_N  DIFFIO_RX_B19N  @S9S_MB_2U_LIB.S9S_MB_2U(SCH_1):RST_CPU0_DRAM_AB_PLD_N
   F2  ROT_P1_RST_IND_N_R  DIFFIO_RX_L7P||ADC1IN8  @S9S_MB_2U_LIB.S9S_MB_2U(SCH_1):ROT_P1_RST_IND_N_R
   F1  NC             DIFFIO_RX_L8N||ADC1IN15  NC
   U5  PWRGD_S0_PWROK_CPU1_LVC1_R  DIFFIO_RX_B6N  @S9S_MB_2U_LIB.S9S_MB_2U(SCH_1):PWRGD_S0_PWROK_CPU1_LVC1_R
  U11  PWRGD_S0_PWROK_CPU0_LVC1_R  DIFFIO_RX_B17P  @S9S_MB_2U_LIB.S9S_MB_2U(SCH_1):PWRGD_S0_PWROK_CPU0_LVC1_R
   L7  PWRGD_PVPP_HBM_CPU1  DIFFIO_RX_L25N  @S9S_MB_2U_LIB.S9S_MB_2U(SCH_1):PWRGD_PVPP_HBM_CPU1
   P3  PWRGD_PVPP_HBM_CPU0  DIFFIO_RX_L24P  @S9S_MB_2U_LIB.S9S_MB_2U(SCH_1):PWRGD_PVPP_HBM_CPU0
   T3  PWRGD_PVNN_PCH_AUX  DIFFIO_RX_L23P  @S9S_MB_2U_LIB.S9S_MB_2U(SCH_1):PWRGD_PVNN_PCH_AUX
   P2  PWRGD_PVNN_MAIN_CPU1  DIFFIO_RX_L24N  @S9S_MB_2U_LIB.S9S_MB_2U(SCH_1):PWRGD_PVNN_MAIN_CPU1
   R3  PWRGD_PVNN_MAIN_CPU0  DIFFIO_RX_L23N  @S9S_MB_2U_LIB.S9S_MB_2U(SCH_1):PWRGD_PVNN_MAIN_CPU0
   P1  PWRGD_PVCCIN_CPU0  DIFFIO_RX_L21P  @S9S_MB_2U_LIB.S9S_MB_2U(SCH_1):PWRGD_PVCCIN_CPU0
   N1  PWRGD_PVCCFA_EHV_FIVRA_CPU0  DIFFIO_RX_L21N  @S9S_MB_2U_LIB.S9S_MB_2U(SCH_1):PWRGD_PVCCFA_EHV_FIVRA_CPU0
   M2  PWRGD_PVCCD_HV_CPU0  DIFFIO_RX_L19P  @S9S_MB_2U_LIB.S9S_MB_2U(SCH_1):PWRGD_PVCCD_HV_CPU0
  N14  PWRGD_PS_PWROK_PLD_R  DIFFIO_RX_R1P  @S9S_MB_2U_LIB.S9S_MB_2U(SCH_1):PWRGD_PS_PWROK_PLD_R
   M1  PWRGD_P3V3_AUX_PLD  DIFFIO_RX_L19N  @S9S_MB_2U_LIB.S9S_MB_2U(SCH_1):PWRGD_P3V3_AUX_PLD
   U2  PWRGD_P3V3     DIFFIO_RX_L28P  @S9S_MB_2U_LIB.S9S_MB_2U(SCH_1):PWRGD_P3V3
   U1  NC             DIFFIO_RX_L28N  NC
   C1  PWRGD_FAIL_CPU1_GH  DIFFIO_RX_L4P||ADC1IN12  @S9S_MB_2U_LIB.S9S_MB_2U(SCH_1):PWRGD_FAIL_CPU1_GH
   H6  PWRGD_FAIL_CPU1_EF  DIFFIO_RX_L3P||ADC1IN4  @S9S_MB_2U_LIB.S9S_MB_2U(SCH_1):PWRGD_FAIL_CPU1_EF
   B1  PWRGD_FAIL_CPU1_CD  DIFFIO_RX_L4N||ADC1IN11  @S9S_MB_2U_LIB.S9S_MB_2U(SCH_1):PWRGD_FAIL_CPU1_CD
   G6  PWRGD_FAIL_CPU1_AB  DIFFIO_RX_L3N||ADC1IN3  @S9S_MB_2U_LIB.S9S_MB_2U(SCH_1):PWRGD_FAIL_CPU1_AB
   D2  PWRGD_FAIL_CPU0_GH  DIFFIO_RX_L2P||ADC1IN16  @S9S_MB_2U_LIB.S9S_MB_2U(SCH_1):PWRGD_FAIL_CPU0_GH
   E4  PWRGD_FAIL_CPU0_EF  DIFFIO_RX_L1P||ADC1IN2  @S9S_MB_2U_LIB.S9S_MB_2U(SCH_1):PWRGD_FAIL_CPU0_EF
   C2  PWRGD_FAIL_CPU0_CD  DIFFIO_RX_L2N||ADC1IN9  @S9S_MB_2U_LIB.S9S_MB_2U(SCH_1):PWRGD_FAIL_CPU0_CD
   D4  PWRGD_FAIL_CPU0_AB  DIFFIO_RX_L1N||ADC1IN1  @S9S_MB_2U_LIB.S9S_MB_2U(SCH_1):PWRGD_FAIL_CPU0_AB
  V17  PWRGD_DRAMPWRGD_CPU1_GH_R_LVC1  DIFFIO_RX_B28P  @S9S_MB_2U_LIB.S9S_MB_2U(SCH_1):PWRGD_DRAMPWRGD_CPU1_GH_R_LVC1
  U13  PWRGD_DRAMPWRGD_CPU1_EF_R_LVC1  DIFFIO_RX_B19P  @S9S_MB_2U_LIB.S9S_MB_2U(SCH_1):PWRGD_DRAMPWRGD_CPU1_EF_R_LVC1
  U15  PWRGD_DRAMPWRGD_CPU1_AB_R_LVC1  DIFFIO_RX_B26P  @S9S_MB_2U_LIB.S9S_MB_2U(SCH_1):PWRGD_DRAMPWRGD_CPU1_AB_R_LVC1
   U7  PWRGD_CPUPWRGD_LVC1  DIFFIO_RX_B11N  @S9S_MB_2U_LIB.S9S_MB_2U(SCH_1):PWRGD_CPUPWRGD_LVC1
   U3  PWRGD_CPU0_LVC1_R  DIFFIO_RX_B2N  @S9S_MB_2U_LIB.S9S_MB_2U(SCH_1):PWRGD_CPU0_LVC1_R
   K3  PU_RST_DEDI_BUSY_PLD_N  DIFFIO_RX_L16P  @S9S_MB_2U_LIB.S9S_MB_2U(SCH_1):PU_RST_DEDI_BUSY_PLD_N
   K7  OCP_SFF_AUX_PWR_EN  DIFFIO_RX_L14P  @S9S_MB_2U_LIB.S9S_MB_2U(SCH_1):OCP_SFF_AUX_PWR_EN
   T2  IRQ_SML1_PMBUS_PLD_ALERT_N  DIFFIO_RX_L26P  @S9S_MB_2U_LIB.S9S_MB_2U(SCH_1):IRQ_SML1_PMBUS_PLD_ALERT_N
   M7  IRQ_SML1_PMBUS_BMC_ALERT_N  DIFFIO_RX_L25P  @S9S_MB_2U_LIB.S9S_MB_2U(SCH_1):IRQ_SML1_PMBUS_BMC_ALERT_N
   T1  IRQ_SML0_ALERT_R_N  DIFFIO_RX_L26N  @S9S_MB_2U_LIB.S9S_MB_2U(SCH_1):IRQ_SML0_ALERT_R_N
  P14  IRQ_SGPIO_INTR_N_R  DIFFIO_RX_R1N  @S9S_MB_2U_LIB.S9S_MB_2U(SCH_1):IRQ_SGPIO_INTR_N_R
  P18  IRQ_PSYS_CRIT_N  DIFFIO_RX_R12N  @S9S_MB_2U_LIB.S9S_MB_2U(SCH_1):IRQ_PSYS_CRIT_N
   G3  IRQ_PCH_CPU_NMI_EVENT_N  DIFFIO_RX_L7N||ADC1IN7  @S9S_MB_2U_LIB.S9S_MB_2U(SCH_1):IRQ_PCH_CPU_NMI_EVENT_N
  G17  IRQ_CPU1_VRHOT_N  DIFFIO_RX_R19N  @S9S_MB_2U_LIB.S9S_MB_2U(SCH_1):IRQ_CPU1_VRHOT_N
  G16  IRQ_CPU0_VRHOT_N  DIFFIO_RX_R28P  @S9S_MB_2U_LIB.S9S_MB_2U(SCH_1):IRQ_CPU0_VRHOT_N
   E1  IRQ_BMC_CPU_NMI_R1  DIFFIO_RX_L6P||ADC1IN14  @S9S_MB_2U_LIB.S9S_MB_2U(SCH_1):IRQ_BMC_CPU_NMI_R1
   D1  IRQ0_A57_R     DIFFIO_RX_L6N||ADC1IN13  @S9S_MB_2U_LIB.S9S_MB_2U(SCH_1):IRQ0_A57_R
   T7  H_CPU_RMCA_LVC1_R_N  DIFFIO_RX_B8N  @S9S_MB_2U_LIB.S9S_MB_2U(SCH_1):H_CPU_RMCA_LVC1_R_N
   V3  H_CPU_ERR2_LVC1_N  DIFFIO_RX_B4N  @S9S_MB_2U_LIB.S9S_MB_2U(SCH_1):H_CPU_ERR2_LVC1_N
   V2  H_CPU_ERR1_LVC1_N  DIFFIO_RX_B2P  @S9S_MB_2U_LIB.S9S_MB_2U(SCH_1):H_CPU_ERR1_LVC1_N
   V8  H_CPU1_MEMTRIP_LVC1_N  DIFFIO_RX_B13P  @S9S_MB_2U_LIB.S9S_MB_2U(SCH_1):H_CPU1_MEMTRIP_LVC1_N
   V7  H_CPU1_MEMHOT_OUT_LVC1_N  DIFFIO_RX_B11P  @S9S_MB_2U_LIB.S9S_MB_2U(SCH_1):H_CPU1_MEMHOT_OUT_LVC1_N
   V5  H_CPU0_MON_FAIL_PLD_LVC1_N  DIFFIO_RX_B6P  @S9S_MB_2U_LIB.S9S_MB_2U(SCH_1):H_CPU0_MON_FAIL_PLD_LVC1_N
   V4  H_CPU0_MEMTRIP_LVC1_N  DIFFIO_RX_B4P  @S9S_MB_2U_LIB.S9S_MB_2U(SCH_1):H_CPU0_MEMTRIP_LVC1_N
   T8  H_CPU0_MEMHOT_IN_LVC1_R_N  DIFFIO_RX_B8P  @S9S_MB_2U_LIB.S9S_MB_2U(SCH_1):H_CPU0_MEMHOT_IN_LVC1_R_N
   J6  FM_TPM_PRSNT_R_N  DIFFIO_RX_L14N  @S9S_MB_2U_LIB.S9S_MB_2U(SCH_1):FM_TPM_PRSNT_R_N
  G18  FM_SYS_THROTTLE_R_N  DIFFIO_RX_R18N  @S9S_MB_2U_LIB.S9S_MB_2U(SCH_1):FM_SYS_THROTTLE_R_N
  G12  FM_SLP_SUS_RSM_RST_N  DIFFIO_RX_R31N  @S9S_MB_2U_LIB.S9S_MB_2U(SCH_1):FM_SLP_SUS_RSM_RST_N
  L18  FM_SLPS4_PLD_N  DIFFIO_RX_R15N  @S9S_MB_2U_LIB.S9S_MB_2U(SCH_1):FM_SLPS4_PLD_N
   L2  FM_S3M_CPU1_CPLD_CRC_ERROR  DIFFIO_RX_L17P  @S9S_MB_2U_LIB.S9S_MB_2U(SCH_1):FM_S3M_CPU1_CPLD_CRC_ERROR
  K16  FM_S3M_CPU1_CPLD_CONFIG_N  DIFFIO_RX_R11N  @S9S_MB_2U_LIB.S9S_MB_2U(SCH_1):FM_S3M_CPU1_CPLD_CONFIG_N
   L1  FM_S3M_CPU0_CPLD_CRC_ERROR  DIFFIO_RX_L17N  @S9S_MB_2U_LIB.S9S_MB_2U(SCH_1):FM_S3M_CPU0_CPLD_CRC_ERROR
  K15  FM_S3M_CPU0_CPLD_CONFIG_N  DIFFIO_RX_R10N  @S9S_MB_2U_LIB.S9S_MB_2U(SCH_1):FM_S3M_CPU0_CPLD_CONFIG_N
  E16  FM_RST_PERST_BIT1  DIFFIO_RX_R29P  @S9S_MB_2U_LIB.S9S_MB_2U(SCH_1):FM_RST_PERST_BIT1
  E17  FM_RST_PERST_BIT0  DIFFIO_RX_R30N  @S9S_MB_2U_LIB.S9S_MB_2U(SCH_1):FM_RST_PERST_BIT0
  J18  FM_RISER1_JTAG_SEL_PLD_N  DIFFIO_RX_R17N  @S9S_MB_2U_LIB.S9S_MB_2U(SCH_1):FM_RISER1_JTAG_SEL_PLD_N
  N18  FM_PS_EN_PLD_R  DIFFIO_RX_R13P  @S9S_MB_2U_LIB.S9S_MB_2U(SCH_1):FM_PS_EN_PLD_R
   G1  FM_PSU_THROTTLE_N  DIFFIO_RX_L8P||ADC1IN10  @S9S_MB_2U_LIB.S9S_MB_2U(SCH_1):FM_PSU_THROTTLE_N
  T16  FM_PFR_DSW_PWROK_N  DIFFIO_RX_R2P  @S9S_MB_2U_LIB.S9S_MB_2U(SCH_1):FM_PFR_DSW_PWROK_N
  G11  FM_PCH_PRSNT_N  DIFFIO_RX_R31P  @S9S_MB_2U_LIB.S9S_MB_2U(SCH_1):FM_PCH_PRSNT_N
  R18  FM_ME_BT_DONE  DIFFIO_RX_R12P  @S9S_MB_2U_LIB.S9S_MB_2U(SCH_1):FM_ME_BT_DONE
   H1  NC             DIFFIO_RX_L10P  NC
   E5  FM_DIMM_12V_CPS_SX_N  DIFFIO_RX_L5P||ADC1IN6  @S9S_MB_2U_LIB.S9S_MB_2U(SCH_1):FM_DIMM_12V_CPS_SX_N
  R16  FM_CPU_RMCA_CATERR_DLY_LVT3_R_N  DIFFIO_RX_R2N  @S9S_MB_2U_LIB.S9S_MB_2U(SCH_1):FM_CPU_RMCA_CATERR_DLY_LVT3_R_N
  D18  FM_CPU1_SKTOCC_LVT3_PLD_N  DIFFIO_RX_R30P  @S9S_MB_2U_LIB.S9S_MB_2U(SCH_1):FM_CPU1_SKTOCC_LVT3_PLD_N
  K18  FM_CPU1_PROC_ID1  DIFFIO_RX_R17P  @S9S_MB_2U_LIB.S9S_MB_2U(SCH_1):FM_CPU1_PROC_ID1
  D16  FM_CPU1_PKGID1  DIFFIO_RX_R29N  @S9S_MB_2U_LIB.S9S_MB_2U(SCH_1):FM_CPU1_PKGID1
  G15  FM_CPU0_SKTOCC_LVT3_PLD_N  DIFFIO_RX_R27N  @S9S_MB_2U_LIB.S9S_MB_2U(SCH_1):FM_CPU0_SKTOCC_LVT3_PLD_N
  J16  FM_CPU0_PROC_ID1  DIFFIO_RX_R23P  @S9S_MB_2U_LIB.S9S_MB_2U(SCH_1):FM_CPU0_PROC_ID1
  J15  FM_CPU0_PROC_ID0  DIFFIO_RX_R22P  @S9S_MB_2U_LIB.S9S_MB_2U(SCH_1):FM_CPU0_PROC_ID0
  F16  FM_CPU0_PKGID1  DIFFIO_RX_R28N  @S9S_MB_2U_LIB.S9S_MB_2U(SCH_1):FM_CPU0_PKGID1
  F15  FM_CPU0_PKGID0  DIFFIO_RX_R27P  @S9S_MB_2U_LIB.S9S_MB_2U(SCH_1):FM_CPU0_PKGID0
   K4  FM_BMC_SUSACK_R_N  DIFFIO_RX_L16N  @S9S_MB_2U_LIB.S9S_MB_2U(SCH_1):FM_BMC_SUSACK_R_N
   F5  FM_BIOS_DEBUG_EN_N  DIFFIO_RX_L5N||ADC1IN5  @S9S_MB_2U_LIB.S9S_MB_2U(SCH_1):FM_BIOS_DEBUG_EN_N
  L16  FM_ADR_TRIGGER_N  DIFFIO_RX_R11P  @S9S_MB_2U_LIB.S9S_MB_2U(SCH_1):FM_ADR_TRIGGER_N
  L15  FM_ADR_COMPLETE  DIFFIO_RX_R10P  @S9S_MB_2U_LIB.S9S_MB_2U(SCH_1):FM_ADR_COMPLETE

TPS259520DSGR  I8   U123   [TPS259520DSGR-TPS259520DSGR,SMA]
    7  P3V3_E1S_2_ILM    ILM  @S9S_MB_2U_LIB.S9S_MB_2U(SCH_1):P3V3_E1S_2_ILM
    6  P3V3_E1S_2_FLT_N   FLT#  @S9S_MB_2U_LIB.S9S_MB_2U(SCH_1):P3V3_E1S_2_FLT_N
    1  P3V3_E1S_2_DVDT   DVDT  @S9S_MB_2U_LIB.S9S_MB_2U(SCH_1):P3V3_E1S_2_DVDT
    5  P3V3_E1S_2       OUT  @S9S_MB_2U_LIB.S9S_MB_2U(SCH_1):P3V3_E1S_2
    4  P3V3_AUX         IN2  @S9S_MB_2U_LIB.S9S_MB_2U(SCH_1):P3V3_AUX
    3  P3V3_AUX         IN1  @S9S_MB_2U_LIB.S9S_MB_2U(SCH_1):P3V3_AUX
   TH  GND            TH_GND  @S9S_MB_2U_LIB.S9S_MB_2U(SCH_1):GND
    8  GND              GND  @S9S_MB_2U_LIB.S9S_MB_2U(SCH_1):GND
    2  FM_P3V3_E1S_2_EN  EN||UVLO  @S9S_MB_2U_LIB.S9S_MB_2U(SCH_1):FM_P3V3_E1S_2_EN

TPS259520DSGR  I59  U124   [TPS259520DSGR-TPS259520DSGR,SMA]
    7  P3V3_E1S_1_ILM    ILM  @S9S_MB_2U_LIB.S9S_MB_2U(SCH_1):P3V3_E1S_1_ILM
    6  P3V3_E1S_1_FLT_N   FLT#  @S9S_MB_2U_LIB.S9S_MB_2U(SCH_1):P3V3_E1S_1_FLT_N
    1  P3V3_E1S_1_DVDT   DVDT  @S9S_MB_2U_LIB.S9S_MB_2U(SCH_1):P3V3_E1S_1_DVDT
    5  P3V3_E1S_1       OUT  @S9S_MB_2U_LIB.S9S_MB_2U(SCH_1):P3V3_E1S_1
    4  P3V3_AUX         IN2  @S9S_MB_2U_LIB.S9S_MB_2U(SCH_1):P3V3_AUX
    3  P3V3_AUX         IN1  @S9S_MB_2U_LIB.S9S_MB_2U(SCH_1):P3V3_AUX
   TH  GND            TH_GND  @S9S_MB_2U_LIB.S9S_MB_2U(SCH_1):GND
    8  GND              GND  @S9S_MB_2U_LIB.S9S_MB_2U(SCH_1):GND
    2  FM_P3V3_E1S_1_EN  EN||UVLO  @S9S_MB_2U_LIB.S9S_MB_2U(SCH_1):FM_P3V3_E1S_1_EN

TPS259520DSGR  I25  U125   [TPS259520DSGR-TPS259520DSGR,SMA]
    7  P3V3_E1S_3_ILM    ILM  @S9S_MB_2U_LIB.S9S_MB_2U(SCH_1):P3V3_E1S_3_ILM
    6  P3V3_E1S_3_FLT_N   FLT#  @S9S_MB_2U_LIB.S9S_MB_2U(SCH_1):P3V3_E1S_3_FLT_N
    1  P3V3_E1S_3_DVDT   DVDT  @S9S_MB_2U_LIB.S9S_MB_2U(SCH_1):P3V3_E1S_3_DVDT
    5  P3V3_E1S_3       OUT  @S9S_MB_2U_LIB.S9S_MB_2U(SCH_1):P3V3_E1S_3
    4  P3V3_AUX         IN2  @S9S_MB_2U_LIB.S9S_MB_2U(SCH_1):P3V3_AUX
    3  P3V3_AUX         IN1  @S9S_MB_2U_LIB.S9S_MB_2U(SCH_1):P3V3_AUX
   TH  GND            TH_GND  @S9S_MB_2U_LIB.S9S_MB_2U(SCH_1):GND
    8  GND              GND  @S9S_MB_2U_LIB.S9S_MB_2U(SCH_1):GND
    2  FM_P3V3_E1S_3_EN  EN||UVLO  @S9S_MB_2U_LIB.S9S_MB_2U(SCH_1):FM_P3V3_E1S_3_EN

TPS259540DSGR  I156  U126   [TPS259540DSGR-TPS259540DSGR,SMA]
    4  P12V_FRONT_CPU    IN2  @S9S_MB_2U_LIB.S9S_MB_2U(SCH_1):P12V_FRONT_CPU
    3  P12V_FRONT_CPU    IN1  @S9S_MB_2U_LIB.S9S_MB_2U(SCH_1):P12V_FRONT_CPU
    7  P12V_E1S_0_ILM    ILM  @S9S_MB_2U_LIB.S9S_MB_2U(SCH_1):P12V_E1S_0_ILM
    6  P12V_E1S_0_FLT_N   FLT#  @S9S_MB_2U_LIB.S9S_MB_2U(SCH_1):P12V_E1S_0_FLT_N
    1  P12V_E1S_0_DVDT   DVDT  @S9S_MB_2U_LIB.S9S_MB_2U(SCH_1):P12V_E1S_0_DVDT
    5  P12V_E1S_0       OUT  @S9S_MB_2U_LIB.S9S_MB_2U(SCH_1):P12V_E1S_0
   TH  GND            TH_GND  @S9S_MB_2U_LIB.S9S_MB_2U(SCH_1):GND
    8  GND              GND  @S9S_MB_2U_LIB.S9S_MB_2U(SCH_1):GND
    2  FM_P12V_E1S_0_EN  EN||UVLO  @S9S_MB_2U_LIB.S9S_MB_2U(SCH_1):FM_P12V_E1S_0_EN

TPS259540DSGR  I159  U127   [TPS259540DSGR-TPS259540DSGR,SMA]
    4  P12V_FRONT_CPU    IN2  @S9S_MB_2U_LIB.S9S_MB_2U(SCH_1):P12V_FRONT_CPU
    3  P12V_FRONT_CPU    IN1  @S9S_MB_2U_LIB.S9S_MB_2U(SCH_1):P12V_FRONT_CPU
    7  P12V_E1S_2_ILM    ILM  @S9S_MB_2U_LIB.S9S_MB_2U(SCH_1):P12V_E1S_2_ILM
    6  P12V_E1S_2_FLT_N   FLT#  @S9S_MB_2U_LIB.S9S_MB_2U(SCH_1):P12V_E1S_2_FLT_N
    1  P12V_E1S_2_DVDT   DVDT  @S9S_MB_2U_LIB.S9S_MB_2U(SCH_1):P12V_E1S_2_DVDT
    5  P12V_E1S_2       OUT  @S9S_MB_2U_LIB.S9S_MB_2U(SCH_1):P12V_E1S_2
   TH  GND            TH_GND  @S9S_MB_2U_LIB.S9S_MB_2U(SCH_1):GND
    8  GND              GND  @S9S_MB_2U_LIB.S9S_MB_2U(SCH_1):GND
    2  FM_P12V_E1S_2_EN  EN||UVLO  @S9S_MB_2U_LIB.S9S_MB_2U(SCH_1):FM_P12V_E1S_2_EN

TPS259540DSGR  I157  U128   [TPS259540DSGR-TPS259540DSGR,SMA]
    4  P12V_FRONT_CPU    IN2  @S9S_MB_2U_LIB.S9S_MB_2U(SCH_1):P12V_FRONT_CPU
    3  P12V_FRONT_CPU    IN1  @S9S_MB_2U_LIB.S9S_MB_2U(SCH_1):P12V_FRONT_CPU
    7  P12V_E1S_1_ILM    ILM  @S9S_MB_2U_LIB.S9S_MB_2U(SCH_1):P12V_E1S_1_ILM
    6  P12V_E1S_1_FLT_N   FLT#  @S9S_MB_2U_LIB.S9S_MB_2U(SCH_1):P12V_E1S_1_FLT_N
    1  P12V_E1S_1_DVDT   DVDT  @S9S_MB_2U_LIB.S9S_MB_2U(SCH_1):P12V_E1S_1_DVDT
    5  P12V_E1S_1       OUT  @S9S_MB_2U_LIB.S9S_MB_2U(SCH_1):P12V_E1S_1
   TH  GND            TH_GND  @S9S_MB_2U_LIB.S9S_MB_2U(SCH_1):GND
    8  GND              GND  @S9S_MB_2U_LIB.S9S_MB_2U(SCH_1):GND
    2  FM_P12V_E1S_1_EN  EN||UVLO  @S9S_MB_2U_LIB.S9S_MB_2U(SCH_1):FM_P12V_E1S_1_EN

TPS259540DSGR  I158  U129   [TPS259540DSGR-TPS259540DSGR,SMA]
    4  P12V_FRONT_CPU    IN2  @S9S_MB_2U_LIB.S9S_MB_2U(SCH_1):P12V_FRONT_CPU
    3  P12V_FRONT_CPU    IN1  @S9S_MB_2U_LIB.S9S_MB_2U(SCH_1):P12V_FRONT_CPU
    7  P12V_E1S_3_ILM    ILM  @S9S_MB_2U_LIB.S9S_MB_2U(SCH_1):P12V_E1S_3_ILM
    6  P12V_E1S_3_FLT_N   FLT#  @S9S_MB_2U_LIB.S9S_MB_2U(SCH_1):P12V_E1S_3_FLT_N
    1  P12V_E1S_3_DVDT   DVDT  @S9S_MB_2U_LIB.S9S_MB_2U(SCH_1):P12V_E1S_3_DVDT
    5  P12V_E1S_3       OUT  @S9S_MB_2U_LIB.S9S_MB_2U(SCH_1):P12V_E1S_3
   TH  GND            TH_GND  @S9S_MB_2U_LIB.S9S_MB_2U(SCH_1):GND
    8  GND              GND  @S9S_MB_2U_LIB.S9S_MB_2U(SCH_1):GND
    2  FM_P12V_E1S_3_EN  EN||UVLO  @S9S_MB_2U_LIB.S9S_MB_2U(SCH_1):FM_P12V_E1S_3_EN

PCA9555PW  I1   U130   [PCA9555PW_SMLF-PCA9555PW,IC,TMA]
    7  NC               P03  NC
    4  NC               P00  NC
   20  NC               P17  NC
   19  NC               P16  NC
   18  NC               P15  NC
   16  NC               P13  NC
   13  NC               P10  NC
   11  NC               P07  NC
   10  NC               P06  NC
    9  NC               P05  NC
    1  NC              INT*  NC
   23  SMB_PEHPCPU0_LVC3_R1_SDA    SDA  @S9S_MB_2U_LIB.S9S_MB_2U(SCH_1):SMB_PEHPCPU0_LVC3_R1_SDA
   22  SMB_PEHPCPU0_LVC3_R1_SCL    SCL  @S9S_MB_2U_LIB.S9S_MB_2U(SCH_1):SMB_PEHPCPU0_LVC3_R1_SCL
    3  PCA9555_1_ADD2     A2  @S9S_MB_2U_LIB.S9S_MB_2U(SCH_1):PCA9555_1_ADD2
    2  PCA9555_1_ADD1     A1  @S9S_MB_2U_LIB.S9S_MB_2U(SCH_1):PCA9555_1_ADD1
   21  PCA9555_1_ADD0     A0  @S9S_MB_2U_LIB.S9S_MB_2U(SCH_1):PCA9555_1_ADD0
   24  P3V3_AUX         VDD  @S9S_MB_2U_LIB.S9S_MB_2U(SCH_1):P3V3_AUX
   12  GND              VSS  @S9S_MB_2U_LIB.S9S_MB_2U(SCH_1):GND
   14  E1S_1_PWR_FAIL_N    P11  @S9S_MB_2U_LIB.S9S_MB_2U(SCH_1):E1S_1_PWR_FAIL_N
   17  E1S_1_BUF_PRSNT_N    P14  @S9S_MB_2U_LIB.S9S_MB_2U(SCH_1):E1S_1_BUF_PRSNT_N
   15  E1S_1_BUF_EN     P12  @S9S_MB_2U_LIB.S9S_MB_2U(SCH_1):E1S_1_BUF_EN
    6  E1S_1_BUF_EN     P02  @S9S_MB_2U_LIB.S9S_MB_2U(SCH_1):E1S_1_BUF_EN
    5  E1S_0_PWR_FAIL_N    P01  @S9S_MB_2U_LIB.S9S_MB_2U(SCH_1):E1S_0_PWR_FAIL_N
    8  E1S_0_BUF_PRSNT_N    P04  @S9S_MB_2U_LIB.S9S_MB_2U(SCH_1):E1S_0_BUF_PRSNT_N

PCA9555PW  I51  U131   [PCA9555PW_SMLF-PCA9555PW,IC,TMA]
   20  NC               P17  NC
   19  NC               P16  NC
   18  NC               P15  NC
   16  NC               P13  NC
   13  NC               P10  NC
   11  NC               P07  NC
   10  NC               P06  NC
    9  NC               P05  NC
    7  NC               P03  NC
    4  NC               P00  NC
    1  NC              INT*  NC
   23  SMB_PEHPCPU0_LVC3_R2_SDA    SDA  @S9S_MB_2U_LIB.S9S_MB_2U(SCH_1):SMB_PEHPCPU0_LVC3_R2_SDA
   22  SMB_PEHPCPU0_LVC3_R2_SCL    SCL  @S9S_MB_2U_LIB.S9S_MB_2U(SCH_1):SMB_PEHPCPU0_LVC3_R2_SCL
    3  PCA9555_2_ADD2     A2  @S9S_MB_2U_LIB.S9S_MB_2U(SCH_1):PCA9555_2_ADD2
    2  PCA9555_2_ADD1     A1  @S9S_MB_2U_LIB.S9S_MB_2U(SCH_1):PCA9555_2_ADD1
   21  PCA9555_2_ADD0     A0  @S9S_MB_2U_LIB.S9S_MB_2U(SCH_1):PCA9555_2_ADD0
   24  P3V3_AUX         VDD  @S9S_MB_2U_LIB.S9S_MB_2U(SCH_1):P3V3_AUX
   12  GND              VSS  @S9S_MB_2U_LIB.S9S_MB_2U(SCH_1):GND
   14  E1S_3_PWR_FAIL_N    P11  @S9S_MB_2U_LIB.S9S_MB_2U(SCH_1):E1S_3_PWR_FAIL_N
   17  E1S_3_BUF_PRSNT_N    P14  @S9S_MB_2U_LIB.S9S_MB_2U(SCH_1):E1S_3_BUF_PRSNT_N
   15  E1S_3_BUF_EN     P12  @S9S_MB_2U_LIB.S9S_MB_2U(SCH_1):E1S_3_BUF_EN
    5  E1S_2_PWR_FAIL_N    P01  @S9S_MB_2U_LIB.S9S_MB_2U(SCH_1):E1S_2_PWR_FAIL_N
    8  E1S_2_BUF_PRSNT_N    P04  @S9S_MB_2U_LIB.S9S_MB_2U(SCH_1):E1S_2_BUF_PRSNT_N
    6  E1S_2_BUF_EN     P02  @S9S_MB_2U_LIB.S9S_MB_2U(SCH_1):E1S_2_BUF_EN

SN74LVC2G17DCKR  I80  U132   [SN74LVC2G17DCKR-SN74LVC2G17DCKA]
    5  P3V3_AUX         VCC  @S9S_MB_2U_LIB.S9S_MB_2U(SCH_1):P3V3_AUX
    2  GND              GND  @S9S_MB_2U_LIB.S9S_MB_2U(SCH_1):GND
    3  E1S_1_PRSNT_N     2A  @S9S_MB_2U_LIB.S9S_MB_2U(SCH_1):E1S_1_PRSNT_N
    4  E1S_1_BUF_PRSNT_R_N     2Y  @S9S_MB_2U_LIB.S9S_MB_2U(SCH_1):E1S_1_BUF_PRSNT_R_N
    1  E1S_0_PRSNT_N     1A  @S9S_MB_2U_LIB.S9S_MB_2U(SCH_1):E1S_0_PRSNT_N
    6  E1S_0_BUF_PRSNT_R_N     1Y  @S9S_MB_2U_LIB.S9S_MB_2U(SCH_1):E1S_0_BUF_PRSNT_R_N

SN74LVC2G17DCKR  I93  U133   [SN74LVC2G17DCKR-SN74LVC2G17DCKA]
    5  P3V3_AUX         VCC  @S9S_MB_2U_LIB.S9S_MB_2U(SCH_1):P3V3_AUX
    2  GND              GND  @S9S_MB_2U_LIB.S9S_MB_2U(SCH_1):GND
    3  E1S_3_PRSNT_N     2A  @S9S_MB_2U_LIB.S9S_MB_2U(SCH_1):E1S_3_PRSNT_N
    4  E1S_3_BUF_PRSNT_R_N     2Y  @S9S_MB_2U_LIB.S9S_MB_2U(SCH_1):E1S_3_BUF_PRSNT_R_N
    1  E1S_2_PRSNT_N     1A  @S9S_MB_2U_LIB.S9S_MB_2U(SCH_1):E1S_2_PRSNT_N
    6  E1S_2_BUF_PRSNT_R_N     1Y  @S9S_MB_2U_LIB.S9S_MB_2U(SCH_1):E1S_2_BUF_PRSNT_R_N

SN74LVC2G07DCKR  I1   U134   [SN74LVC2G07DCKR_SMLF-SN74LVC2GA]
    3  RST_PCIE_E1S_PERST_N     2A  @S9S_MB_2U_LIB.S9S_MB_2U(SCH_1):RST_PCIE_E1S_PERST_N
    1  RST_PCIE_E1S_PERST_N     1A  @S9S_MB_2U_LIB.S9S_MB_2U(SCH_1):RST_PCIE_E1S_PERST_N
    4  RST_PCIE_BUF_E1S_1_PERST_N     2Y  @S9S_MB_2U_LIB.S9S_MB_2U(SCH_1):RST_PCIE_BUF_E1S_1_PERST_N
    6  RST_PCIE_BUF_E1S_0_PERST_N     1Y  @S9S_MB_2U_LIB.S9S_MB_2U(SCH_1):RST_PCIE_BUF_E1S_0_PERST_N
    5  P3V3_AUX         VCC  @S9S_MB_2U_LIB.S9S_MB_2U(SCH_1):P3V3_AUX
    2  GND              GND  @S9S_MB_2U_LIB.S9S_MB_2U(SCH_1):GND

SN74LVC2G07DCKR  I24  U135   [SN74LVC2G07DCKR_SMLF-SN74LVC2GA]
    3  RST_PCIE_E1S_PERST_N     2A  @S9S_MB_2U_LIB.S9S_MB_2U(SCH_1):RST_PCIE_E1S_PERST_N
    1  RST_PCIE_E1S_PERST_N     1A  @S9S_MB_2U_LIB.S9S_MB_2U(SCH_1):RST_PCIE_E1S_PERST_N
    4  RST_PCIE_BUF_E1S_3_PERST_N     2Y  @S9S_MB_2U_LIB.S9S_MB_2U(SCH_1):RST_PCIE_BUF_E1S_3_PERST_N
    6  RST_PCIE_BUF_E1S_2_PERST_N     1Y  @S9S_MB_2U_LIB.S9S_MB_2U(SCH_1):RST_PCIE_BUF_E1S_2_PERST_N
    5  P3V3_AUX         VCC  @S9S_MB_2U_LIB.S9S_MB_2U(SCH_1):P3V3_AUX
    2  GND              GND  @S9S_MB_2U_LIB.S9S_MB_2U(SCH_1):GND

SN74LVC2G07DCKR  I46  U136   [SN74LVC2G07DCKR_SMLF-SN74LVC2GA]
    3  RST_SMB_E1S_N     2A  @S9S_MB_2U_LIB.S9S_MB_2U(SCH_1):RST_SMB_E1S_N
    1  RST_SMB_E1S_N     1A  @S9S_MB_2U_LIB.S9S_MB_2U(SCH_1):RST_SMB_E1S_N
    4  RST_SMB_BUF_E1S_1_N     2Y  @S9S_MB_2U_LIB.S9S_MB_2U(SCH_1):RST_SMB_BUF_E1S_1_N
    6  RST_SMB_BUF_E1S_0_N     1Y  @S9S_MB_2U_LIB.S9S_MB_2U(SCH_1):RST_SMB_BUF_E1S_0_N
    5  P3V3_AUX         VCC  @S9S_MB_2U_LIB.S9S_MB_2U(SCH_1):P3V3_AUX
    2  GND              GND  @S9S_MB_2U_LIB.S9S_MB_2U(SCH_1):GND

SN74LVC2G07DCKR  I48  U137   [SN74LVC2G07DCKR_SMLF-SN74LVC2GA]
    3  RST_SMB_E1S_N     2A  @S9S_MB_2U_LIB.S9S_MB_2U(SCH_1):RST_SMB_E1S_N
    1  RST_SMB_E1S_N     1A  @S9S_MB_2U_LIB.S9S_MB_2U(SCH_1):RST_SMB_E1S_N
    4  RST_SMB_BUF_E1S_3_N     2Y  @S9S_MB_2U_LIB.S9S_MB_2U(SCH_1):RST_SMB_BUF_E1S_3_N
    6  RST_SMB_BUF_E1S_2_N     1Y  @S9S_MB_2U_LIB.S9S_MB_2U(SCH_1):RST_SMB_BUF_E1S_2_N
    5  P3V3_AUX         VCC  @S9S_MB_2U_LIB.S9S_MB_2U(SCH_1):P3V3_AUX
    2  GND              GND  @S9S_MB_2U_LIB.S9S_MB_2U(SCH_1):GND

TPS259540DSGR  I52  U138   [TPS259540DSGR-TPS259540DSGR,SMA]
    7  P12V_SCM_ILM     ILM  @S9S_MB_2U_LIB.S9S_MB_2U(SCH_1):P12V_SCM_ILM
    6  P12V_SCM_FLT_N   FLT#  @S9S_MB_2U_LIB.S9S_MB_2U(SCH_1):P12V_SCM_FLT_N
    2  P12V_SCM_EN_N  EN||UVLO  @S9S_MB_2U_LIB.S9S_MB_2U(SCH_1):P12V_SCM_EN_N
    1  P12V_SCM_DVDT   DVDT  @S9S_MB_2U_LIB.S9S_MB_2U(SCH_1):P12V_SCM_DVDT
    5  P12V_SCM         OUT  @S9S_MB_2U_LIB.S9S_MB_2U(SCH_1):P12V_SCM
    4  P12V_AUX         IN2  @S9S_MB_2U_LIB.S9S_MB_2U(SCH_1):P12V_AUX
    3  P12V_AUX         IN1  @S9S_MB_2U_LIB.S9S_MB_2U(SCH_1):P12V_AUX
   TH  GND            TH_GND  @S9S_MB_2U_LIB.S9S_MB_2U(SCH_1):GND
    8  GND              GND  @S9S_MB_2U_LIB.S9S_MB_2U(SCH_1):GND

PCA9546APWR  I91  U141   [PCA9546APWR-PCA9546APWR,SMLF,IA]
    4  SMB_PCIE_3V3AUX_SDA_R4    SD0  @S9S_MB_2U_LIB.S9S_MB_2U(SCH_1):SMB_PCIE_3V3AUX_SDA_R4
    6  SMB_PCIE_3V3AUX_SDA_R3    SD1  @S9S_MB_2U_LIB.S9S_MB_2U(SCH_1):SMB_PCIE_3V3AUX_SDA_R3
    5  SMB_PCIE_3V3AUX_SCL_R4    SC0  @S9S_MB_2U_LIB.S9S_MB_2U(SCH_1):SMB_PCIE_3V3AUX_SCL_R4
    7  SMB_PCIE_3V3AUX_SCL_R3    SC1  @S9S_MB_2U_LIB.S9S_MB_2U(SCH_1):SMB_PCIE_3V3AUX_SCL_R3
   15  SMB_PCIE3_3V3AUX_SDA    SDA  @S9S_MB_2U_LIB.S9S_MB_2U(SCH_1):SMB_PCIE3_3V3AUX_SDA
   14  SMB_PCIE3_3V3AUX_SCL    SCL  @S9S_MB_2U_LIB.S9S_MB_2U(SCH_1):SMB_PCIE3_3V3AUX_SCL
    3  PU_RST_SMB_PCIE3_N  RESET#  @S9S_MB_2U_LIB.S9S_MB_2U(SCH_1):PU_RST_SMB_PCIE3_N
   13  PCA9546_PCIE3_ADDR2     A2  @S9S_MB_2U_LIB.S9S_MB_2U(SCH_1):PCA9546_PCIE3_ADDR2
    2  PCA9546_PCIE3_ADDR1     A1  @S9S_MB_2U_LIB.S9S_MB_2U(SCH_1):PCA9546_PCIE3_ADDR1
    1  PCA9546_PCIE3_ADDR0     A0  @S9S_MB_2U_LIB.S9S_MB_2U(SCH_1):PCA9546_PCIE3_ADDR0
   16  P3V3_AUX         VCC  @S9S_MB_2U_LIB.S9S_MB_2U(SCH_1):P3V3_AUX
   11  NC               SD3  NC
    9  NC               SD2  NC
   12  NC               SC3  NC
   10  NC               SC2  NC
    8  GND              GND  @S9S_MB_2U_LIB.S9S_MB_2U(SCH_1):GND

TP_TDR_4P_FTS  I13  X1     [TP_TDR_4P_FTS_TH-TP_TDR_4P_DIPA]
    3  T_GND             P2  @S9S_MB_2U_LIB.S9S_MB_2U(SCH_1):T_GND
    2  T_GND             P1  @S9S_MB_2U_LIB.S9S_MB_2U(SCH_1):T_GND
    1  TDR_DIFF_85_TOP_DP     S1  @S9S_MB_2U_LIB.S9S_MB_2U(SCH_1):TDR_DIFF_85_TOP_DP
    4  TDR_DIFF_85_TOP_DN     S2  @S9S_MB_2U_LIB.S9S_MB_2U(SCH_1):TDR_DIFF_85_TOP_DN

TP_TDR_4P_FTS  I18  X2     [TP_TDR_4P_FTS_TH-TP_TDR_4P_DIPA]
    3  T_GND             P2  @S9S_MB_2U_LIB.S9S_MB_2U(SCH_1):T_GND
    2  T_GND             P1  @S9S_MB_2U_LIB.S9S_MB_2U(SCH_1):T_GND
    1  TDR_DIFF_85_IN1_DP     S1  @S9S_MB_2U_LIB.S9S_MB_2U(SCH_1):TDR_DIFF_85_IN1_DP
    4  TDR_DIFF_85_IN1_DN     S2  @S9S_MB_2U_LIB.S9S_MB_2U(SCH_1):TDR_DIFF_85_IN1_DN

TP_TDR_4P_FTS  I39  X3     [TP_TDR_4P_FTS_TH-TP_TDR_4P_DIPA]
    3  T_GND             P2  @S9S_MB_2U_LIB.S9S_MB_2U(SCH_1):T_GND
    2  T_GND             P1  @S9S_MB_2U_LIB.S9S_MB_2U(SCH_1):T_GND
    1  TDR_DIFF_85_IN2_DP     S1  @S9S_MB_2U_LIB.S9S_MB_2U(SCH_1):TDR_DIFF_85_IN2_DP
    4  TDR_DIFF_85_IN2_DN     S2  @S9S_MB_2U_LIB.S9S_MB_2U(SCH_1):TDR_DIFF_85_IN2_DN

TP_TDR_4P_FTS  I47  X4     [TP_TDR_4P_FTS_TH-TP_TDR_4P_DIPA]
    3  T_GND             P2  @S9S_MB_2U_LIB.S9S_MB_2U(SCH_1):T_GND
    2  T_GND             P1  @S9S_MB_2U_LIB.S9S_MB_2U(SCH_1):T_GND
    1  TDR_DIFF_85_IN3_DP     S1  @S9S_MB_2U_LIB.S9S_MB_2U(SCH_1):TDR_DIFF_85_IN3_DP
    4  TDR_DIFF_85_IN3_DN     S2  @S9S_MB_2U_LIB.S9S_MB_2U(SCH_1):TDR_DIFF_85_IN3_DN

TP_TDR_4P_FTS  I48  X5     [TP_TDR_4P_FTS_TH-TP_TDR_4P_DIPA]
    3  T_GND             P2  @S9S_MB_2U_LIB.S9S_MB_2U(SCH_1):T_GND
    2  T_GND             P1  @S9S_MB_2U_LIB.S9S_MB_2U(SCH_1):T_GND
    1  TDR_DIFF_85_IN4_DP     S1  @S9S_MB_2U_LIB.S9S_MB_2U(SCH_1):TDR_DIFF_85_IN4_DP
    4  TDR_DIFF_85_IN4_DN     S2  @S9S_MB_2U_LIB.S9S_MB_2U(SCH_1):TDR_DIFF_85_IN4_DN

TP_TDR_4P_FTS  I53  X6     [TP_TDR_4P_FTS_TH-TP_TDR_4P_DIPA]
    3  T_GND             P2  @S9S_MB_2U_LIB.S9S_MB_2U(SCH_1):T_GND
    2  T_GND             P1  @S9S_MB_2U_LIB.S9S_MB_2U(SCH_1):T_GND
    1  TDR_DIFF_85_BOT_DP     S1  @S9S_MB_2U_LIB.S9S_MB_2U(SCH_1):TDR_DIFF_85_BOT_DP
    4  TDR_DIFF_85_BOT_DN     S2  @S9S_MB_2U_LIB.S9S_MB_2U(SCH_1):TDR_DIFF_85_BOT_DN

TP_TDR_4P_FTS  I15  X7     [TP_TDR_4P_FTS_TH-TP_TDR_4P_DIPA]
    3  T_GND             P2  @S9S_MB_2U_LIB.S9S_MB_2U(SCH_1):T_GND
    2  T_GND             P1  @S9S_MB_2U_LIB.S9S_MB_2U(SCH_1):T_GND
    4  TDR_DIFF_85_TOP_DP     S2  @S9S_MB_2U_LIB.S9S_MB_2U(SCH_1):TDR_DIFF_85_TOP_DP
    1  TDR_DIFF_85_TOP_DN     S1  @S9S_MB_2U_LIB.S9S_MB_2U(SCH_1):TDR_DIFF_85_TOP_DN

TP_TDR_4P_FTS  I19  X8     [TP_TDR_4P_FTS_TH-TP_TDR_4P_DIPA]
    3  T_GND             P2  @S9S_MB_2U_LIB.S9S_MB_2U(SCH_1):T_GND
    2  T_GND             P1  @S9S_MB_2U_LIB.S9S_MB_2U(SCH_1):T_GND
    4  TDR_DIFF_85_IN1_DP     S2  @S9S_MB_2U_LIB.S9S_MB_2U(SCH_1):TDR_DIFF_85_IN1_DP
    1  TDR_DIFF_85_IN1_DN     S1  @S9S_MB_2U_LIB.S9S_MB_2U(SCH_1):TDR_DIFF_85_IN1_DN

TP_TDR_4P_FTS  I41  X9     [TP_TDR_4P_FTS_TH-TP_TDR_4P_DIPA]
    3  T_GND             P2  @S9S_MB_2U_LIB.S9S_MB_2U(SCH_1):T_GND
    2  T_GND             P1  @S9S_MB_2U_LIB.S9S_MB_2U(SCH_1):T_GND
    4  TDR_DIFF_85_IN2_DP     S2  @S9S_MB_2U_LIB.S9S_MB_2U(SCH_1):TDR_DIFF_85_IN2_DP
    1  TDR_DIFF_85_IN2_DN     S1  @S9S_MB_2U_LIB.S9S_MB_2U(SCH_1):TDR_DIFF_85_IN2_DN

TP_TDR_4P_FTS  I44  X10    [TP_TDR_4P_FTS_TH-TP_TDR_4P_DIPA]
    3  T_GND             P2  @S9S_MB_2U_LIB.S9S_MB_2U(SCH_1):T_GND
    2  T_GND             P1  @S9S_MB_2U_LIB.S9S_MB_2U(SCH_1):T_GND
    4  TDR_DIFF_85_IN3_DP     S2  @S9S_MB_2U_LIB.S9S_MB_2U(SCH_1):TDR_DIFF_85_IN3_DP
    1  TDR_DIFF_85_IN3_DN     S1  @S9S_MB_2U_LIB.S9S_MB_2U(SCH_1):TDR_DIFF_85_IN3_DN

TP_TDR_4P_FTS  I45  X11    [TP_TDR_4P_FTS_TH-TP_TDR_4P_DIPA]
    3  T_GND             P2  @S9S_MB_2U_LIB.S9S_MB_2U(SCH_1):T_GND
    2  T_GND             P1  @S9S_MB_2U_LIB.S9S_MB_2U(SCH_1):T_GND
    4  TDR_DIFF_85_IN4_DP     S2  @S9S_MB_2U_LIB.S9S_MB_2U(SCH_1):TDR_DIFF_85_IN4_DP
    1  TDR_DIFF_85_IN4_DN     S1  @S9S_MB_2U_LIB.S9S_MB_2U(SCH_1):TDR_DIFF_85_IN4_DN

TP_TDR_4P_FTS  I52  X12    [TP_TDR_4P_FTS_TH-TP_TDR_4P_DIPA]
    3  T_GND             P2  @S9S_MB_2U_LIB.S9S_MB_2U(SCH_1):T_GND
    2  T_GND             P1  @S9S_MB_2U_LIB.S9S_MB_2U(SCH_1):T_GND
    4  TDR_DIFF_85_BOT_DP     S2  @S9S_MB_2U_LIB.S9S_MB_2U(SCH_1):TDR_DIFF_85_BOT_DP
    1  TDR_DIFF_85_BOT_DN     S1  @S9S_MB_2U_LIB.S9S_MB_2U(SCH_1):TDR_DIFF_85_BOT_DN

TP_TDR_4P_FTS  I68  X13    [TP_TDR_4P_FTS_TH-TP_TDR_4P_DIPA]
    3  T_GND             P2  @S9S_MB_2U_LIB.S9S_MB_2U(SCH_1):T_GND
    2  T_GND             P1  @S9S_MB_2U_LIB.S9S_MB_2U(SCH_1):T_GND
    1  TDR_DIFF_100_TOP_DP     S1  @S9S_MB_2U_LIB.S9S_MB_2U(SCH_1):TDR_DIFF_100_TOP_DP
    4  TDR_DIFF_100_TOP_DN     S2  @S9S_MB_2U_LIB.S9S_MB_2U(SCH_1):TDR_DIFF_100_TOP_DN

TP_TDR_4P_FTS  I67  X14    [TP_TDR_4P_FTS_TH-TP_TDR_4P_DIPA]
    3  T_GND             P2  @S9S_MB_2U_LIB.S9S_MB_2U(SCH_1):T_GND
    2  T_GND             P1  @S9S_MB_2U_LIB.S9S_MB_2U(SCH_1):T_GND
    1  TDR_DIFF_100_IN1_DP     S1  @S9S_MB_2U_LIB.S9S_MB_2U(SCH_1):TDR_DIFF_100_IN1_DP
    4  TDR_DIFF_100_IN1_DN     S2  @S9S_MB_2U_LIB.S9S_MB_2U(SCH_1):TDR_DIFF_100_IN1_DN

TP_TDR_4P_FTS  I66  X15    [TP_TDR_4P_FTS_TH-TP_TDR_4P_DIPA]
    3  T_GND             P2  @S9S_MB_2U_LIB.S9S_MB_2U(SCH_1):T_GND
    2  T_GND             P1  @S9S_MB_2U_LIB.S9S_MB_2U(SCH_1):T_GND
    1  TDR_DIFF_100_IN2_DP     S1  @S9S_MB_2U_LIB.S9S_MB_2U(SCH_1):TDR_DIFF_100_IN2_DP
    4  TDR_DIFF_100_IN2_DN     S2  @S9S_MB_2U_LIB.S9S_MB_2U(SCH_1):TDR_DIFF_100_IN2_DN

TP_TDR_4P_FTS  I62  X16    [TP_TDR_4P_FTS_TH-TP_TDR_4P_DIPA]
    3  T_GND             P2  @S9S_MB_2U_LIB.S9S_MB_2U(SCH_1):T_GND
    2  T_GND             P1  @S9S_MB_2U_LIB.S9S_MB_2U(SCH_1):T_GND
    1  TDR_DIFF_100_IN3_DP     S1  @S9S_MB_2U_LIB.S9S_MB_2U(SCH_1):TDR_DIFF_100_IN3_DP
    4  TDR_DIFF_100_IN3_DN     S2  @S9S_MB_2U_LIB.S9S_MB_2U(SCH_1):TDR_DIFF_100_IN3_DN

TP_TDR_4P_FTS  I61  X17    [TP_TDR_4P_FTS_TH-TP_TDR_4P_DIPA]
    3  T_GND             P2  @S9S_MB_2U_LIB.S9S_MB_2U(SCH_1):T_GND
    2  T_GND             P1  @S9S_MB_2U_LIB.S9S_MB_2U(SCH_1):T_GND
    1  TDR_DIFF_100_IN4_DP     S1  @S9S_MB_2U_LIB.S9S_MB_2U(SCH_1):TDR_DIFF_100_IN4_DP
    4  TDR_DIFF_100_IN4_DN     S2  @S9S_MB_2U_LIB.S9S_MB_2U(SCH_1):TDR_DIFF_100_IN4_DN

TP_TDR_4P_FTS  I55  X18    [TP_TDR_4P_FTS_TH-TP_TDR_4P_DIPA]
    3  T_GND             P2  @S9S_MB_2U_LIB.S9S_MB_2U(SCH_1):T_GND
    2  T_GND             P1  @S9S_MB_2U_LIB.S9S_MB_2U(SCH_1):T_GND
    1  TDR_DIFF_100_BOT_DP     S1  @S9S_MB_2U_LIB.S9S_MB_2U(SCH_1):TDR_DIFF_100_BOT_DP
    4  TDR_DIFF_100_BOT_DN     S2  @S9S_MB_2U_LIB.S9S_MB_2U(SCH_1):TDR_DIFF_100_BOT_DN

TP_TDR_4P_FTS  I73  X19    [TP_TDR_4P_FTS_TH-TP_TDR_4P_DIPA]
    3  T_GND             P2  @S9S_MB_2U_LIB.S9S_MB_2U(SCH_1):T_GND
    2  T_GND             P1  @S9S_MB_2U_LIB.S9S_MB_2U(SCH_1):T_GND
    4  TDR_DIFF_100_TOP_DP     S2  @S9S_MB_2U_LIB.S9S_MB_2U(SCH_1):TDR_DIFF_100_TOP_DP
    1  TDR_DIFF_100_TOP_DN     S1  @S9S_MB_2U_LIB.S9S_MB_2U(SCH_1):TDR_DIFF_100_TOP_DN

TP_TDR_4P_FTS  I74  X20    [TP_TDR_4P_FTS_TH-TP_TDR_4P_DIPA]
    3  T_GND             P2  @S9S_MB_2U_LIB.S9S_MB_2U(SCH_1):T_GND
    2  T_GND             P1  @S9S_MB_2U_LIB.S9S_MB_2U(SCH_1):T_GND
    4  TDR_DIFF_100_IN1_DP     S2  @S9S_MB_2U_LIB.S9S_MB_2U(SCH_1):TDR_DIFF_100_IN1_DP
    1  TDR_DIFF_100_IN1_DN     S1  @S9S_MB_2U_LIB.S9S_MB_2U(SCH_1):TDR_DIFF_100_IN1_DN

TP_TDR_4P_FTS  I72  X21    [TP_TDR_4P_FTS_TH-TP_TDR_4P_DIPA]
    3  T_GND             P2  @S9S_MB_2U_LIB.S9S_MB_2U(SCH_1):T_GND
    2  T_GND             P1  @S9S_MB_2U_LIB.S9S_MB_2U(SCH_1):T_GND
    4  TDR_DIFF_100_IN2_DP     S2  @S9S_MB_2U_LIB.S9S_MB_2U(SCH_1):TDR_DIFF_100_IN2_DP
    1  TDR_DIFF_100_IN2_DN     S1  @S9S_MB_2U_LIB.S9S_MB_2U(SCH_1):TDR_DIFF_100_IN2_DN

TP_TDR_4P_FTS  I69  X22    [TP_TDR_4P_FTS_TH-TP_TDR_4P_DIPA]
    3  T_GND             P2  @S9S_MB_2U_LIB.S9S_MB_2U(SCH_1):T_GND
    2  T_GND             P1  @S9S_MB_2U_LIB.S9S_MB_2U(SCH_1):T_GND
    4  TDR_DIFF_100_IN3_DP     S2  @S9S_MB_2U_LIB.S9S_MB_2U(SCH_1):TDR_DIFF_100_IN3_DP
    1  TDR_DIFF_100_IN3_DN     S1  @S9S_MB_2U_LIB.S9S_MB_2U(SCH_1):TDR_DIFF_100_IN3_DN

TP_TDR_4P_FTS  I78  X23    [TP_TDR_4P_FTS_TH-TP_TDR_4P_DIPA]
    3  T_GND             P2  @S9S_MB_2U_LIB.S9S_MB_2U(SCH_1):T_GND
    2  T_GND             P1  @S9S_MB_2U_LIB.S9S_MB_2U(SCH_1):T_GND
    4  TDR_DIFF_100_IN4_DP     S2  @S9S_MB_2U_LIB.S9S_MB_2U(SCH_1):TDR_DIFF_100_IN4_DP
    1  TDR_DIFF_100_IN4_DN     S1  @S9S_MB_2U_LIB.S9S_MB_2U(SCH_1):TDR_DIFF_100_IN4_DN

TP_TDR_4P_FTS  I57  X24    [TP_TDR_4P_FTS_TH-TP_TDR_4P_DIPA]
    3  T_GND             P2  @S9S_MB_2U_LIB.S9S_MB_2U(SCH_1):T_GND
    2  T_GND             P1  @S9S_MB_2U_LIB.S9S_MB_2U(SCH_1):T_GND
    4  TDR_DIFF_100_BOT_DP     S2  @S9S_MB_2U_LIB.S9S_MB_2U(SCH_1):TDR_DIFF_100_BOT_DP
    1  TDR_DIFF_100_BOT_DN     S1  @S9S_MB_2U_LIB.S9S_MB_2U(SCH_1):TDR_DIFF_100_BOT_DN

Q_CRYSTAL  I11  Y1     [Q_CRYSTAL_SMLF-32.768KHZ,IC,BGA]
    1  XTAL_PCH_RTC2_R      1  @S9S_MB_2U_LIB.S9S_MB_2U(SCH_1):XTAL_PCH_RTC2_R
    2  XTAL_PCH_RTC1      2  @S9S_MB_2U_LIB.S9S_MB_2U(SCH_1):XTAL_PCH_RTC1

Q_XTAL_4P_13  I185  Y2     [Q_XTAL_4P_13_SMLF-25MHZ,IC,BG6A]
    3  XTAL_CLK_GEN1_25M_X2      3  @S9S_MB_2U_LIB.S9S_MB_2U(SCH_1):XTAL_CLK_GEN1_25M_X2
    1  XTAL_CLK_GEN1_25M_X1_R      1  @S9S_MB_2U_LIB.S9S_MB_2U(SCH_1):XTAL_CLK_GEN1_25M_X1_R
    4  GND                4  @S9S_MB_2U_LIB.S9S_MB_2U(SCH_1):GND
    2  GND                2  @S9S_MB_2U_LIB.S9S_MB_2U(SCH_1):GND

Q_XTAL_4P_13BI_24GND  I75  Y3     [Q_XTAL_4P_13BI_24GND-25MHZ,SMLA]
    3  XTAL_PCH_25M_OUT     X2  @S9S_MB_2U_LIB.S9S_MB_2U(SCH_1):XTAL_PCH_25M_OUT
    1  XTAL_PCH_25M_IN_R     X1  @S9S_MB_2U_LIB.S9S_MB_2U(SCH_1):XTAL_PCH_25M_IN_R
    4  GND               G2  @S9S_MB_2U_LIB.S9S_MB_2U(SCH_1):GND
    2  GND               G1  @S9S_MB_2U_LIB.S9S_MB_2U(SCH_1):GND
END OF PART CROSS REFERENCE

SIGNAL CROSS REFERENCE (forward interface)

CLK_100M_BMC_P3E_DN   @S9S_MB_2U_LIB.S9S_MB_2U(SCH_1):CLK_100M_BMC_P3E_DN
  J41    A13  GND_A13  SCONN168_623403212  I115
  U4     B11  CLKOUT_SRC_N_6  EMMITSBURG_REV0P9  I78

CLK_100M_BMC_P3E_DP   @S9S_MB_2U_LIB.S9S_MB_2U(SCH_1):CLK_100M_BMC_P3E_DP
  J41    A12  PRSNTB2#  SCONN168_623403212  I115
  U4     D11  CLKOUT_SRC_P_6  EMMITSBURG_REV0P9  I78

CLK_100M_CK440_PCH_EXTCLK_DN   @S9S_MB_2U_LIB.S9S_MB_2U(SCH_1):CLK_100M_CK440_PCH_EXTCLK_DN
  R554     2      B  Q_RES       I226
  U4     D21  REFCLK_INJ_S_N  EMMITSBURG_REV0P9  I78

CLK_100M_CK440_PCH_EXTCLK_DP   @S9S_MB_2U_LIB.S9S_MB_2U(SCH_1):CLK_100M_CK440_PCH_EXTCLK_DP
  R553     2      B  Q_RES       I225
  U4     B21  REFCLK_INJ_S_P  EMMITSBURG_REV0P9  I78

CLK_100M_CK440_PCH_EXTCLK_R_DN   @S9S_MB_2U_LIB.S9S_MB_2U(SCH_1):CLK_100M_CK440_PCH_EXTCLK_R_DN
  R554     1      A  Q_RES       I226
  U13    A47  MXCK2#  9SQ440NQQI8  I180

CLK_100M_CK440_PCH_EXTCLK_R_DP   @S9S_MB_2U_LIB.S9S_MB_2U(SCH_1):CLK_100M_CK440_PCH_EXTCLK_R_DP
  R553     1      A  Q_RES       I225
  U13    A48  MXCK2  9SQ440NQQI8  I180

CLK_100M_DB2000_CPU0_BCLK0_DN   @S9S_MB_2U_LIB.S9S_MB_2U(SCH_1):CLK_100M_DB2000_CPU0_BCLK0_DN
  U2     AT30  BCLK0_DN  SOCKET4677_AZIFS054P001C01  I57
  U38     K1  DIF0#  9QXL2001BNHGI8  I119

CLK_100M_DB2000_CPU0_BCLK0_DP   @S9S_MB_2U_LIB.S9S_MB_2U(SCH_1):CLK_100M_DB2000_CPU0_BCLK0_DP
  U2     AV30  BCLK0_DP  SOCKET4677_AZIFS054P001C01  I57
  U38     J1   DIF0  9QXL2001BNHGI8  I119

CLK_100M_DB2000_CPU0_BCLK1_DN   @S9S_MB_2U_LIB.S9S_MB_2U(SCH_1):CLK_100M_DB2000_CPU0_BCLK1_DN
  U2     CY28  BCLK1_DN  SOCKET4677_AZIFS054P001C01  I57
  U38     M1  DIF1#  9QXL2001BNHGI8  I119

CLK_100M_DB2000_CPU0_BCLK1_DP   @S9S_MB_2U_LIB.S9S_MB_2U(SCH_1):CLK_100M_DB2000_CPU0_BCLK1_DP
  U2     CW29  BCLK1_DP  SOCKET4677_AZIFS054P001C01  I57
  U38     L1   DIF1  9QXL2001BNHGI8  I119

CLK_100M_DB2000_CPU0_BCLK2_DN   @S9S_MB_2U_LIB.S9S_MB_2U(SCH_1):CLK_100M_DB2000_CPU0_BCLK2_DN
  U2     AU29  BCLK2_DN  SOCKET4677_AZIFS054P001C01  I57
  U38     M3  DIF2#  9QXL2001BNHGI8  I119

CLK_100M_DB2000_CPU0_BCLK2_DP   @S9S_MB_2U_LIB.S9S_MB_2U(SCH_1):CLK_100M_DB2000_CPU0_BCLK2_DP
  U2     AV28  BCLK2_DP  SOCKET4677_AZIFS054P001C01  I57
  U38     M2   DIF2  9QXL2001BNHGI8  I119

CLK_100M_DB2000_CPU0_BCLK3_DN   @S9S_MB_2U_LIB.S9S_MB_2U(SCH_1):CLK_100M_DB2000_CPU0_BCLK3_DN
  U2     CW27  BCLK3_DN  SOCKET4677_AZIFS054P001C01  I57
  U38     M5  DIF3#  9QXL2001BNHGI8  I119

CLK_100M_DB2000_CPU0_BCLK3_DP   @S9S_MB_2U_LIB.S9S_MB_2U(SCH_1):CLK_100M_DB2000_CPU0_BCLK3_DP
  U2     DA27  BCLK3_DP  SOCKET4677_AZIFS054P001C01  I57
  U38     M4   DIF3  9QXL2001BNHGI8  I119

CLK_100M_DB2000_CPU1_BCLK0_DN   @S9S_MB_2U_LIB.S9S_MB_2U(SCH_1):CLK_100M_DB2000_CPU1_BCLK0_DN
  U1     AT30  BCLK0_DN  SOCKET4677_AZIFS054P001C01  I51
  U38     M8  DIF4#  9QXL2001BNHGI8  I119

CLK_100M_DB2000_CPU1_BCLK0_DP   @S9S_MB_2U_LIB.S9S_MB_2U(SCH_1):CLK_100M_DB2000_CPU1_BCLK0_DP
  U1     AV30  BCLK0_DP  SOCKET4677_AZIFS054P001C01  I51
  U38     M7   DIF4  9QXL2001BNHGI8  I119

CLK_100M_DB2000_CPU1_BCLK1_DN   @S9S_MB_2U_LIB.S9S_MB_2U(SCH_1):CLK_100M_DB2000_CPU1_BCLK1_DN
  U1     CY28  BCLK1_DN  SOCKET4677_AZIFS054P001C01  I51
  U38    M10  DIF5#  9QXL2001BNHGI8  I119

CLK_100M_DB2000_CPU1_BCLK1_DP   @S9S_MB_2U_LIB.S9S_MB_2U(SCH_1):CLK_100M_DB2000_CPU1_BCLK1_DP
  U1     CW29  BCLK1_DP  SOCKET4677_AZIFS054P001C01  I51
  U38     M9   DIF5  9QXL2001BNHGI8  I119

CLK_100M_DB2000_CPU1_BCLK2_DN   @S9S_MB_2U_LIB.S9S_MB_2U(SCH_1):CLK_100M_DB2000_CPU1_BCLK2_DN
  U1     AU29  BCLK2_DN  SOCKET4677_AZIFS054P001C01  I51
  U38    M12  DIF6#  9QXL2001BNHGI8  I119

CLK_100M_DB2000_CPU1_BCLK2_DP   @S9S_MB_2U_LIB.S9S_MB_2U(SCH_1):CLK_100M_DB2000_CPU1_BCLK2_DP
  U1     AV28  BCLK2_DP  SOCKET4677_AZIFS054P001C01  I51
  U38    M11   DIF6  9QXL2001BNHGI8  I119

CLK_100M_DB2000_CPU1_BCLK3_DN   @S9S_MB_2U_LIB.S9S_MB_2U(SCH_1):CLK_100M_DB2000_CPU1_BCLK3_DN
  U1     CW27  BCLK3_DN  SOCKET4677_AZIFS054P001C01  I51
  U38    K12  DIF7#  9QXL2001BNHGI8  I119

CLK_100M_DB2000_CPU1_BCLK3_DP   @S9S_MB_2U_LIB.S9S_MB_2U(SCH_1):CLK_100M_DB2000_CPU1_BCLK3_DP
  U1     DA27  BCLK3_DP  SOCKET4677_AZIFS054P001C01  I51
  U38    L12   DIF7  9QXL2001BNHGI8  I119

CLK_100M_DB2000_DN   @S9S_MB_2U_LIB.S9S_MB_2U(SCH_1):CLK_100M_DB2000_DN
  U13    A33  100M0#  9SQ440NQQI8  I180
  U38     H1  DIF_IN#  9QXL2001BNHGI8  I119

CLK_100M_DB2000_DP   @S9S_MB_2U_LIB.S9S_MB_2U(SCH_1):CLK_100M_DB2000_DP
  U13    A34  100M0  9SQ440NQQI8  I180
  U38     G1  DIF_IN  9QXL2001BNHGI8  I119

CLK_100M_E1S_0_DN   @S9S_MB_2U_LIB.S9S_MB_2U(SCH_1):CLK_100M_E1S_0_DN
  J90    B14  REFCLKN0  CONN56_ME2005602311011  I105
  R529     2      B  Q_RES       I242

CLK_100M_E1S_0_DP   @S9S_MB_2U_LIB.S9S_MB_2U(SCH_1):CLK_100M_E1S_0_DP
  J90    B15  REFCLKP0  CONN56_ME2005602311011  I105
  R528     2      B  Q_RES       I239

CLK_100M_E1S_0_R_DN   @S9S_MB_2U_LIB.S9S_MB_2U(SCH_1):CLK_100M_E1S_0_R_DN
  R529     1      A  Q_RES       I242
  U13    A51  MXCK0#  9SQ440NQQI8  I180

CLK_100M_E1S_0_R_DP   @S9S_MB_2U_LIB.S9S_MB_2U(SCH_1):CLK_100M_E1S_0_R_DP
  R528     1      A  Q_RES       I239
  U13    A52  MXCK0  9SQ440NQQI8  I180

CLK_100M_E1S_1_DN   @S9S_MB_2U_LIB.S9S_MB_2U(SCH_1):CLK_100M_E1S_1_DN
  J91    B14  REFCLKN0  CONN56_ME2005602311011  I123
  R531     2      B  Q_RES       I240

CLK_100M_E1S_1_DP   @S9S_MB_2U_LIB.S9S_MB_2U(SCH_1):CLK_100M_E1S_1_DP
  J91    B15  REFCLKP0  CONN56_ME2005602311011  I123
  R530     2      B  Q_RES       I241

CLK_100M_E1S_1_R_DN   @S9S_MB_2U_LIB.S9S_MB_2U(SCH_1):CLK_100M_E1S_1_R_DN
  R531     1      A  Q_RES       I240
  U13    A49  MXCK1#  9SQ440NQQI8  I180

CLK_100M_E1S_1_R_DP   @S9S_MB_2U_LIB.S9S_MB_2U(SCH_1):CLK_100M_E1S_1_R_DP
  R530     1      A  Q_RES       I241
  U13    A50  MXCK1  9SQ440NQQI8  I180

CLK_100M_E1S_2_DN   @S9S_MB_2U_LIB.S9S_MB_2U(SCH_1):CLK_100M_E1S_2_DN
  J92    B14  REFCLKN0  CONN56_ME2005602311011  I105
  R533     2      B  Q_RES       I244

CLK_100M_E1S_2_DP   @S9S_MB_2U_LIB.S9S_MB_2U(SCH_1):CLK_100M_E1S_2_DP
  J92    B15  REFCLKP0  CONN56_ME2005602311011  I105
  R532     2      B  Q_RES       I243

CLK_100M_E1S_2_R_DN   @S9S_MB_2U_LIB.S9S_MB_2U(SCH_1):CLK_100M_E1S_2_R_DN
  R533     1      A  Q_RES       I244
  U13    A43  MXCK4#  9SQ440NQQI8  I180

CLK_100M_E1S_2_R_DP   @S9S_MB_2U_LIB.S9S_MB_2U(SCH_1):CLK_100M_E1S_2_R_DP
  R532     1      A  Q_RES       I243
  U13    A44  MXCK4  9SQ440NQQI8  I180

CLK_100M_E1S_3_DN   @S9S_MB_2U_LIB.S9S_MB_2U(SCH_1):CLK_100M_E1S_3_DN
  J93    B14  REFCLKN0  CONN56_ME2005602311011  I123
  R535     2      B  Q_RES       I247

CLK_100M_E1S_3_DP   @S9S_MB_2U_LIB.S9S_MB_2U(SCH_1):CLK_100M_E1S_3_DP
  J93    B15  REFCLKP0  CONN56_ME2005602311011  I123
  R534     2      B  Q_RES       I246

CLK_100M_E1S_3_R_DN   @S9S_MB_2U_LIB.S9S_MB_2U(SCH_1):CLK_100M_E1S_3_R_DN
  R535     1      A  Q_RES       I247
  U13    A41  MXCK5#  9SQ440NQQI8  I180

CLK_100M_E1S_3_R_DP   @S9S_MB_2U_LIB.S9S_MB_2U(SCH_1):CLK_100M_E1S_3_R_DP
  R534     1      A  Q_RES       I246
  U13    A42  MXCK5  9SQ440NQQI8  I180

CLK_100M_EDSFF1A_1_DN   @S9S_MB_2U_LIB.S9S_MB_2U(SCH_1):CLK_100M_EDSFF1A_1_DN
  J62    A14  REFCLKN1  SCONN84_123318136  I33
  R2144    2      B  Q_RES       I228

CLK_100M_EDSFF1A_1_DP   @S9S_MB_2U_LIB.S9S_MB_2U(SCH_1):CLK_100M_EDSFF1A_1_DP
  J62    A15  REFCLKP1  SCONN84_123318136  I33
  R2143    2      B  Q_RES       I227

CLK_100M_EDSFF1A_1_R_DN   @S9S_MB_2U_LIB.S9S_MB_2U(SCH_1):CLK_100M_EDSFF1A_1_R_DN
  R2144    1      A  Q_RES       I228
  U38     A8  DIF13#  9QXL2001BNHGI8  I119

CLK_100M_EDSFF1A_1_R_DP   @S9S_MB_2U_LIB.S9S_MB_2U(SCH_1):CLK_100M_EDSFF1A_1_R_DP
  R2143    1      A  Q_RES       I227
  U38     A9  DIF13  9QXL2001BNHGI8  I119

CLK_100M_EDSFF1A_DN   @S9S_MB_2U_LIB.S9S_MB_2U(SCH_1):CLK_100M_EDSFF1A_DN
  J62    B14  REFCLKN0  SCONN84_123318136  I33
  R1278    2      B  Q_RES       I186

CLK_100M_EDSFF1A_DP   @S9S_MB_2U_LIB.S9S_MB_2U(SCH_1):CLK_100M_EDSFF1A_DP
  J62    B15  REFCLKP0  SCONN84_123318136  I33
  R1277    2      B  Q_RES       I185

CLK_100M_EDSFF1A_R_DN   @S9S_MB_2U_LIB.S9S_MB_2U(SCH_1):CLK_100M_EDSFF1A_R_DN
  R1278    1      A  Q_RES       I186
  U38    A10  DIF12#  9QXL2001BNHGI8  I119

CLK_100M_EDSFF1A_R_DP   @S9S_MB_2U_LIB.S9S_MB_2U(SCH_1):CLK_100M_EDSFF1A_R_DP
  R1277    1      A  Q_RES       I185
  U38    A11  DIF12  9QXL2001BNHGI8  I119

CLK_100M_EDSFF1B_1_DN   @S9S_MB_2U_LIB.S9S_MB_2U(SCH_1):CLK_100M_EDSFF1B_1_DN
  J87    A14  REFCLKN1  SCONN84_123318136  I43
  R2146    2      B  Q_RES       I232

CLK_100M_EDSFF1B_1_DP   @S9S_MB_2U_LIB.S9S_MB_2U(SCH_1):CLK_100M_EDSFF1B_1_DP
  J87    A15  REFCLKP1  SCONN84_123318136  I43
  R2145    2      B  Q_RES       I231

CLK_100M_EDSFF1B_1_R_DN   @S9S_MB_2U_LIB.S9S_MB_2U(SCH_1):CLK_100M_EDSFF1B_1_R_DN
  R2146    1      A  Q_RES       I232
  U38     A4  DIF15#  9QXL2001BNHGI8  I119

CLK_100M_EDSFF1B_1_R_DP   @S9S_MB_2U_LIB.S9S_MB_2U(SCH_1):CLK_100M_EDSFF1B_1_R_DP
  R2145    1      A  Q_RES       I231
  U38     A5  DIF15  9QXL2001BNHGI8  I119

CLK_100M_EDSFF1B_DN   @S9S_MB_2U_LIB.S9S_MB_2U(SCH_1):CLK_100M_EDSFF1B_DN
  J87    B14  REFCLKN0  SCONN84_123318136  I43
  R1280    2      B  Q_RES       I190

CLK_100M_EDSFF1B_DP   @S9S_MB_2U_LIB.S9S_MB_2U(SCH_1):CLK_100M_EDSFF1B_DP
  J87    B15  REFCLKP0  SCONN84_123318136  I43
  R1279    2      B  Q_RES       I189

CLK_100M_EDSFF1B_R_DN   @S9S_MB_2U_LIB.S9S_MB_2U(SCH_1):CLK_100M_EDSFF1B_R_DN
  R1280    1      A  Q_RES       I190
  U38     A6  DIF14#  9QXL2001BNHGI8  I119

CLK_100M_EDSFF1B_R_DP   @S9S_MB_2U_LIB.S9S_MB_2U(SCH_1):CLK_100M_EDSFF1B_R_DP
  R1279    1      A  Q_RES       I189
  U38     A7  DIF14  9QXL2001BNHGI8  I119

CLK_100M_EDSFF2A_DN   @S9S_MB_2U_LIB.S9S_MB_2U(SCH_1):CLK_100M_EDSFF2A_DN
  J33    B14  REFCLKN0  SCONN84_123318136  I53
  R1362    2      B  Q_RES       I187

CLK_100M_EDSFF2A_DP   @S9S_MB_2U_LIB.S9S_MB_2U(SCH_1):CLK_100M_EDSFF2A_DP
  J33    B15  REFCLKP0  SCONN84_123318136  I53
  R1361    2      B  Q_RES       I188

CLK_100M_EDSFF2A_R_DN   @S9S_MB_2U_LIB.S9S_MB_2U(SCH_1):CLK_100M_EDSFF2A_R_DN
  R1362    1      A  Q_RES       I187
  U38     A2  DIF16#  9QXL2001BNHGI8  I119

CLK_100M_EDSFF2A_R_DP   @S9S_MB_2U_LIB.S9S_MB_2U(SCH_1):CLK_100M_EDSFF2A_R_DP
  R1361    1      A  Q_RES       I188
  U38     A3  DIF16  9QXL2001BNHGI8  I119

CLK_100M_EDSFF2B_DN   @S9S_MB_2U_LIB.S9S_MB_2U(SCH_1):CLK_100M_EDSFF2B_DN
  J34    B14  REFCLKN0  SCONN84_123318136  I43
  R1364    2      B  Q_RES       I205

CLK_100M_EDSFF2B_DP   @S9S_MB_2U_LIB.S9S_MB_2U(SCH_1):CLK_100M_EDSFF2B_DP
  J34    B15  REFCLKP0  SCONN84_123318136  I43
  R1363    2      B  Q_RES       I206

CLK_100M_EDSFF2B_R_DN   @S9S_MB_2U_LIB.S9S_MB_2U(SCH_1):CLK_100M_EDSFF2B_R_DN
  R1364    1      A  Q_RES       I205
  U38     B1  DIF17#  9QXL2001BNHGI8  I119

CLK_100M_EDSFF2B_R_DP   @S9S_MB_2U_LIB.S9S_MB_2U(SCH_1):CLK_100M_EDSFF2B_R_DP
  R1363    1      A  Q_RES       I206
  U38     A1  DIF17  9QXL2001BNHGI8  I119

CLK_100M_EDSFF3_DN   @S9S_MB_2U_LIB.S9S_MB_2U(SCH_1):CLK_100M_EDSFF3_DN
  J35    B17  SIGNAL_B17  SCONN140_G64V3431BHR  I64
  R1282    2      B  Q_RES       I262

CLK_100M_EDSFF3_DP   @S9S_MB_2U_LIB.S9S_MB_2U(SCH_1):CLK_100M_EDSFF3_DP
  J35    B18  SIGNAL_B18  SCONN140_G64V3431BHR  I64
  R1281    2      B  Q_RES       I261

CLK_100M_EDSFF3_R_DN   @S9S_MB_2U_LIB.S9S_MB_2U(SCH_1):CLK_100M_EDSFF3_R_DN
  R1282    1      A  Q_RES       I262
  U13    A37  MXCK7#  9SQ440NQQI8  I180

CLK_100M_EDSFF3_R_DP   @S9S_MB_2U_LIB.S9S_MB_2U(SCH_1):CLK_100M_EDSFF3_R_DP
  R1281    1      A  Q_RES       I261
  U13    A38  MXCK7  9SQ440NQQI8  I180

CLK_100M_EDSFF4A_DN   @S9S_MB_2U_LIB.S9S_MB_2U(SCH_1):CLK_100M_EDSFF4A_DN
  J88    B14  REFCLKN0  SCONN84_123318136  I16
  R1284    2      B  Q_RES       I210

CLK_100M_EDSFF4A_DP   @S9S_MB_2U_LIB.S9S_MB_2U(SCH_1):CLK_100M_EDSFF4A_DP
  J88    B15  REFCLKP0  SCONN84_123318136  I16
  R1283    2      B  Q_RES       I208

CLK_100M_EDSFF4A_R_DN   @S9S_MB_2U_LIB.S9S_MB_2U(SCH_1):CLK_100M_EDSFF4A_R_DN
  R1284    1      A  Q_RES       I210
  U38     D1  DIF18#  9QXL2001BNHGI8  I119

CLK_100M_EDSFF4A_R_DP   @S9S_MB_2U_LIB.S9S_MB_2U(SCH_1):CLK_100M_EDSFF4A_R_DP
  R1283    1      A  Q_RES       I208
  U38     C1  DIF18  9QXL2001BNHGI8  I119

CLK_100M_EDSFF4B_DN   @S9S_MB_2U_LIB.S9S_MB_2U(SCH_1):CLK_100M_EDSFF4B_DN
  J61    B14  REFCLKN0  SCONN84_123318136  I49
  R2049    2      B  Q_RES       I218

CLK_100M_EDSFF4B_DP   @S9S_MB_2U_LIB.S9S_MB_2U(SCH_1):CLK_100M_EDSFF4B_DP
  J61    B15  REFCLKP0  SCONN84_123318136  I49
  R2048    2      B  Q_RES       I217

CLK_100M_EDSFF4B_R_DN   @S9S_MB_2U_LIB.S9S_MB_2U(SCH_1):CLK_100M_EDSFF4B_R_DN
  R2049    1      A  Q_RES       I218
  U38     F1  DIF19#  9QXL2001BNHGI8  I119

CLK_100M_EDSFF4B_R_DP   @S9S_MB_2U_LIB.S9S_MB_2U(SCH_1):CLK_100M_EDSFF4B_R_DP
  R2048    1      A  Q_RES       I217
  U38     E1  DIF19  9QXL2001BNHGI8  I119

CLK_100M_OCP_SFF_0_DN   @S9S_MB_2U_LIB.S9S_MB_2U(SCH_1):CLK_100M_OCP_SFF_0_DN
  J37    B14  REFCLKN0  SCONN168_623403212  I86
  R564     2      B  Q_RES       I170

CLK_100M_OCP_SFF_0_DP   @S9S_MB_2U_LIB.S9S_MB_2U(SCH_1):CLK_100M_OCP_SFF_0_DP
  J37    B15  REFCLKP0  SCONN168_623403212  I86
  R563     2      B  Q_RES       I169

CLK_100M_OCP_SFF_0_R_DN   @S9S_MB_2U_LIB.S9S_MB_2U(SCH_1):CLK_100M_OCP_SFF_0_R_DN
  R564     1      A  Q_RES       I170
  U38    H12  DIF8#  9QXL2001BNHGI8  I119

CLK_100M_OCP_SFF_0_R_DP   @S9S_MB_2U_LIB.S9S_MB_2U(SCH_1):CLK_100M_OCP_SFF_0_R_DP
  R563     1      A  Q_RES       I169
  U38    J12   DIF8  9QXL2001BNHGI8  I119

CLK_100M_OCP_SFF_1_DN   @S9S_MB_2U_LIB.S9S_MB_2U(SCH_1):CLK_100M_OCP_SFF_1_DN
  J37    A14  REFCLKN1  SCONN168_623403212  I86
  R566     2      B  Q_RES       I168

CLK_100M_OCP_SFF_1_DP   @S9S_MB_2U_LIB.S9S_MB_2U(SCH_1):CLK_100M_OCP_SFF_1_DP
  J37    A15  REFCLKP1  SCONN168_623403212  I86
  R565     2      B  Q_RES       I167

CLK_100M_OCP_SFF_1_R_DN   @S9S_MB_2U_LIB.S9S_MB_2U(SCH_1):CLK_100M_OCP_SFF_1_R_DN
  R566     1      A  Q_RES       I168
  U38    F12  DIF9#  9QXL2001BNHGI8  I119

CLK_100M_OCP_SFF_1_R_DP   @S9S_MB_2U_LIB.S9S_MB_2U(SCH_1):CLK_100M_OCP_SFF_1_R_DP
  R565     1      A  Q_RES       I167
  U38    G12   DIF9  9QXL2001BNHGI8  I119

CLK_100M_OCP_SFF_2_DN   @S9S_MB_2U_LIB.S9S_MB_2U(SCH_1):CLK_100M_OCP_SFF_2_DN
  J37    OCP_B11  REFCLKN2  SCONN168_623403212  I86
  R1274    2      B  Q_RES       I165

CLK_100M_OCP_SFF_2_DP   @S9S_MB_2U_LIB.S9S_MB_2U(SCH_1):CLK_100M_OCP_SFF_2_DP
  J37    OCP_B12  REFCLKP2  SCONN168_623403212  I86
  R1273    2      B  Q_RES       I166

CLK_100M_OCP_SFF_2_R_DN   @S9S_MB_2U_LIB.S9S_MB_2U(SCH_1):CLK_100M_OCP_SFF_2_R_DN
  R1274    1      A  Q_RES       I165
  U38    C12  DIF10#  9QXL2001BNHGI8  I119

CLK_100M_OCP_SFF_2_R_DP   @S9S_MB_2U_LIB.S9S_MB_2U(SCH_1):CLK_100M_OCP_SFF_2_R_DP
  R1273    1      A  Q_RES       I166
  U38    D12  DIF10  9QXL2001BNHGI8  I119

CLK_100M_OCP_SFF_3_DN   @S9S_MB_2U_LIB.S9S_MB_2U(SCH_1):CLK_100M_OCP_SFF_3_DN
  J37    OCP_A11  REFCLKN3  SCONN168_623403212  I86
  R1276    2      B  Q_RES       I163

CLK_100M_OCP_SFF_3_DP   @S9S_MB_2U_LIB.S9S_MB_2U(SCH_1):CLK_100M_OCP_SFF_3_DP
  J37    OCP_A12  REFCLKP3  SCONN168_623403212  I86
  R1275    2      B  Q_RES       I164

CLK_100M_OCP_SFF_3_R_DN   @S9S_MB_2U_LIB.S9S_MB_2U(SCH_1):CLK_100M_OCP_SFF_3_R_DN
  R1276    1      A  Q_RES       I163
  U38    A12  DIF11#  9QXL2001BNHGI8  I119

CLK_100M_OCP_SFF_3_R_DP   @S9S_MB_2U_LIB.S9S_MB_2U(SCH_1):CLK_100M_OCP_SFF_3_R_DP
  R1275    1      A  Q_RES       I164
  U38    B12  DIF11  9QXL2001BNHGI8  I119

CLK_100M_PE_0_DN   @S9S_MB_2U_LIB.S9S_MB_2U(SCH_1):CLK_100M_PE_0_DN
  J55    A14  SIGNAL_A14  SCONN140_G64V3431BHR  I150
  R2182    2      B  Q_RES       I278

CLK_100M_PE_0_DP   @S9S_MB_2U_LIB.S9S_MB_2U(SCH_1):CLK_100M_PE_0_DP
  J55    A15  SIGNAL_A15  SCONN140_G64V3431BHR  I150
  R2181    2      B  Q_RES       I277

CLK_100M_PE_0_R_DN   @S9S_MB_2U_LIB.S9S_MB_2U(SCH_1):CLK_100M_PE_0_R_DN
  R2182    1      A  Q_RES       I278
  U13    A31  100M1#  9SQ440NQQI8  I180

CLK_100M_PE_0_R_DP   @S9S_MB_2U_LIB.S9S_MB_2U(SCH_1):CLK_100M_PE_0_R_DP
  R2181    1      A  Q_RES       I277
  U13    A32  100M1  9SQ440NQQI8  I180

CLK_100M_PE_1_DN   @S9S_MB_2U_LIB.S9S_MB_2U(SCH_1):CLK_100M_PE_1_DN
  J55    B14  SIGNAL_B14  SCONN140_G64V3431BHR  I150
  R2184    2      B  Q_RES       I280

CLK_100M_PE_1_DP   @S9S_MB_2U_LIB.S9S_MB_2U(SCH_1):CLK_100M_PE_1_DP
  J55    B15  SIGNAL_B15  SCONN140_G64V3431BHR  I150
  R2183    2      B  Q_RES       I279

CLK_100M_PE_1_R_DN   @S9S_MB_2U_LIB.S9S_MB_2U(SCH_1):CLK_100M_PE_1_R_DN
  R2184    1      A  Q_RES       I280
  U13    A27  100M2#  9SQ440NQQI8  I180

CLK_100M_PE_1_R_DP   @S9S_MB_2U_LIB.S9S_MB_2U(SCH_1):CLK_100M_PE_1_R_DP
  R2183    1      A  Q_RES       I279
  U13    A28  100M2  9SQ440NQQI8  I180

CLK_100M_PE_2_DN   @S9S_MB_2U_LIB.S9S_MB_2U(SCH_1):CLK_100M_PE_2_DN
  J89    A33    A33  SCONN280_ME1028040102011  I239
  R521     2      B  Q_RES       I123

CLK_100M_PE_2_DP   @S9S_MB_2U_LIB.S9S_MB_2U(SCH_1):CLK_100M_PE_2_DP
  J89    A34    A34  SCONN280_ME1028040102011  I239
  R520     2      B  Q_RES       I28

CLK_100M_PE_2_R_DN   @S9S_MB_2U_LIB.S9S_MB_2U(SCH_1):CLK_100M_PE_2_R_DN
  R521     1      A  Q_RES       I123
  U13    A24  100M3#  9SQ440NQQI8  I180

CLK_100M_PE_2_R_DP   @S9S_MB_2U_LIB.S9S_MB_2U(SCH_1):CLK_100M_PE_2_R_DP
  R520     1      A  Q_RES       I28
  U13    A25  100M3  9SQ440NQQI8  I180

CLK_100M_PE_3_DN   @S9S_MB_2U_LIB.S9S_MB_2U(SCH_1):CLK_100M_PE_3_DN
  J89    B33    B33  SCONN280_ME1028040102011  I239
  R523     2      B  Q_RES       I128

CLK_100M_PE_3_DP   @S9S_MB_2U_LIB.S9S_MB_2U(SCH_1):CLK_100M_PE_3_DP
  J89    B34    B34  SCONN280_ME1028040102011  I239
  R522     2      B  Q_RES       I129

CLK_100M_PE_3_R_DN   @S9S_MB_2U_LIB.S9S_MB_2U(SCH_1):CLK_100M_PE_3_R_DN
  R523     1      A  Q_RES       I128
  U13    A22  100M4#  9SQ440NQQI8  I180

CLK_100M_PE_3_R_DP   @S9S_MB_2U_LIB.S9S_MB_2U(SCH_1):CLK_100M_PE_3_R_DP
  R522     1      A  Q_RES       I129
  U13    A23  100M4  9SQ440NQQI8  I180

CLK_100M_PE_4_DN   @S9S_MB_2U_LIB.S9S_MB_2U(SCH_1):CLK_100M_PE_4_DN
  J57    A14  SIGNAL_A14  SCONN140_G64V3431BHR  I242
  R525     2      B  Q_RES       I135

CLK_100M_PE_4_DP   @S9S_MB_2U_LIB.S9S_MB_2U(SCH_1):CLK_100M_PE_4_DP
  J57    A15  SIGNAL_A15  SCONN140_G64V3431BHR  I242
  R524     2      B  Q_RES       I136

CLK_100M_PE_4_R_DN   @S9S_MB_2U_LIB.S9S_MB_2U(SCH_1):CLK_100M_PE_4_R_DN
  R525     1      A  Q_RES       I135
  U13    A20  100M5#  9SQ440NQQI8  I180

CLK_100M_PE_4_R_DP   @S9S_MB_2U_LIB.S9S_MB_2U(SCH_1):CLK_100M_PE_4_R_DP
  R524     1      A  Q_RES       I136
  U13    A21  100M5  9SQ440NQQI8  I180

CLK_100M_PE_5_DN   @S9S_MB_2U_LIB.S9S_MB_2U(SCH_1):CLK_100M_PE_5_DN
  J57    B14  SIGNAL_B14  SCONN140_G64V3431BHR  I242
  R527     2      B  Q_RES       I138

CLK_100M_PE_5_DP   @S9S_MB_2U_LIB.S9S_MB_2U(SCH_1):CLK_100M_PE_5_DP
  J57    B15  SIGNAL_B15  SCONN140_G64V3431BHR  I242
  R526     2      B  Q_RES       I137

CLK_100M_PE_5_R_DN   @S9S_MB_2U_LIB.S9S_MB_2U(SCH_1):CLK_100M_PE_5_R_DN
  R527     1      A  Q_RES       I138
  U13    A18  100M6#  9SQ440NQQI8  I180

CLK_100M_PE_5_R_DP   @S9S_MB_2U_LIB.S9S_MB_2U(SCH_1):CLK_100M_PE_5_R_DP
  R526     1      A  Q_RES       I137
  U13    A19  100M6  9SQ440NQQI8  I180

CLK_100M_PE_M2_0_DN   @S9S_MB_2U_LIB.S9S_MB_2U(SCH_1):CLK_100M_PE_M2_0_DN
  J59     53  REFCLKN  SCONN75K_APCI0155P004A  I178
  U4     H21  CLKOUT_SRC_N_2  EMMITSBURG_REV0P9  I78

CLK_100M_PE_M2_0_DP   @S9S_MB_2U_LIB.S9S_MB_2U(SCH_1):CLK_100M_PE_M2_0_DP
  J59     55  REFCLKP  SCONN75K_APCI0155P004A  I178
  U4     K21  CLKOUT_SRC_P_2  EMMITSBURG_REV0P9  I78

CLK_24M_66M_LPC0_ESPI   @S9S_MB_2U_LIB.S9S_MB_2U(SCH_1):CLK_24M_66M_LPC0_ESPI
  R1872    1      A  Q_RES       I65
  U4     BD13  GPPC_A_9_ESPI_CLK  EMMITSBURG_REV0P9  I93

CLK_25M_CK440_CPU0_DN   @S9S_MB_2U_LIB.S9S_MB_2U(SCH_1):CLK_25M_CK440_CPU0_DN
  R1014    1      A  Q_RES       I13
  U13     A4  25M0#  9SQ440NQQI8  I180

CLK_25M_CK440_CPU0_DP   @S9S_MB_2U_LIB.S9S_MB_2U(SCH_1):CLK_25M_CK440_CPU0_DP
  R1012    1      A  Q_RES       I10
  U13     A5   25M0  9SQ440NQQI8  I180

CLK_25M_CK440_CPU0_R_DN   @S9S_MB_2U_LIB.S9S_MB_2U(SCH_1):CLK_25M_CK440_CPU0_R_DN
  R1014    2      B  Q_RES       I13
  R1021    1      A  Q_RES        I6

CLK_25M_CK440_CPU0_R_DP   @S9S_MB_2U_LIB.S9S_MB_2U(SCH_1):CLK_25M_CK440_CPU0_R_DP
  R1012    2      B  Q_RES       I10
  R1020    1      A  Q_RES        I5

CLK_25M_CK440_CPU1_DN   @S9S_MB_2U_LIB.S9S_MB_2U(SCH_1):CLK_25M_CK440_CPU1_DN
  R1018    1      A  Q_RES       I20
  U13     A2  25M1#  9SQ440NQQI8  I180

CLK_25M_CK440_CPU1_DP   @S9S_MB_2U_LIB.S9S_MB_2U(SCH_1):CLK_25M_CK440_CPU1_DP
  R1016    1      A  Q_RES       I18
  U13     A3   25M1  9SQ440NQQI8  I180

CLK_25M_CK440_CPU1_R_DN   @S9S_MB_2U_LIB.S9S_MB_2U(SCH_1):CLK_25M_CK440_CPU1_R_DN
  R1018    2      B  Q_RES       I20
  R1023    1      A  Q_RES        I8

CLK_25M_CK440_CPU1_R_DP   @S9S_MB_2U_LIB.S9S_MB_2U(SCH_1):CLK_25M_CK440_CPU1_R_DP
  R1016    2      B  Q_RES       I18
  R1022    1      A  Q_RES        I7

CLK_25M_CK440_ISCLK_REF_DN   @S9S_MB_2U_LIB.S9S_MB_2U(SCH_1):CLK_25M_CK440_ISCLK_REF_DN
  R1011    1      A  Q_RES       I29
  U13    A55  25M2#  9SQ440NQQI8  I180

CLK_25M_CK440_ISCLK_REF_DP   @S9S_MB_2U_LIB.S9S_MB_2U(SCH_1):CLK_25M_CK440_ISCLK_REF_DP
  R1010    1      A  Q_RES       I22
  U13    A56   25M2  9SQ440NQQI8  I180

CLK_25M_NSSC_CPU0_DN   @S9S_MB_2U_LIB.S9S_MB_2U(SCH_1):CLK_25M_NSSC_CPU0_DN
  R1015    2      B  Q_RES       I12
  R1021    2      B  Q_RES        I6
  U2     CW31  XTAL_CLK_DN  SOCKET4677_AZIFS054P001C01  I57

CLK_25M_NSSC_CPU0_DP   @S9S_MB_2U_LIB.S9S_MB_2U(SCH_1):CLK_25M_NSSC_CPU0_DP
  R1013    2      B  Q_RES       I11
  R1020    2      B  Q_RES        I5
  U2     CY32  XTAL_CLK_DP  SOCKET4677_AZIFS054P001C01  I57

CLK_25M_NSSC_CPU1_DN   @S9S_MB_2U_LIB.S9S_MB_2U(SCH_1):CLK_25M_NSSC_CPU1_DN
  R1019    2      B  Q_RES       I21
  R1023    2      B  Q_RES        I8
  U1     CW31  XTAL_CLK_DN  SOCKET4677_AZIFS054P001C01  I51

CLK_25M_NSSC_CPU1_DP   @S9S_MB_2U_LIB.S9S_MB_2U(SCH_1):CLK_25M_NSSC_CPU1_DP
  R1017    2      B  Q_RES       I19
  R1022    2      B  Q_RES        I7
  U1     CY32  XTAL_CLK_DP  SOCKET4677_AZIFS054P001C01  I51

CLK_25M_OSC_FPGA_R   @S9S_MB_2U_LIB.S9S_MB_2U(SCH_1):CLK_25M_OSC_FPGA_R
  OSC2     3    OUT  Q_OSC4P     I132
  R1100    1      A  Q_RES       I139

CLK_25M_OSC_MAIN_FPGA   @S9S_MB_2U_LIB.S9S_MB_2U(SCH_1):CLK_25M_OSC_MAIN_FPGA
  R1100    2      B  Q_RES       I139
  U122    L3  DIFFIO_RX_L18N||CLK0N  10M04SAU324I7G  I139

CLK_25M_PCH_CPU0_DN   @S9S_MB_2U_LIB.S9S_MB_2U(SCH_1):CLK_25M_PCH_CPU0_DN
  R1015    1      A  Q_RES       I12
  U4     D27  PMSYNC_CLK_N_0  EMMITSBURG_REV0P9  I78

CLK_25M_PCH_CPU0_DP   @S9S_MB_2U_LIB.S9S_MB_2U(SCH_1):CLK_25M_PCH_CPU0_DP
  R1013    1      A  Q_RES       I11
  U4     B27  PMSYNC_CLK_P_0  EMMITSBURG_REV0P9  I78

CLK_25M_PCH_CPU1_DN   @S9S_MB_2U_LIB.S9S_MB_2U(SCH_1):CLK_25M_PCH_CPU1_DN
  R1019    1      A  Q_RES       I21
  U4     C28  PMSYNC_CLK_N_1  EMMITSBURG_REV0P9  I78

CLK_25M_PCH_CPU1_DP   @S9S_MB_2U_LIB.S9S_MB_2U(SCH_1):CLK_25M_PCH_CPU1_DP
  R1017    1      A  Q_RES       I19
  U4     A28  PMSYNC_CLK_P_1  EMMITSBURG_REV0P9  I78

CLK_25M_PCH_REF_NS_DN   @S9S_MB_2U_LIB.S9S_MB_2U(SCH_1):CLK_25M_PCH_REF_NS_DN
  R1011    2      B  Q_RES       I29
  U4     D25  REFCLK_INJ_NS_N  EMMITSBURG_REV0P9  I78

CLK_25M_PCH_REF_NS_DP   @S9S_MB_2U_LIB.S9S_MB_2U(SCH_1):CLK_25M_PCH_REF_NS_DP
  R1010    2      B  Q_RES       I22
  U4     B25  REFCLK_INJ_NS_P  EMMITSBURG_REV0P9  I78

CLK_50M_BMC_MAC_R   @S9S_MB_2U_LIB.S9S_MB_2U(SCH_1):CLK_50M_BMC_MAC_R
  R1140    1      A  Q_RES       I52
  U90      3     Y0  PI6CV304LE  I46

CLK_50M_EN      @S9S_MB_2U_LIB.S9S_MB_2U(SCH_1):CLK_50M_EN
  OSC1     1     OE  OSC4_SIT1602AI2233E50000000D  I58
  R1138    2      B  Q_RES       I61
  U90      2     OE  PI6CV304LE  I46

CLK_50M_NCSI_OCP_1   @S9S_MB_2U_LIB.S9S_MB_2U(SCH_1):CLK_50M_NCSI_OCP_1
  R1141    1      A  Q_RES       I53
  U90      5     Y1  PI6CV304LE  I46

CLK_50M_NCSI_OCP_SFF   @S9S_MB_2U_LIB.S9S_MB_2U(SCH_1):CLK_50M_NCSI_OCP_SFF
  J37    OCP_A14  RBT_CLK_IN  SCONN168_623403212  I86
  R1141    2      B  Q_RES       I53

CLK_50M_RMII    @S9S_MB_2U_LIB.S9S_MB_2U(SCH_1):CLK_50M_RMII
  OSC1     3    OUT  OSC4_SIT1602AI2233E50000000D  I58
  R1139    1      A  Q_RES       I56

CLK_50M_RMII_BMC_OCP   @S9S_MB_2U_LIB.S9S_MB_2U(SCH_1):CLK_50M_RMII_BMC_OCP
  J41    B18  PETP0  SCONN168_623403212  I115
  R1140    2      B  Q_RES       I52

CLK_50M_RMII_R   @S9S_MB_2U_LIB.S9S_MB_2U(SCH_1):CLK_50M_RMII_R
  R1139    2      B  Q_RES       I56
  U90      1  CLK_IN  PI6CV304LE  I46

CLK_CK440_SMB_ADDR0   @S9S_MB_2U_LIB.S9S_MB_2U(SCH_1):CLK_CK440_SMB_ADDR0
  R912     2      B  Q_RES       I278
  R953     1      A  Q_RES       I282
  U13    A11  SMB_ADR0_TRI  9SQ440NQQI8  I180

CLK_CK440_SMB_ADDR1   @S9S_MB_2U_LIB.S9S_MB_2U(SCH_1):CLK_CK440_SMB_ADDR1
  R562     2      B  Q_RES       I280
  R734     1      A  Q_RES       I283
  U13     B9  SMB_ADR1_TRI  9SQ440NQQI8  I180

CPU_RMCA_CATERR_LVT3_N   @S9S_MB_2U_LIB.S9S_MB_2U(SCH_1):CPU_RMCA_CATERR_LVT3_N
  Q33      G      G  MOSFET_PCH_GDS_ESD_PROTECTED  I242
  R365     2      B  Q_RES       I247

DBP_CPU0_HOOK8_MBP2_GTL_QS_R_N   @S9S_MB_2U_LIB.S9S_MB_2U(SCH_1):DBP_CPU0_HOOK8_MBP2_GTL_QS_R_N
  R24      1      A  Q_RES       I25
  U2     BJ23  MBP2_N  SOCKET4677_AZIFS054P001C01   I1

DBP_CPU0_HOOK9_MBP3_GTL_QS_R_N   @S9S_MB_2U_LIB.S9S_MB_2U(SCH_1):DBP_CPU0_HOOK9_MBP3_GTL_QS_R_N
  R25      1      A  Q_RES       I26
  U2     BK24  MBP3_N  SOCKET4677_AZIFS054P001C01   I1

DBP_CPU0_MBP0_GTL_R_N   @S9S_MB_2U_LIB.S9S_MB_2U(SCH_1):DBP_CPU0_MBP0_GTL_R_N
  R22      1      A  Q_RES       I19
  U2     BL23  MBP0_N  SOCKET4677_AZIFS054P001C01   I1

DBP_CPU0_MBP1_GTL_R_N   @S9S_MB_2U_LIB.S9S_MB_2U(SCH_1):DBP_CPU0_MBP1_GTL_R_N
  R23      1      A  Q_RES       I20
  U2     BN25  MBP1_N  SOCKET4677_AZIFS054P001C01   I1

DBP_CPU1_HOOK8_MBP2_GTL_QS_R_N   @S9S_MB_2U_LIB.S9S_MB_2U(SCH_1):DBP_CPU1_HOOK8_MBP2_GTL_QS_R_N
  R53      1      A  Q_RES       I23
  U1     BJ23  MBP2_N  SOCKET4677_AZIFS054P001C01  I16

DBP_CPU1_HOOK9_MBP3_GTL_QS_R_N   @S9S_MB_2U_LIB.S9S_MB_2U(SCH_1):DBP_CPU1_HOOK9_MBP3_GTL_QS_R_N
  R54      1      A  Q_RES       I22
  U1     BK24  MBP3_N  SOCKET4677_AZIFS054P001C01  I16

DBP_CPU1_MBP0_GTL_R_N   @S9S_MB_2U_LIB.S9S_MB_2U(SCH_1):DBP_CPU1_MBP0_GTL_R_N
  R51      1      A  Q_RES       I24
  U1     BL23  MBP0_N  SOCKET4677_AZIFS054P001C01  I16

DBP_CPU1_MBP1_GTL_R_N   @S9S_MB_2U_LIB.S9S_MB_2U(SCH_1):DBP_CPU1_MBP1_GTL_R_N
  R52      1      A  Q_RES       I25
  U1     BN25  MBP1_N  SOCKET4677_AZIFS054P001C01  I16

DBP_CPU_HOOK8_MBP2_GTL_QS_N   @S9S_MB_2U_LIB.S9S_MB_2U(SCH_1):DBP_CPU_HOOK8_MBP2_GTL_QS_N
  R24      2      B  Q_RES       I25
  R53      2      B  Q_RES       I23
  R760     2      B  Q_RES       I174
  U18      6     2B  74CBTLV3126PW  I129

DBP_CPU_HOOK9_MBP3_GTL_QS_N   @S9S_MB_2U_LIB.S9S_MB_2U(SCH_1):DBP_CPU_HOOK9_MBP3_GTL_QS_N
  R25      2      B  Q_RES       I26
  R54      2      B  Q_RES       I22
  R761     2      B  Q_RES       I175
  U18      3     1B  74CBTLV3126PW  I129

DBP_CPU_MBP0_GTL_N   @S9S_MB_2U_LIB.S9S_MB_2U(SCH_1):DBP_CPU_MBP0_GTL_N
  R18      2      B  Q_RES       I35
  R20      1      A  Q_RES       I31
  R22      2      B  Q_RES       I19
  R49      2      B  Q_RES       I34
  R51      2      B  Q_RES       I24

DBP_CPU_MBP1_GTL_N   @S9S_MB_2U_LIB.S9S_MB_2U(SCH_1):DBP_CPU_MBP1_GTL_N
  R19      2      B  Q_RES       I36
  R21      1      A  Q_RES       I32
  R23      2      B  Q_RES       I20
  R50      2      B  Q_RES       I35
  R52      2      B  Q_RES       I25

DELTA_L_85_10INCH_BOT_DN   @S9S_MB_2U_LIB.S9S_MB_2U(SCH_1):DELTA_L_85_10INCH_BOT_DN
  J76      2      2  DELTA_L     I33
  J82      1      1  DELTA_L     I70

DELTA_L_85_10INCH_BOT_DP   @S9S_MB_2U_LIB.S9S_MB_2U(SCH_1):DELTA_L_85_10INCH_BOT_DP
  J76      1      1  DELTA_L     I33
  J82      2      2  DELTA_L     I70

DELTA_L_85_10INCH_IN1_DN   @S9S_MB_2U_LIB.S9S_MB_2U(SCH_1):DELTA_L_85_10INCH_IN1_DN
  J77      2      2  DELTA_L     I50
  J83      1      1  DELTA_L     I69

DELTA_L_85_10INCH_IN1_DP   @S9S_MB_2U_LIB.S9S_MB_2U(SCH_1):DELTA_L_85_10INCH_IN1_DP
  J77      1      1  DELTA_L     I50
  J83      2      2  DELTA_L     I69

DELTA_L_85_10INCH_IN2_DN   @S9S_MB_2U_LIB.S9S_MB_2U(SCH_1):DELTA_L_85_10INCH_IN2_DN
  J78      2      2  DELTA_L     I52
  J84      1      1  DELTA_L     I68

DELTA_L_85_10INCH_IN2_DP   @S9S_MB_2U_LIB.S9S_MB_2U(SCH_1):DELTA_L_85_10INCH_IN2_DP
  J78      1      1  DELTA_L     I52
  J84      2      2  DELTA_L     I68

DELTA_L_85_10INCH_IN3_DN   @S9S_MB_2U_LIB.S9S_MB_2U(SCH_1):DELTA_L_85_10INCH_IN3_DN
  J79      2      2  DELTA_L     I56
  J85      1      1  DELTA_L     I67

DELTA_L_85_10INCH_IN3_DP   @S9S_MB_2U_LIB.S9S_MB_2U(SCH_1):DELTA_L_85_10INCH_IN3_DP
  J79      1      1  DELTA_L     I56
  J85      2      2  DELTA_L     I67

DELTA_L_85_10INCH_IN4_DN   @S9S_MB_2U_LIB.S9S_MB_2U(SCH_1):DELTA_L_85_10INCH_IN4_DN
  J80      2      2  DELTA_L     I32
  J86      1      1  DELTA_L     I66

DELTA_L_85_10INCH_IN4_DP   @S9S_MB_2U_LIB.S9S_MB_2U(SCH_1):DELTA_L_85_10INCH_IN4_DP
  J80      1      1  DELTA_L     I32
  J86      2      2  DELTA_L     I66

DELTA_L_85_10INCH_TOP_DN   @S9S_MB_2U_LIB.S9S_MB_2U(SCH_1):DELTA_L_85_10INCH_TOP_DN
  J75      2      2  DELTA_L     I34
  J81      1      1  DELTA_L     I71

DELTA_L_85_10INCH_TOP_DP   @S9S_MB_2U_LIB.S9S_MB_2U(SCH_1):DELTA_L_85_10INCH_TOP_DP
  J75      1      1  DELTA_L     I34
  J81      2      2  DELTA_L     I71

DELTA_L_85_5INCH_BOT_DN   @S9S_MB_2U_LIB.S9S_MB_2U(SCH_1):DELTA_L_85_5INCH_BOT_DN
  J64      2      2  DELTA_L      I5
  J70      1      1  DELTA_L     I61

DELTA_L_85_5INCH_BOT_DP   @S9S_MB_2U_LIB.S9S_MB_2U(SCH_1):DELTA_L_85_5INCH_BOT_DP
  J64      1      1  DELTA_L      I5
  J70      2      2  DELTA_L     I61

DELTA_L_85_5INCH_IN1_DN   @S9S_MB_2U_LIB.S9S_MB_2U(SCH_1):DELTA_L_85_5INCH_IN1_DN
  J65      2      2  DELTA_L     I10
  J71      1      1  DELTA_L     I62

DELTA_L_85_5INCH_IN1_DP   @S9S_MB_2U_LIB.S9S_MB_2U(SCH_1):DELTA_L_85_5INCH_IN1_DP
  J65      1      1  DELTA_L     I10
  J71      2      2  DELTA_L     I62

DELTA_L_85_5INCH_IN2_DN   @S9S_MB_2U_LIB.S9S_MB_2U(SCH_1):DELTA_L_85_5INCH_IN2_DN
  J66      2      2  DELTA_L      I9
  J72      1      1  DELTA_L     I63

DELTA_L_85_5INCH_IN2_DP   @S9S_MB_2U_LIB.S9S_MB_2U(SCH_1):DELTA_L_85_5INCH_IN2_DP
  J66      1      1  DELTA_L      I9
  J72      2      2  DELTA_L     I63

DELTA_L_85_5INCH_IN3_DN   @S9S_MB_2U_LIB.S9S_MB_2U(SCH_1):DELTA_L_85_5INCH_IN3_DN
  J67      2      2  DELTA_L     I24
  J73      1      1  DELTA_L     I64

DELTA_L_85_5INCH_IN3_DP   @S9S_MB_2U_LIB.S9S_MB_2U(SCH_1):DELTA_L_85_5INCH_IN3_DP
  J67      1      1  DELTA_L     I24
  J73      2      2  DELTA_L     I64

DELTA_L_85_5INCH_IN4_DN   @S9S_MB_2U_LIB.S9S_MB_2U(SCH_1):DELTA_L_85_5INCH_IN4_DN
  J68      2      2  DELTA_L     I31
  J74      1      1  DELTA_L     I65

DELTA_L_85_5INCH_IN4_DP   @S9S_MB_2U_LIB.S9S_MB_2U(SCH_1):DELTA_L_85_5INCH_IN4_DP
  J68      1      1  DELTA_L     I31
  J74      2      2  DELTA_L     I65

DELTA_L_85_5INCH_TOP_DN   @S9S_MB_2U_LIB.S9S_MB_2U(SCH_1):DELTA_L_85_5INCH_TOP_DN
  J63      2      2  DELTA_L      I1
  J69      1      1  DELTA_L     I60

DELTA_L_85_5INCH_TOP_DP   @S9S_MB_2U_LIB.S9S_MB_2U(SCH_1):DELTA_L_85_5INCH_TOP_DP
  J63      1      1  DELTA_L      I1
  J69      2      2  DELTA_L     I60

DELTA_L_GND     @S9S_MB_2U_LIB.S9S_MB_2U(SCH_1):DELTA_L_GND
  J65      3      3  DELTA_L     I10
  J66      3      3  DELTA_L      I9
  J67      3      3  DELTA_L     I24
  J71      3      3  DELTA_L     I62
  J72      3      3  DELTA_L     I63
  J73      3      3  DELTA_L     I64
  J77      3      3  DELTA_L     I50
  J80      3      3  DELTA_L     I32
  J83      3      3  DELTA_L     I69
  J86      3      3  DELTA_L     I66

DELTA_R_GND     @S9S_MB_2U_LIB.S9S_MB_2U(SCH_1):DELTA_R_GND
  J63      3      3  DELTA_L      I1
  J64      3      3  DELTA_L      I5
  J68      3      3  DELTA_L     I31
  J69      3      3  DELTA_L     I60
  J70      3      3  DELTA_L     I61
  J74      3      3  DELTA_L     I65
  J75      3      3  DELTA_L     I34
  J76      3      3  DELTA_L     I33
  J78      3      3  DELTA_L     I52
  J79      3      3  DELTA_L     I56
  J81      3      3  DELTA_L     I71
  J82      3      3  DELTA_L     I70
  J84      3      3  DELTA_L     I68
  J85      3      3  DELTA_L     I67

DMI_CPU0_PCH_RX_C_DN<0>   @S9S_MB_2U_LIB.S9S_MB_2U(SCH_1):DMI_CPU0_PCH_RX_C_DN<0>
  C169     1      1  Q_CAP_DIFFBUS  I127
  U2     BB18  DMI_RX_DN0  SOCKET4677_AZIFS054P001C01  I169

DMI_CPU0_PCH_RX_C_DN<1>   @S9S_MB_2U_LIB.S9S_MB_2U(SCH_1):DMI_CPU0_PCH_RX_C_DN<1>
  C167     1      1  Q_CAP_DIFFBUS  I126
  U2     BD18  DMI_RX_DP1  SOCKET4677_AZIFS054P001C01  I169

DMI_CPU0_PCH_RX_C_DN<2>   @S9S_MB_2U_LIB.S9S_MB_2U(SCH_1):DMI_CPU0_PCH_RX_C_DN<2>
  C165     1      1  Q_CAP_DIFFBUS  I123
  U2     BF18  DMI_RX_DN2  SOCKET4677_AZIFS054P001C01  I169

DMI_CPU0_PCH_RX_C_DN<3>   @S9S_MB_2U_LIB.S9S_MB_2U(SCH_1):DMI_CPU0_PCH_RX_C_DN<3>
  C163     1      1  Q_CAP_DIFFBUS  I121
  U2     BH18  DMI_RX_DP3  SOCKET4677_AZIFS054P001C01  I169

DMI_CPU0_PCH_RX_C_DN<4>   @S9S_MB_2U_LIB.S9S_MB_2U(SCH_1):DMI_CPU0_PCH_RX_C_DN<4>
  C161     1      1  Q_CAP_DIFFBUS  I119
  U2     BL19  DMI_RX_DP4  SOCKET4677_AZIFS054P001C01  I169

DMI_CPU0_PCH_RX_C_DN<5>   @S9S_MB_2U_LIB.S9S_MB_2U(SCH_1):DMI_CPU0_PCH_RX_C_DN<5>
  C159     1      1  Q_CAP_DIFFBUS  I117
  U2     BM18  DMI_RX_DP5  SOCKET4677_AZIFS054P001C01  I169

DMI_CPU0_PCH_RX_C_DN<6>   @S9S_MB_2U_LIB.S9S_MB_2U(SCH_1):DMI_CPU0_PCH_RX_C_DN<6>
  C157     1      1  Q_CAP_DIFFBUS  I115
  U2     BR19  DMI_RX_DP6  SOCKET4677_AZIFS054P001C01  I169

DMI_CPU0_PCH_RX_C_DN<7>   @S9S_MB_2U_LIB.S9S_MB_2U(SCH_1):DMI_CPU0_PCH_RX_C_DN<7>
  C155     1      1  Q_CAP_DIFFBUS  I113
  U2     BU17  DMI_RX_DN7  SOCKET4677_AZIFS054P001C01  I169

DMI_CPU0_PCH_RX_C_DP<0>   @S9S_MB_2U_LIB.S9S_MB_2U(SCH_1):DMI_CPU0_PCH_RX_C_DP<0>
  C170     1      1  Q_CAP_DIFFBUS  I128
  U2     BC19  DMI_RX_DP0  SOCKET4677_AZIFS054P001C01  I169

DMI_CPU0_PCH_RX_C_DP<1>   @S9S_MB_2U_LIB.S9S_MB_2U(SCH_1):DMI_CPU0_PCH_RX_C_DP<1>
  C168     1      1  Q_CAP_DIFFBUS  I125
  U2     BE17  DMI_RX_DN1  SOCKET4677_AZIFS054P001C01  I169

DMI_CPU0_PCH_RX_C_DP<2>   @S9S_MB_2U_LIB.S9S_MB_2U(SCH_1):DMI_CPU0_PCH_RX_C_DP<2>
  C166     1      1  Q_CAP_DIFFBUS  I124
  U2     BG19  DMI_RX_DP2  SOCKET4677_AZIFS054P001C01  I169

DMI_CPU0_PCH_RX_C_DP<3>   @S9S_MB_2U_LIB.S9S_MB_2U(SCH_1):DMI_CPU0_PCH_RX_C_DP<3>
  C164     1      1  Q_CAP_DIFFBUS  I122
  U2     BJ17  DMI_RX_DN3  SOCKET4677_AZIFS054P001C01  I169

DMI_CPU0_PCH_RX_C_DP<4>   @S9S_MB_2U_LIB.S9S_MB_2U(SCH_1):DMI_CPU0_PCH_RX_C_DP<4>
  C162     1      1  Q_CAP_DIFFBUS  I120
  U2     BK18  DMI_RX_DN4  SOCKET4677_AZIFS054P001C01  I169

DMI_CPU0_PCH_RX_C_DP<5>   @S9S_MB_2U_LIB.S9S_MB_2U(SCH_1):DMI_CPU0_PCH_RX_C_DP<5>
  C160     1      1  Q_CAP_DIFFBUS  I118
  U2     BN17  DMI_RX_DN5  SOCKET4677_AZIFS054P001C01  I169

DMI_CPU0_PCH_RX_C_DP<6>   @S9S_MB_2U_LIB.S9S_MB_2U(SCH_1):DMI_CPU0_PCH_RX_C_DP<6>
  C158     1      1  Q_CAP_DIFFBUS  I116
  U2     BP18  DMI_RX_DN6  SOCKET4677_AZIFS054P001C01  I169

DMI_CPU0_PCH_RX_C_DP<7>   @S9S_MB_2U_LIB.S9S_MB_2U(SCH_1):DMI_CPU0_PCH_RX_C_DP<7>
  C156     1      1  Q_CAP_DIFFBUS  I114
  U2     BT18  DMI_RX_DP7  SOCKET4677_AZIFS054P001C01  I169

DMI_CPU0_PCH_RX_DN<0>   @S9S_MB_2U_LIB.S9S_MB_2U(SCH_1):DMI_CPU0_PCH_RX_DN<0>
  C169     2      2  Q_CAP_DIFFBUS  I127
  U4     K28  DMI_0_TXN  EMMITSBURG_REV0P9  I119

DMI_CPU0_PCH_RX_DN<1>   @S9S_MB_2U_LIB.S9S_MB_2U(SCH_1):DMI_CPU0_PCH_RX_DN<1>
  C167     2      2  Q_CAP_DIFFBUS  I126
  U4     G29  DMI_1_TXN  EMMITSBURG_REV0P9  I119

DMI_CPU0_PCH_RX_DN<2>   @S9S_MB_2U_LIB.S9S_MB_2U(SCH_1):DMI_CPU0_PCH_RX_DN<2>
  C165     2      2  Q_CAP_DIFFBUS  I123
  U4     J29  DMI_2_TXN  EMMITSBURG_REV0P9  I119

DMI_CPU0_PCH_RX_DN<3>   @S9S_MB_2U_LIB.S9S_MB_2U(SCH_1):DMI_CPU0_PCH_RX_DN<3>
  C163     2      2  Q_CAP_DIFFBUS  I121
  U4     L32  DMI_3_TXN  EMMITSBURG_REV0P9  I119

DMI_CPU0_PCH_RX_DN<4>   @S9S_MB_2U_LIB.S9S_MB_2U(SCH_1):DMI_CPU0_PCH_RX_DN<4>
  C161     2      2  Q_CAP_DIFFBUS  I119
  U4     J32  DMI_4_SATA_19_PCIE3_19_TXN  EMMITSBURG_REV0P9  I119

DMI_CPU0_PCH_RX_DN<5>   @S9S_MB_2U_LIB.S9S_MB_2U(SCH_1):DMI_CPU0_PCH_RX_DN<5>
  C159     2      2  Q_CAP_DIFFBUS  I117
  U4     G36  DMI_5_SATA_18_PCIE3_18_TXN  EMMITSBURG_REV0P9  I119

DMI_CPU0_PCH_RX_DN<6>   @S9S_MB_2U_LIB.S9S_MB_2U(SCH_1):DMI_CPU0_PCH_RX_DN<6>
  C157     2      2  Q_CAP_DIFFBUS  I115
  U4     K37  DMI_6_SATA_17_PCIE3_17_TXN  EMMITSBURG_REV0P9  I119

DMI_CPU0_PCH_RX_DN<7>   @S9S_MB_2U_LIB.S9S_MB_2U(SCH_1):DMI_CPU0_PCH_RX_DN<7>
  C155     2      2  Q_CAP_DIFFBUS  I113
  U4     F37  DMI_7_SATA_16_PCIE3_16_TXN  EMMITSBURG_REV0P9  I119

DMI_CPU0_PCH_RX_DP<0>   @S9S_MB_2U_LIB.S9S_MB_2U(SCH_1):DMI_CPU0_PCH_RX_DP<0>
  C170     2      2  Q_CAP_DIFFBUS  I128
  U4     H28  DMI_0_TXP  EMMITSBURG_REV0P9  I119

DMI_CPU0_PCH_RX_DP<1>   @S9S_MB_2U_LIB.S9S_MB_2U(SCH_1):DMI_CPU0_PCH_RX_DP<1>
  C168     2      2  Q_CAP_DIFFBUS  I125
  U4     F28  DMI_1_TXP  EMMITSBURG_REV0P9  I119

DMI_CPU0_PCH_RX_DP<2>   @S9S_MB_2U_LIB.S9S_MB_2U(SCH_1):DMI_CPU0_PCH_RX_DP<2>
  C166     2      2  Q_CAP_DIFFBUS  I124
  U4     H31  DMI_2_TXP  EMMITSBURG_REV0P9  I119

DMI_CPU0_PCH_RX_DP<3>   @S9S_MB_2U_LIB.S9S_MB_2U(SCH_1):DMI_CPU0_PCH_RX_DP<3>
  C164     2      2  Q_CAP_DIFFBUS  I122
  U4     K31  DMI_3_TXP  EMMITSBURG_REV0P9  I119

DMI_CPU0_PCH_RX_DP<4>   @S9S_MB_2U_LIB.S9S_MB_2U(SCH_1):DMI_CPU0_PCH_RX_DP<4>
  C162     2      2  Q_CAP_DIFFBUS  I120
  U4     G32  DMI_4_SATA_19_PCIE3_19_TXP  EMMITSBURG_REV0P9  I119

DMI_CPU0_PCH_RX_DP<5>   @S9S_MB_2U_LIB.S9S_MB_2U(SCH_1):DMI_CPU0_PCH_RX_DP<5>
  C160     2      2  Q_CAP_DIFFBUS  I118
  U4     H34  DMI_5_SATA_18_PCIE3_18_TXP  EMMITSBURG_REV0P9  I119

DMI_CPU0_PCH_RX_DP<6>   @S9S_MB_2U_LIB.S9S_MB_2U(SCH_1):DMI_CPU0_PCH_RX_DP<6>
  C158     2      2  Q_CAP_DIFFBUS  I116
  U4     J36  DMI_6_SATA_17_PCIE3_17_TXP  EMMITSBURG_REV0P9  I119

DMI_CPU0_PCH_RX_DP<7>   @S9S_MB_2U_LIB.S9S_MB_2U(SCH_1):DMI_CPU0_PCH_RX_DP<7>
  C156     2      2  Q_CAP_DIFFBUS  I114
  U4     H37  DMI_7_SATA_16_PCIE3_16_TXP  EMMITSBURG_REV0P9  I119

DMI_CPU0_PCH_TX_C_DN<0>   @S9S_MB_2U_LIB.S9S_MB_2U(SCH_1):DMI_CPU0_PCH_TX_C_DN<0>
  C153     1      1  Q_CAP_DIFFBUS  I21
  U4     A30  DMI_0_RXN  EMMITSBURG_REV0P9  I119

DMI_CPU0_PCH_TX_C_DN<1>   @S9S_MB_2U_LIB.S9S_MB_2U(SCH_1):DMI_CPU0_PCH_TX_C_DN<1>
  C151     1      1  Q_CAP_DIFFBUS  I24
  U4     B31  DMI_1_RXN  EMMITSBURG_REV0P9  I119

DMI_CPU0_PCH_TX_C_DN<2>   @S9S_MB_2U_LIB.S9S_MB_2U(SCH_1):DMI_CPU0_PCH_TX_C_DN<2>
  C149     1      1  Q_CAP_DIFFBUS  I25
  U4     A32  DMI_2_RXN  EMMITSBURG_REV0P9  I119

DMI_CPU0_PCH_TX_C_DN<3>   @S9S_MB_2U_LIB.S9S_MB_2U(SCH_1):DMI_CPU0_PCH_TX_C_DN<3>
  C147     1      1  Q_CAP_DIFFBUS  I28
  U4     B33  DMI_3_RXN  EMMITSBURG_REV0P9  I119

DMI_CPU0_PCH_TX_C_DN<4>   @S9S_MB_2U_LIB.S9S_MB_2U(SCH_1):DMI_CPU0_PCH_TX_C_DN<4>
  C145     1      1  Q_CAP_DIFFBUS  I30
  U4     A34  DMI_4_SATA_19_PCIE3_19_RXN  EMMITSBURG_REV0P9  I119

DMI_CPU0_PCH_TX_C_DN<5>   @S9S_MB_2U_LIB.S9S_MB_2U(SCH_1):DMI_CPU0_PCH_TX_C_DN<5>
  C143     1      1  Q_CAP_DIFFBUS  I32
  U4     B35  DMI_5_SATA_18_PCIE3_18_RXN  EMMITSBURG_REV0P9  I119

DMI_CPU0_PCH_TX_C_DN<6>   @S9S_MB_2U_LIB.S9S_MB_2U(SCH_1):DMI_CPU0_PCH_TX_C_DN<6>
  C141     1      1  Q_CAP_DIFFBUS  I34
  U4     A36  DMI_6_SATA_17_PCIE3_17_RXN  EMMITSBURG_REV0P9  I119

DMI_CPU0_PCH_TX_C_DN<7>   @S9S_MB_2U_LIB.S9S_MB_2U(SCH_1):DMI_CPU0_PCH_TX_C_DN<7>
  C139     1      1  Q_CAP_DIFFBUS  I35
  U4     B37  DMI_7_SATA_16_PCIE3_16_RXN  EMMITSBURG_REV0P9  I119

DMI_CPU0_PCH_TX_C_DP<0>   @S9S_MB_2U_LIB.S9S_MB_2U(SCH_1):DMI_CPU0_PCH_TX_C_DP<0>
  C154     1      1  Q_CAP_DIFFBUS  I22
  U4     C30  DMI_0_RXP  EMMITSBURG_REV0P9  I119

DMI_CPU0_PCH_TX_C_DP<1>   @S9S_MB_2U_LIB.S9S_MB_2U(SCH_1):DMI_CPU0_PCH_TX_C_DP<1>
  C152     1      1  Q_CAP_DIFFBUS  I23
  U4     D31  DMI_1_RXP  EMMITSBURG_REV0P9  I119

DMI_CPU0_PCH_TX_C_DP<2>   @S9S_MB_2U_LIB.S9S_MB_2U(SCH_1):DMI_CPU0_PCH_TX_C_DP<2>
  C150     1      1  Q_CAP_DIFFBUS  I26
  U4     C32  DMI_2_RXP  EMMITSBURG_REV0P9  I119

DMI_CPU0_PCH_TX_C_DP<3>   @S9S_MB_2U_LIB.S9S_MB_2U(SCH_1):DMI_CPU0_PCH_TX_C_DP<3>
  C148     1      1  Q_CAP_DIFFBUS  I27
  U4     D33  DMI_3_RXP  EMMITSBURG_REV0P9  I119

DMI_CPU0_PCH_TX_C_DP<4>   @S9S_MB_2U_LIB.S9S_MB_2U(SCH_1):DMI_CPU0_PCH_TX_C_DP<4>
  C146     1      1  Q_CAP_DIFFBUS  I29
  U4     C34  DMI_4_SATA_19_PCIE3_19_RXP  EMMITSBURG_REV0P9  I119

DMI_CPU0_PCH_TX_C_DP<5>   @S9S_MB_2U_LIB.S9S_MB_2U(SCH_1):DMI_CPU0_PCH_TX_C_DP<5>
  C144     1      1  Q_CAP_DIFFBUS  I31
  U4     D35  DMI_5_SATA_18_PCIE3_18_RXP  EMMITSBURG_REV0P9  I119

DMI_CPU0_PCH_TX_C_DP<6>   @S9S_MB_2U_LIB.S9S_MB_2U(SCH_1):DMI_CPU0_PCH_TX_C_DP<6>
  C142     1      1  Q_CAP_DIFFBUS  I33
  U4     C36  DMI_6_SATA_17_PCIE3_17_RXP  EMMITSBURG_REV0P9  I119

DMI_CPU0_PCH_TX_C_DP<7>   @S9S_MB_2U_LIB.S9S_MB_2U(SCH_1):DMI_CPU0_PCH_TX_C_DP<7>
  C140     1      1  Q_CAP_DIFFBUS  I36
  U4     D37  DMI_7_SATA_16_PCIE3_16_RXP  EMMITSBURG_REV0P9  I119

DMI_CPU0_PCH_TX_DN<0>   @S9S_MB_2U_LIB.S9S_MB_2U(SCH_1):DMI_CPU0_PCH_TX_DN<0>
  C153     2      2  Q_CAP_DIFFBUS  I21
  U2     CA19  DMI_TX_DP0  SOCKET4677_AZIFS054P001C01  I169

DMI_CPU0_PCH_TX_DN<1>   @S9S_MB_2U_LIB.S9S_MB_2U(SCH_1):DMI_CPU0_PCH_TX_DN<1>
  C151     2      2  Q_CAP_DIFFBUS  I24
  U2     BY18  DMI_TX_DP1  SOCKET4677_AZIFS054P001C01  I169

DMI_CPU0_PCH_TX_DN<2>   @S9S_MB_2U_LIB.S9S_MB_2U(SCH_1):DMI_CPU0_PCH_TX_DN<2>
  C149     2      2  Q_CAP_DIFFBUS  I25
  U2     CC19  DMI_TX_DP2  SOCKET4677_AZIFS054P001C01  I169

DMI_CPU0_PCH_TX_DN<3>   @S9S_MB_2U_LIB.S9S_MB_2U(SCH_1):DMI_CPU0_PCH_TX_DN<3>
  C147     2      2  Q_CAP_DIFFBUS  I28
  U2     CE17  DMI_TX_DN3  SOCKET4677_AZIFS054P001C01  I169

DMI_CPU0_PCH_TX_DN<4>   @S9S_MB_2U_LIB.S9S_MB_2U(SCH_1):DMI_CPU0_PCH_TX_DN<4>
  C145     2      2  Q_CAP_DIFFBUS  I30
  U2     CF18  DMI_TX_DN4  SOCKET4677_AZIFS054P001C01  I169

DMI_CPU0_PCH_TX_DN<5>   @S9S_MB_2U_LIB.S9S_MB_2U(SCH_1):DMI_CPU0_PCH_TX_DN<5>
  C143     2      2  Q_CAP_DIFFBUS  I32
  U2     CJ17  DMI_TX_DN5  SOCKET4677_AZIFS054P001C01  I169

DMI_CPU0_PCH_TX_DN<6>   @S9S_MB_2U_LIB.S9S_MB_2U(SCH_1):DMI_CPU0_PCH_TX_DN<6>
  C141     2      2  Q_CAP_DIFFBUS  I34
  U2     CL19  DMI_TX_DP6  SOCKET4677_AZIFS054P001C01  I169

DMI_CPU0_PCH_TX_DN<7>   @S9S_MB_2U_LIB.S9S_MB_2U(SCH_1):DMI_CPU0_PCH_TX_DN<7>
  C139     2      2  Q_CAP_DIFFBUS  I35
  U2     CM18  DMI_TX_DP7  SOCKET4677_AZIFS054P001C01  I169

DMI_CPU0_PCH_TX_DP<0>   @S9S_MB_2U_LIB.S9S_MB_2U(SCH_1):DMI_CPU0_PCH_TX_DP<0>
  C154     2      2  Q_CAP_DIFFBUS  I22
  U2     BW19  DMI_TX_DN0  SOCKET4677_AZIFS054P001C01  I169

DMI_CPU0_PCH_TX_DP<1>   @S9S_MB_2U_LIB.S9S_MB_2U(SCH_1):DMI_CPU0_PCH_TX_DP<1>
  C152     2      2  Q_CAP_DIFFBUS  I23
  U2     CA17  DMI_TX_DN1  SOCKET4677_AZIFS054P001C01  I169

DMI_CPU0_PCH_TX_DP<2>   @S9S_MB_2U_LIB.S9S_MB_2U(SCH_1):DMI_CPU0_PCH_TX_DP<2>
  C150     2      2  Q_CAP_DIFFBUS  I26
  U2     CB18  DMI_TX_DN2  SOCKET4677_AZIFS054P001C01  I169

DMI_CPU0_PCH_TX_DP<3>   @S9S_MB_2U_LIB.S9S_MB_2U(SCH_1):DMI_CPU0_PCH_TX_DP<3>
  C148     2      2  Q_CAP_DIFFBUS  I27
  U2     CD18  DMI_TX_DP3  SOCKET4677_AZIFS054P001C01  I169

DMI_CPU0_PCH_TX_DP<4>   @S9S_MB_2U_LIB.S9S_MB_2U(SCH_1):DMI_CPU0_PCH_TX_DP<4>
  C146     2      2  Q_CAP_DIFFBUS  I29
  U2     CG19  DMI_TX_DP4  SOCKET4677_AZIFS054P001C01  I169

DMI_CPU0_PCH_TX_DP<5>   @S9S_MB_2U_LIB.S9S_MB_2U(SCH_1):DMI_CPU0_PCH_TX_DP<5>
  C144     2      2  Q_CAP_DIFFBUS  I31
  U2     CH18  DMI_TX_DP5  SOCKET4677_AZIFS054P001C01  I169

DMI_CPU0_PCH_TX_DP<6>   @S9S_MB_2U_LIB.S9S_MB_2U(SCH_1):DMI_CPU0_PCH_TX_DP<6>
  C142     2      2  Q_CAP_DIFFBUS  I33
  U2     CK18  DMI_TX_DN6  SOCKET4677_AZIFS054P001C01  I169

DMI_CPU0_PCH_TX_DP<7>   @S9S_MB_2U_LIB.S9S_MB_2U(SCH_1):DMI_CPU0_PCH_TX_DP<7>
  C140     2      2  Q_CAP_DIFFBUS  I36
  U2     CN17  DMI_TX_DN7  SOCKET4677_AZIFS054P001C01  I169

E1S_0_BUF_PRSNT_N   @S9S_MB_2U_LIB.S9S_MB_2U(SCH_1):E1S_0_BUF_PRSNT_N
  R2106    1      A  Q_RES       I35
  U130     8    P04  PCA9555PW    I1

E1S_0_BUF_PRSNT_R_N   @S9S_MB_2U_LIB.S9S_MB_2U(SCH_1):E1S_0_BUF_PRSNT_R_N
  R2106    2      B  Q_RES       I35
  U132     6     1Y  SN74LVC2G17DCKR  I80

E1S_0_EN        @S9S_MB_2U_LIB.S9S_MB_2U(SCH_1):E1S_0_EN
  R2105    2      B  Q_RES       I34
  R2160    1      A  Q_RES       I187
  R2164    1      A  Q_RES       I70

E1S_0_LED_ACT_N   @S9S_MB_2U_LIB.S9S_MB_2U(SCH_1):E1S_0_LED_ACT_N
  J90    A10  LED#||ACTIVITY  CONN56_ME2005602311011  I105
  R2151    2      B  Q_RES       I94

E1S_0_PRSNT_N   @S9S_MB_2U_LIB.S9S_MB_2U(SCH_1):E1S_0_PRSNT_N
  J90    A12  PRSNT0#  CONN56_ME2005602311011  I105
  U132     1     1A  SN74LVC2G17DCKR  I80

E1S_0_PWR_FAIL_N   @S9S_MB_2U_LIB.S9S_MB_2U(SCH_1):E1S_0_PWR_FAIL_N
  R2151    1      A  Q_RES       I94
  U130     5    P01  PCA9555PW    I1

E1S_1_BUF_EN    @S9S_MB_2U_LIB.S9S_MB_2U(SCH_1):E1S_1_BUF_EN
  R2105    1      A  Q_RES       I34
  R2107    1      A  Q_RES       I44
  U130     6    P02  PCA9555PW    I1
  U130    15    P12  PCA9555PW    I1

E1S_1_BUF_PRSNT_N   @S9S_MB_2U_LIB.S9S_MB_2U(SCH_1):E1S_1_BUF_PRSNT_N
  R2108    1      A  Q_RES       I41
  U130    17    P14  PCA9555PW    I1

E1S_1_BUF_PRSNT_R_N   @S9S_MB_2U_LIB.S9S_MB_2U(SCH_1):E1S_1_BUF_PRSNT_R_N
  R2108    2      B  Q_RES       I41
  U132     4     2Y  SN74LVC2G17DCKR  I80

E1S_1_EN        @S9S_MB_2U_LIB.S9S_MB_2U(SCH_1):E1S_1_EN
  R2107    2      B  Q_RES       I44
  R2161    1      A  Q_RES       I193
  R2165    1      A  Q_RES       I74

E1S_1_LED_ACT_N   @S9S_MB_2U_LIB.S9S_MB_2U(SCH_1):E1S_1_LED_ACT_N
  J91    A10  LED#||ACTIVITY  CONN56_ME2005602311011  I123
  R2152    2      B  Q_RES       I97

E1S_1_PRSNT_N   @S9S_MB_2U_LIB.S9S_MB_2U(SCH_1):E1S_1_PRSNT_N
  J91    A12  PRSNT0#  CONN56_ME2005602311011  I123
  U132     3     2A  SN74LVC2G17DCKR  I80

E1S_1_PWR_FAIL_N   @S9S_MB_2U_LIB.S9S_MB_2U(SCH_1):E1S_1_PWR_FAIL_N
  R2152    1      A  Q_RES       I97
  U130    14    P11  PCA9555PW    I1

E1S_2_BUF_EN    @S9S_MB_2U_LIB.S9S_MB_2U(SCH_1):E1S_2_BUF_EN
  R2109    1      A  Q_RES       I56
  U131     6    P02  PCA9555PW   I51

E1S_2_BUF_PRSNT_N   @S9S_MB_2U_LIB.S9S_MB_2U(SCH_1):E1S_2_BUF_PRSNT_N
  R2110    1      A  Q_RES       I57
  U131     8    P04  PCA9555PW   I51

E1S_2_BUF_PRSNT_R_N   @S9S_MB_2U_LIB.S9S_MB_2U(SCH_1):E1S_2_BUF_PRSNT_R_N
  R2110    2      B  Q_RES       I57
  U133     6     1Y  SN74LVC2G17DCKR  I93

E1S_2_EN        @S9S_MB_2U_LIB.S9S_MB_2U(SCH_1):E1S_2_EN
  R2109    2      B  Q_RES       I56
  R2159    1      A  Q_RES       I189
  R2163    1      A  Q_RES       I72

E1S_2_LED_ACT_N   @S9S_MB_2U_LIB.S9S_MB_2U(SCH_1):E1S_2_LED_ACT_N
  J92    A10  LED#||ACTIVITY  CONN56_ME2005602311011  I105
  R2153    2      B  Q_RES       I100

E1S_2_PRSNT_N   @S9S_MB_2U_LIB.S9S_MB_2U(SCH_1):E1S_2_PRSNT_N
  J92    A12  PRSNT0#  CONN56_ME2005602311011  I105
  U133     1     1A  SN74LVC2G17DCKR  I93

E1S_2_PWR_FAIL_N   @S9S_MB_2U_LIB.S9S_MB_2U(SCH_1):E1S_2_PWR_FAIL_N
  R2153    1      A  Q_RES       I100
  U131     5    P01  PCA9555PW   I51

E1S_3_BUF_EN    @S9S_MB_2U_LIB.S9S_MB_2U(SCH_1):E1S_3_BUF_EN
  R2111    1      A  Q_RES       I59
  U131    15    P12  PCA9555PW   I51

E1S_3_BUF_PRSNT_N   @S9S_MB_2U_LIB.S9S_MB_2U(SCH_1):E1S_3_BUF_PRSNT_N
  R2112    1      A  Q_RES       I58
  U131    17    P14  PCA9555PW   I51

E1S_3_BUF_PRSNT_R_N   @S9S_MB_2U_LIB.S9S_MB_2U(SCH_1):E1S_3_BUF_PRSNT_R_N
  R2112    2      B  Q_RES       I58
  U133     4     2Y  SN74LVC2G17DCKR  I93

E1S_3_EN        @S9S_MB_2U_LIB.S9S_MB_2U(SCH_1):E1S_3_EN
  R2111    2      B  Q_RES       I59
  R2162    1      A  Q_RES       I191
  R2166    1      A  Q_RES       I76

E1S_3_LED_ACT_N   @S9S_MB_2U_LIB.S9S_MB_2U(SCH_1):E1S_3_LED_ACT_N
  J93    A10  LED#||ACTIVITY  CONN56_ME2005602311011  I123
  R2154    2      B  Q_RES       I98

E1S_3_PRSNT_N   @S9S_MB_2U_LIB.S9S_MB_2U(SCH_1):E1S_3_PRSNT_N
  J93    A12  PRSNT0#  CONN56_ME2005602311011  I123
  U133     3     2A  SN74LVC2G17DCKR  I93

E1S_3_PWR_FAIL_N   @S9S_MB_2U_LIB.S9S_MB_2U(SCH_1):E1S_3_PWR_FAIL_N
  R2154    1      A  Q_RES       I98
  U131    14    P11  PCA9555PW   I51

EDSFF1A_PERST1_CLKREQ_N   @S9S_MB_2U_LIB.S9S_MB_2U(SCH_1):EDSFF1A_PERST1_CLKREQ_N
  J62    A11  PERST1_N_CLKREQ_N  SCONN84_123318136  I33
  R1542    2      B  Q_RES       I418
  R1544    1      A  Q_RES       I416
  R1969    1      A  Q_RES       I87

EDSFF3_CLK_EN_N   @S9S_MB_2U_LIB.S9S_MB_2U(SCH_1):EDSFF3_CLK_EN_N
  R2148    2      B  Q_RES       I337
  U13    A30   OE1#  9SQ440NQQI8  I180

EDSFF3_PRSNT_0_N   @S9S_MB_2U_LIB.S9S_MB_2U(SCH_1):EDSFF3_PRSNT_0_N
  J35     A1  GND_A1  SCONN140_G64V3431BHR  I64
  R1618    1      A  Q_RES       I446

EDSFF3_USB2_5_DN   @S9S_MB_2U_LIB.S9S_MB_2U(SCH_1):EDSFF3_USB2_5_DN
  J35    A14  SIGNAL_A14  SCONN140_G64V3431BHR  I64
  R2149    1      A  Q_RES       I460

EDSFF3_USB2_5_DP   @S9S_MB_2U_LIB.S9S_MB_2U(SCH_1):EDSFF3_USB2_5_DP
  J35    A15  SIGNAL_A15  SCONN140_G64V3431BHR  I64
  R2150    1      A  Q_RES       I457

EDSFF4A_PERST1_CLKREQ_N   @S9S_MB_2U_LIB.S9S_MB_2U(SCH_1):EDSFF4A_PERST1_CLKREQ_N
  J88    A11  PERST1_N_CLKREQ_N  SCONN84_123318136  I16
  R1989    1      A  Q_RES       I10

EDSFF4B_PERST1_CLKREQ_N   @S9S_MB_2U_LIB.S9S_MB_2U(SCH_1):EDSFF4B_PERST1_CLKREQ_N
  J61    A11  PERST1_N_CLKREQ_N  SCONN84_123318136  I49
  R2001    1      A  Q_RES       I10

ESPI_ALERT1_N_LPC_RCIN_N   @S9S_MB_2U_LIB.S9S_MB_2U(SCH_1):ESPI_ALERT1_N_LPC_RCIN_N
  R1255    2      B  Q_RES       I26
  U4     BD15  GPPC_A_1_ESPI_ALERT1_N  EMMITSBURG_REV0P9  I93

ESPI_BMC_LPC_RST_N   @S9S_MB_2U_LIB.S9S_MB_2U(SCH_1):ESPI_BMC_LPC_RST_N
  J41     B4  +12V_EDGE_B4  SCONN168_623403212  I115
  U61      4      A  NC7SB3157   I39

ESPI_HOST_LPC_BMC_CLK   @S9S_MB_2U_LIB.S9S_MB_2U(SCH_1):ESPI_HOST_LPC_BMC_CLK
  J41     B1  +12V_EDGE_B1  SCONN168_623403212  I115
  R1872    2      B  Q_RES       I65

ESPI_HOST_LPC_BMC_LFRAME_N   @S9S_MB_2U_LIB.S9S_MB_2U(SCH_1):ESPI_HOST_LPC_BMC_LFRAME_N
  J41     B2  +12V_EDGE_B2  SCONN168_623403212  I115
  R1479    2      B  Q_RES       I52

ESPI_LAD0_DATA_IO0   @S9S_MB_2U_LIB.S9S_MB_2U(SCH_1):ESPI_LAD0_DATA_IO0
  R1871    1      A  Q_RES       I64
  U4     BG12  GPPC_A_2_ESPI_IO_0  EMMITSBURG_REV0P9  I93

ESPI_LAD0_DATA_IO1   @S9S_MB_2U_LIB.S9S_MB_2U(SCH_1):ESPI_LAD0_DATA_IO1
  R1870    1      A  Q_RES       I63
  U4     BF19  GPPC_A_3_ESPI_IO_1  EMMITSBURG_REV0P9  I93

ESPI_LAD0_DATA_IO2   @S9S_MB_2U_LIB.S9S_MB_2U(SCH_1):ESPI_LAD0_DATA_IO2
  R1869    1      A  Q_RES       I62
  U4     BE18  GPPC_A_4_ESPI_IO_2  EMMITSBURG_REV0P9  I93

ESPI_LAD0_DATA_IO3   @S9S_MB_2U_LIB.S9S_MB_2U(SCH_1):ESPI_LAD0_DATA_IO3
  R1868    1      A  Q_RES       I61
  U4     BD19  GPPC_A_5_ESPI_IO_3  EMMITSBURG_REV0P9  I93

ESPI_LFRAME_N_BMC_CS0_N   @S9S_MB_2U_LIB.S9S_MB_2U(SCH_1):ESPI_LFRAME_N_BMC_CS0_N
  R1479    1      A  Q_RES       I52
  R1961    2      B  Q_RES       I70
  U4     BE20  GPPC_A_6_ESPI_CS0_N  EMMITSBURG_REV0P9  I93

ESPI_LPC_LAD0_IO0   @S9S_MB_2U_LIB.S9S_MB_2U(SCH_1):ESPI_LPC_LAD0_IO0
  J41     B5  +12V_EDGE_B5  SCONN168_623403212  I115
  R1871    2      B  Q_RES       I64

ESPI_LPC_LAD0_IO1   @S9S_MB_2U_LIB.S9S_MB_2U(SCH_1):ESPI_LPC_LAD0_IO1
  J41     B6  +12V_EDGE_B6  SCONN168_623403212  I115
  R1870    2      B  Q_RES       I63

ESPI_LPC_LAD0_IO2   @S9S_MB_2U_LIB.S9S_MB_2U(SCH_1):ESPI_LPC_LAD0_IO2
  J41     B7  BIF0#  SCONN168_623403212  I115
  R1869    2      B  Q_RES       I62

ESPI_LPC_LAD0_IO3   @S9S_MB_2U_LIB.S9S_MB_2U(SCH_1):ESPI_LPC_LAD0_IO3
  J41     B8  BIF1#  SCONN168_623403212  I115
  R1868    2      B  Q_RES       I61

FAN_PDB_PRSNT_N   @S9S_MB_2U_LIB.S9S_MB_2U(SCH_1):FAN_PDB_PRSNT_N
  J44      2      2  CONN24_52SH90245BRD  I125
  R2157    2      B  Q_RES       I171

FB_BMC_ISOLATE   @S9S_MB_2U_LIB.S9S_MB_2U(SCH_1):FB_BMC_ISOLATE
  R1289    1      A  Q_RES       I56
  U66      4      4  74HC1G126GW  I53
  U67      1    1OE  74CBTLV3126PW   I1
  U67      4    2OE  74CBTLV3126PW   I1
  U67     10    3OE  74CBTLV3126PW   I1
  U67     13    4OE  74CBTLV3126PW   I1
  U68      1    1OE  74CBTLV3126PW   I2
  U68      4    2OE  74CBTLV3126PW   I2
  U68     10    3OE  74CBTLV3126PW   I2
  U68     13    4OE  74CBTLV3126PW   I2

FM_ADR_ACK      @S9S_MB_2U_LIB.S9S_MB_2U(SCH_1):FM_ADR_ACK
  R369     2      B  Q_RES       I16
  R700     2      B  Q_RES       I382
  U4     AD4  GPP_D_16_ADR_ACK  EMMITSBURG_REV0P9  I93

FM_ADR_ACK_R    @S9S_MB_2U_LIB.S9S_MB_2U(SCH_1):FM_ADR_ACK_R
  R700     1      A  Q_RES       I382
  U122   L11  DIFFIO_RX_R8N  10M04SAU324I7G  I155

FM_ADR_COMPLETE   @S9S_MB_2U_LIB.S9S_MB_2U(SCH_1):FM_ADR_COMPLETE
  R1341    1      A  Q_RES       I69
  S1       6     B3  SW8S_DHNF04FTVTR   I4
  U4     AC1  GPP_D_13_ADR_COMPLETE  EMMITSBURG_REV0P9  I93
  U122   L15  DIFFIO_RX_R10P  10M04SAU324I7G  I93

FM_ADR_MODE0    @S9S_MB_2U_LIB.S9S_MB_2U(SCH_1):FM_ADR_MODE0
  R773     2      B  Q_RES       I124
  R1455    2      B  Q_RES       I27
  R1809    2      B  Q_RES       I89
  R1810    1      A  Q_RES       I88
  U4     AV11  GPPC_S_3_CPU_GP_1  EMMITSBURG_REV0P9  I27

FM_ADR_MODE0_R   @S9S_MB_2U_LIB.S9S_MB_2U(SCH_1):FM_ADR_MODE0_R
  R1455    1      A  Q_RES       I27
  U122   L12  DIFFIO_RX_R8P  10M04SAU324I7G  I155

FM_ADR_MODE1    @S9S_MB_2U_LIB.S9S_MB_2U(SCH_1):FM_ADR_MODE1
  R269     1      A  Q_RES       I91
  R378     2      B  Q_RES       I77
  R379     1      A  Q_RES       I76
  U4     AL5  GPPC_C_18  EMMITSBURG_REV0P9  I93

FM_ADR_MODE1_R   @S9S_MB_2U_LIB.S9S_MB_2U(SCH_1):FM_ADR_MODE1_R
  R269     2      B  Q_RES       I91
  U122   A17   IO_7  10M04SAU324I7G  I155

FM_ADR_TRIGGER_N   @S9S_MB_2U_LIB.S9S_MB_2U(SCH_1):FM_ADR_TRIGGER_N
  R698     2      B  Q_RES       I32
  R1435    1      A  Q_RES       I221
  U122   L16  DIFFIO_RX_R11P  10M04SAU324I7G  I93

FM_ADR_TRIGGER_R_N   @S9S_MB_2U_LIB.S9S_MB_2U(SCH_1):FM_ADR_TRIGGER_R_N
  R698     1      A  Q_RES       I32
  U4     AH4  GPP_D_14_ADR_TRIGGER_N  EMMITSBURG_REV0P9  I93

FM_AUX_SW_EN    @S9S_MB_2U_LIB.S9S_MB_2U(SCH_1):FM_AUX_SW_EN
  R991     1      A  Q_RES       I20
  U122    C7  DIFFIO_RX_T21N  10M04SAU324I7G  I155

FM_BIOS_ADV_FUNCTIONS   @S9S_MB_2U_LIB.S9S_MB_2U(SCH_1):FM_BIOS_ADV_FUNCTIONS
  R1498    2      B  Q_RES       I76
  R1499    1      A  Q_RES       I77
  U4     AF11  GPP_L_3  EMMITSBURG_REV0P9  I22

FM_BIOS_DEBUG_EN_N   @S9S_MB_2U_LIB.S9S_MB_2U(SCH_1):FM_BIOS_DEBUG_EN_N
  R2147    1      A  Q_RES       I253
  U122    F5  DIFFIO_RX_L5N||ADC1IN5  10M04SAU324I7G  I93

FM_BIOS_DEBUG_EN_R_N   @S9S_MB_2U_LIB.S9S_MB_2U(SCH_1):FM_BIOS_DEBUG_EN_R_N
  R2147    2      B  Q_RES       I253
  U4     AA3  GPP_D_22_USB2_OCB_7  EMMITSBURG_REV0P9  I93

FM_BIOS_IMAGE_SWAP_N   @S9S_MB_2U_LIB.S9S_MB_2U(SCH_1):FM_BIOS_IMAGE_SWAP_N
  R1339    2      B  Q_RES       I81
  S1       5     B4  SW8S_DHNF04FTVTR   I4
  U4      Y4  GPP_D_19_MSMI_N  EMMITSBURG_REV0P9  I93

FM_BIOS_POST_CMPLT_BMC_N   @S9S_MB_2U_LIB.S9S_MB_2U(SCH_1):FM_BIOS_POST_CMPLT_BMC_N
  R1300    2      B  Q_RES        I5
  U122    D9  DIFFIO_RX_T12N  10M04SAU324I7G  I155

FM_BIOS_POST_CMPLT_N   @S9S_MB_2U_LIB.S9S_MB_2U(SCH_1):FM_BIOS_POST_CMPLT_N
  R1300    1      A  Q_RES        I5
  R1449    2      B  Q_RES       I41
  U4     AL3  GPPC_C_17_ME_SML4ALERT_N  EMMITSBURG_REV0P9  I93

FM_BMC_CPU_FBRK_OUT_N   @S9S_MB_2U_LIB.S9S_MB_2U(SCH_1):FM_BMC_CPU_FBRK_OUT_N
  R1381    2      B  Q_RES        I7
  R1845    1      A  Q_RES       I613
  U84     12     A1  GTL2014PW   I18

FM_BMC_CPU_FBRK_OUT_R_N   @S9S_MB_2U_LIB.S9S_MB_2U(SCH_1):FM_BMC_CPU_FBRK_OUT_R_N
  J41    A54  PERP11  SCONN168_623403212  I115
  R1845    2      B  Q_RES       I613

FM_BMC_DBP_PRESENT_R_N   @S9S_MB_2U_LIB.S9S_MB_2U(SCH_1):FM_BMC_DBP_PRESENT_R_N
  R1472    2      B  Q_RES       I144
  U122    A4  DIFFIO_RX_T23P  10M04SAU324I7G  I155

FM_BMC_EN_DET   @S9S_MB_2U_LIB.S9S_MB_2U(SCH_1):FM_BMC_EN_DET
  C1293    1      A  Q_CAP       I95
  R1375    1      A  Q_RES       I97
  U86      2     1A  74CBTLV3126PW  I84
  U86      5     2A  74CBTLV3126PW  I84
  U86      9     3A  74CBTLV3126PW  I84
  U86     12     4A  74CBTLV3126PW  I84
  U87      S  SOURCE  MOSFET_N    I96

FM_BMC_PWRBTN_N   @S9S_MB_2U_LIB.S9S_MB_2U(SCH_1):FM_BMC_PWRBTN_N
  R139     1      A  Q_RES       I249
  R1744    2      B  Q_RES       I94
  U4     AR10  PWRBTN_N  EMMITSBURG_REV0P9  I36

FM_BMC_PWRBTN_OUT_N   @S9S_MB_2U_LIB.S9S_MB_2U(SCH_1):FM_BMC_PWRBTN_OUT_N
  R1744    1      A  Q_RES       I94
  R1815    1      A  Q_RES       I527

FM_BMC_PWRBTN_OUT_R_N   @S9S_MB_2U_LIB.S9S_MB_2U(SCH_1):FM_BMC_PWRBTN_OUT_R_N
  J41    A47  PERN9  SCONN168_623403212  I115
  R1815    2      B  Q_RES       I527

FM_BMC_READY_R_N   @S9S_MB_2U_LIB.S9S_MB_2U(SCH_1):FM_BMC_READY_R_N
  R2155    2      B  Q_RES       I447
  U4     W10  GPP_M_8  EMMITSBURG_REV0P9  I22

FM_BMC_READY_R_PLD_N   @S9S_MB_2U_LIB.S9S_MB_2U(SCH_1):FM_BMC_READY_R_PLD_N
  R2155    1      A  Q_RES       I447
  U122   D13  DIFFIO_RX_T3N  10M04SAU324I7G  I155

FM_BMC_RSTBTN_OUT_N   @S9S_MB_2U_LIB.S9S_MB_2U(SCH_1):FM_BMC_RSTBTN_OUT_N
  R697     1      A  Q_RES       I66
  U122   D10  DIFFIO_RX_T12P  10M04SAU324I7G  I155

FM_BMC_SUSACK_R_N   @S9S_MB_2U_LIB.S9S_MB_2U(SCH_1):FM_BMC_SUSACK_R_N
  R2071    1      A  Q_RES       I327
  U122    K4  DIFFIO_RX_L16N  10M04SAU324I7G  I93

FM_CK440Q_DEV_25M_EN   @S9S_MB_2U_LIB.S9S_MB_2U(SCH_1):FM_CK440Q_DEV_25M_EN
  C1324    1      A  Q_CAP       I286
  R1483    2      B  Q_RES       I265
  R1484    1      A  Q_RES       I268
  R1680    2      B  Q_RES       I252
  U13     A1  25MPG  9SQ440NQQI8  I180

FM_CK440_MXCK_25M_100M   @S9S_MB_2U_LIB.S9S_MB_2U(SCH_1):FM_CK440_MXCK_25M_100M
  R1194    2      B  Q_RES       I277
  R1196    1      A  Q_RES       I281
  U13    B38  MXCK_SEL_100M#  9SQ440NQQI8  I180

FM_CLK_CK440_SS_EN   @S9S_MB_2U_LIB.S9S_MB_2U(SCH_1):FM_CLK_CK440_SS_EN
  R1471    2      B  Q_RES       I267
  R1502    1      A  Q_RES       I270
  U13    A16  SS_EN_TRI  9SQ440NQQI8  I180

FM_CLK_GEN1_OE0_N   @S9S_MB_2U_LIB.S9S_MB_2U(SCH_1):FM_CLK_GEN1_OE0_N
  R1527    1      A  Q_RES       I269
  U13    B27   OE0#  9SQ440NQQI8  I180

FM_COMP_P3V3_AUX_ENIN   @S9S_MB_2U_LIB.S9S_MB_2U(SCH_1):FM_COMP_P3V3_AUX_ENIN
  R1690    2      B  Q_RES        I2
  R1745    1      A  Q_RES       I33
  U94      1   ENIN  ADM1086AKSZREEL7   I1
  U117     1  ENABLE  TPS3897PDRYR  I37

FM_COMP_P3V3_AUX_VIN   @S9S_MB_2U_LIB.S9S_MB_2U(SCH_1):FM_COMP_P3V3_AUX_VIN
  R1688    2      B  Q_RES        I4
  R1689    1      A  Q_RES        I6
  R1950    1      A  Q_RES       I35
  U94      3    VIN  ADM1086AKSZREEL7   I1
  U117     3  SENSE  TPS3897PDRYR  I37

FM_COMP_P3V3_STBY_CEXT   @S9S_MB_2U_LIB.S9S_MB_2U(SCH_1):FM_COMP_P3V3_STBY_CEXT
  C1316    1      A  Q_CAP       I60
  U94      5   CEXT  ADM1086AKSZREEL7   I1
  U117     5     CT  TPS3897PDRYR  I37

FM_CPU0_PKGID0   @S9S_MB_2U_LIB.S9S_MB_2U(SCH_1):FM_CPU0_PKGID0
  R283     2      B  Q_RES       I147
  U2     BL64  PKG_ID0  SOCKET4677_AZIFS054P001C01  I57
  U122   F15  DIFFIO_RX_R27P  10M04SAU324I7G  I93

FM_CPU0_PKGID1   @S9S_MB_2U_LIB.S9S_MB_2U(SCH_1):FM_CPU0_PKGID1
  R284     2      B  Q_RES       I148
  U2     AY63  PKG_ID1  SOCKET4677_AZIFS054P001C01  I57
  U122   F16  DIFFIO_RX_R28N  10M04SAU324I7G  I93

FM_CPU0_PKGID2   @S9S_MB_2U_LIB.S9S_MB_2U(SCH_1):FM_CPU0_PKGID2
  R285     2      B  Q_RES       I150
  U2     BN64  PKG_ID2  SOCKET4677_AZIFS054P001C01  I57
  U122   F18  IO_6||VREFB6N0  10M04SAU324I7G  I139

FM_CPU0_PROC_ID0   @S9S_MB_2U_LIB.S9S_MB_2U(SCH_1):FM_CPU0_PROC_ID0
  R286     2      B  Q_RES       I151
  U2     BG72  PROC_ID0  SOCKET4677_AZIFS054P001C01  I57
  U122   J15  DIFFIO_RX_R22P  10M04SAU324I7G  I93

FM_CPU0_PROC_ID1   @S9S_MB_2U_LIB.S9S_MB_2U(SCH_1):FM_CPU0_PROC_ID1
  R287     2      B  Q_RES       I152
  U2     BH71  PROC_ID1  SOCKET4677_AZIFS054P001C01  I57
  U122   J16  DIFFIO_RX_R23P  10M04SAU324I7G  I93

FM_CPU0_SKTOCC_LVT3_N   @S9S_MB_2U_LIB.S9S_MB_2U(SCH_1):FM_CPU0_SKTOCC_LVT3_N
  R738     1      A  Q_RES       I110
  R1447    1      A  Q_RES       I68
  U2     CG66  SKTOCC_N  SOCKET4677_AZIFS054P001C01   I1

FM_CPU0_SKTOCC_LVT3_PLD_N   @S9S_MB_2U_LIB.S9S_MB_2U(SCH_1):FM_CPU0_SKTOCC_LVT3_PLD_N
  R1447    2      B  Q_RES       I68
  U122   G15  DIFFIO_RX_R27N  10M04SAU324I7G  I93

FM_CPU0_SKTOCC_N   @S9S_MB_2U_LIB.S9S_MB_2U(SCH_1):FM_CPU0_SKTOCC_N
  R738     2      B  Q_RES       I110
  R740     2      B  Q_RES       I107
  U21      6      S  NC7SB3157   I58
  U23      2      A  74LVC1G02GW  I96

FM_CPU1_PKGID0   @S9S_MB_2U_LIB.S9S_MB_2U(SCH_1):FM_CPU1_PKGID0
  R270     2      B  Q_RES       I93
  U1     BL64  PKG_ID0  SOCKET4677_AZIFS054P001C01  I51
  U122   D17  DIFFIO_RX_R34P  10M04SAU324I7G  I155

FM_CPU1_PKGID1   @S9S_MB_2U_LIB.S9S_MB_2U(SCH_1):FM_CPU1_PKGID1
  R271     2      B  Q_RES       I92
  U1     AY63  PKG_ID1  SOCKET4677_AZIFS054P001C01  I51
  U122   D16  DIFFIO_RX_R29N  10M04SAU324I7G  I93

FM_CPU1_PKGID2   @S9S_MB_2U_LIB.S9S_MB_2U(SCH_1):FM_CPU1_PKGID2
  R272     2      B  Q_RES       I90
  U1     BN64  PKG_ID2  SOCKET4677_AZIFS054P001C01  I51
  U122   D15  DIFFIO_RX_R33N  10M04SAU324I7G  I155

FM_CPU1_PROC_ID0   @S9S_MB_2U_LIB.S9S_MB_2U(SCH_1):FM_CPU1_PROC_ID0
  R273     2      B  Q_RES       I89
  U1     BG72  PROC_ID0  SOCKET4677_AZIFS054P001C01  I51
  U122   K17  DIFFIO_RX_R16N||CLK3N  10M04SAU324I7G  I139

FM_CPU1_PROC_ID1   @S9S_MB_2U_LIB.S9S_MB_2U(SCH_1):FM_CPU1_PROC_ID1
  R274     2      B  Q_RES       I88
  U1     BH71  PROC_ID1  SOCKET4677_AZIFS054P001C01  I51
  U122   K18  DIFFIO_RX_R17P  10M04SAU324I7G  I93

FM_CPU1_SKTOCC_LVT3_N   @S9S_MB_2U_LIB.S9S_MB_2U(SCH_1):FM_CPU1_SKTOCC_LVT3_N
  R737     1      A  Q_RES       I106
  R1448    1      A  Q_RES       I62
  U1     CG66  SKTOCC_N  SOCKET4677_AZIFS054P001C01  I29

FM_CPU1_SKTOCC_LVT3_PLD_N   @S9S_MB_2U_LIB.S9S_MB_2U(SCH_1):FM_CPU1_SKTOCC_LVT3_PLD_N
  R1448    2      B  Q_RES       I62
  U122   D18  DIFFIO_RX_R30P  10M04SAU324I7G  I93

FM_CPU1_SKTOCC_N   @S9S_MB_2U_LIB.S9S_MB_2U(SCH_1):FM_CPU1_SKTOCC_N
  R737     2      B  Q_RES       I106
  R739     2      B  Q_RES       I109
  U22      6      S  NC7SB3157   I71
  U23      1      B  74LVC1G02GW  I96

FM_CPU_EN       @S9S_MB_2U_LIB.S9S_MB_2U(SCH_1):FM_CPU_EN
  R745     1      A  Q_RES       I97
  U23      4      Y  74LVC1G02GW  I96

FM_CPU_EN_R     @S9S_MB_2U_LIB.S9S_MB_2U(SCH_1):FM_CPU_EN_R
  R745     2      B  Q_RES       I97
  U16      4     OE  NC7SZ66M5X  I88

FM_CPU_FBRK_DEBUG_N   @S9S_MB_2U_LIB.S9S_MB_2U(SCH_1):FM_CPU_FBRK_DEBUG_N
  C552     1      A  Q_CAP       I96
  J42     38     38  SCONN60_QSH03001LDAKTR  I44
  R779     2      B  Q_RES       I95
  R780     1      A  Q_RES       I92
  R1247    2      B  Q_RES       I14
  U84      3     B1  GTL2014PW   I18

FM_CPU_FBRK_DEBUG_R_N   @S9S_MB_2U_LIB.S9S_MB_2U(SCH_1):FM_CPU_FBRK_DEBUG_R_N
  R780     2      B  Q_RES       I92
  U1     AV57  FBRK_N  SOCKET4677_AZIFS054P001C01  I29
  U2     AV57  FBRK_N  SOCKET4677_AZIFS054P001C01   I1

FM_CPU_RMCA_CATERR_DLY_LVT3_R_N   @S9S_MB_2U_LIB.S9S_MB_2U(SCH_1):FM_CPU_RMCA_CATERR_DLY_LVT3_R_N
  R1456    1      A  Q_RES       I28
  U122   R16  DIFFIO_RX_R2N  10M04SAU324I7G  I93

FM_CPU_RMCA_CATERR_DLY_N   @S9S_MB_2U_LIB.S9S_MB_2U(SCH_1):FM_CPU_RMCA_CATERR_DLY_N
  R1456    2      B  Q_RES       I28
  U4     AF4  GPP_D_18_MEMTRIP_N  EMMITSBURG_REV0P9  I93

FM_CPU_RMCA_CATERR_LVT3_R_N   @S9S_MB_2U_LIB.S9S_MB_2U(SCH_1):FM_CPU_RMCA_CATERR_LVT3_R_N
  R365     1      A  Q_RES       I247
  R1558    1      A  Q_RES       I318
  R1841    2      B  Q_RES       I245
  U122   R15  DIFFIO_RX_R7P  10M04SAU324I7G  I155

FM_DB2000_12_OE_N   @S9S_MB_2U_LIB.S9S_MB_2U(SCH_1):FM_DB2000_12_OE_N
  R1544    2      B  Q_RES       I416
  U38    B10  VOE12#  9QXL2001BNHGI8  I119

FM_DB2000_1_OE_N   @S9S_MB_2U_LIB.S9S_MB_2U(SCH_1):FM_DB2000_1_OE_N
  R576     2      B  Q_RES       I156
  U38    K11  VOE7#  9QXL2001BNHGI8  I119
  U38     L8  VOE5#||DATA  9QXL2001BNHGI8  I119
  U38    L10  VOE6#||CLK  9QXL2001BNHGI8  I119

FM_DB2000_8_OE_N   @S9S_MB_2U_LIB.S9S_MB_2U(SCH_1):FM_DB2000_8_OE_N
  R1543    2      B  Q_RES       I411
  U38    C11  VOE11#  9QXL2001BNHGI8  I119
  U38    E11  VOE10#||SHFT_LD#  9QXL2001BNHGI8  I119
  U38    E12  VOE9#  9QXL2001BNHGI8  I119
  U38    H11  VOE8#  9QXL2001BNHGI8  I119

FM_DB2000_DEV_EN   @S9S_MB_2U_LIB.S9S_MB_2U(SCH_1):FM_DB2000_DEV_EN
  R575     2      B  Q_RES       I199
  U38     M6  VCKPWRGD_PD#  9QXL2001BNHGI8  I119

FM_DB2000_OE_N   @S9S_MB_2U_LIB.S9S_MB_2U(SCH_1):FM_DB2000_OE_N
  R113     2      B  Q_RES       I27
  R576     1      A  Q_RES       I156

FM_DB2000_VSBEN   @S9S_MB_2U_LIB.S9S_MB_2U(SCH_1):FM_DB2000_VSBEN
  R573     2      B  Q_RES       I194
  R574     1      A  Q_RES       I197
  U38     E2  VSBEN  9QXL2001BNHGI8  I119

FM_DIMM_12V_CPS_SX_N   @S9S_MB_2U_LIB.S9S_MB_2U(SCH_1):FM_DIMM_12V_CPS_SX_N
  R735     2      B  Q_RES       I123
  R736     1      A  Q_RES       I125
  U122    E5  DIFFIO_RX_L5P||ADC1IN6  10M04SAU324I7G  I93

FM_DIS_PS_PWROK_DLY   @S9S_MB_2U_LIB.S9S_MB_2U(SCH_1):FM_DIS_PS_PWROK_DLY
  R1492    1      A  Q_RES       I272
  R1494    1      A  Q_RES       I275
  U122   D14  DIFFIO_RX_T1N  10M04SAU324I7G  I155

FM_EDSFF1A_PWRBRK_N   @S9S_MB_2U_LIB.S9S_MB_2U(SCH_1):FM_EDSFF1A_PWRBRK_N
  J62     B8  RFUB8  SCONN84_123318136  I33
  R1965    2      B  Q_RES       I61

FM_EDSFF1A_TYPE_ID   @S9S_MB_2U_LIB.S9S_MB_2U(SCH_1):FM_EDSFF1A_TYPE_ID
  J62     B7    MFG  SCONN84_123318136  I33
  R1963    2      B  Q_RES       I83
  U4     AV24  GPP_E_4_SATA0_XPCIE_2  EMMITSBURG_REV0P9  I22

FM_EDSFF1B_PWRBRK_N   @S9S_MB_2U_LIB.S9S_MB_2U(SCH_1):FM_EDSFF1B_PWRBRK_N
  J87     B8  RFUB8  SCONN84_123318136  I43
  R1975    2      B  Q_RES       I74

FM_EDSFF1B_TYPE_ID   @S9S_MB_2U_LIB.S9S_MB_2U(SCH_1):FM_EDSFF1B_TYPE_ID
  J87     B7    MFG  SCONN84_123318136  I43
  R1973    2      B  Q_RES       I85
  U4     AV28  GPP_E_5_SATA0_XPCIE_3  EMMITSBURG_REV0P9  I22

FM_EDSFF2A_PWRBRK_N   @S9S_MB_2U_LIB.S9S_MB_2U(SCH_1):FM_EDSFF2A_PWRBRK_N
  J33     B8  RFUB8  SCONN84_123318136  I53
  R1585    2      B  Q_RES       I112

FM_EDSFF2A_TYPE_ID   @S9S_MB_2U_LIB.S9S_MB_2U(SCH_1):FM_EDSFF2A_TYPE_ID
  J33     B7    MFG  SCONN84_123318136  I53
  R1609    2      B  Q_RES       I88
  U4     BB24  GPP_E_6_SATA0_USB3_XPCIE_0  EMMITSBURG_REV0P9  I22

FM_EDSFF2B_PWRBRK_N   @S9S_MB_2U_LIB.S9S_MB_2U(SCH_1):FM_EDSFF2B_PWRBRK_N
  J34     B8  RFUB8  SCONN84_123318136  I43
  R1587    2      B  Q_RES       I98

FM_EDSFF2B_TYPE_ID   @S9S_MB_2U_LIB.S9S_MB_2U(SCH_1):FM_EDSFF2B_TYPE_ID
  J34     B7    MFG  SCONN84_123318136  I43
  R1610    2      B  Q_RES       I85
  U4     AW32  GPP_E_7_SATA0_USB3_XPCIE_1  EMMITSBURG_REV0P9  I22

FM_EDSFF3_PWRBRK_N   @S9S_MB_2U_LIB.S9S_MB_2U(SCH_1):FM_EDSFF3_PWRBRK_N
  J35    B14  SIGNAL_B14  SCONN140_G64V3431BHR  I64
  R1589    2      B  Q_RES       I453

FM_EDSFF3_TYPE_ID   @S9S_MB_2U_LIB.S9S_MB_2U(SCH_1):FM_EDSFF3_TYPE_ID
  J35    A17  SIGNAL_A17  SCONN140_G64V3431BHR  I64
  R2180    2      B  Q_RES       I465
  U4     AW36  GPP_E_8_SATA0_SCLOCK_SATA0_LED_N  EMMITSBURG_REV0P9  I22

FM_EDSFF4A_PWRBRK_N   @S9S_MB_2U_LIB.S9S_MB_2U(SCH_1):FM_EDSFF4A_PWRBRK_N
  J88     B8  RFUB8  SCONN84_123318136  I16
  R1985    2      B  Q_RES       I31

FM_EDSFF4A_TYPE_ID   @S9S_MB_2U_LIB.S9S_MB_2U(SCH_1):FM_EDSFF4A_TYPE_ID
  J61     B7    MFG  SCONN84_123318136  I49
  J88     B7    MFG  SCONN84_123318136  I16
  R1983    2      B  Q_RES        I5
  U4     BA29  GPP_E_9_SATA0_SLOAD_SATA0_DEVSLP  EMMITSBURG_REV0P9  I22

FM_EDSFF4B_TYPE_ID   @S9S_MB_2U_LIB.S9S_MB_2U(SCH_1):FM_EDSFF4B_TYPE_ID
  R1993    2      B  Q_RES        I3
  U4     AV31  GPP_E_10_SATA0_SDATAOUT_SATA0_GP  EMMITSBURG_REV0P9  I22

FM_ESPI_CS_SWIZZLE   @S9S_MB_2U_LIB.S9S_MB_2U(SCH_1):FM_ESPI_CS_SWIZZLE
  R609     2      B  Q_RES       I39
  R610     1      A  Q_RES       I40
  U4     BB8  GPPC_S_11  EMMITSBURG_REV0P9  I27

FM_ESPI_FLASH_MODE   @S9S_MB_2U_LIB.S9S_MB_2U(SCH_1):FM_ESPI_FLASH_MODE
  R607     2      B  Q_RES       I21
  R608     1      A  Q_RES       I36
  U4     AG1  GPP_D_7  EMMITSBURG_REV0P9  I93

FM_ESPI_PLD_EN   @S9S_MB_2U_LIB.S9S_MB_2U(SCH_1):FM_ESPI_PLD_EN
  R1748    1      A  Q_RES       I54
  U60      6      S  NC7SB3157   I34
  U61      6      S  NC7SB3157   I39

FM_ESPI_PLD_R_EN   @S9S_MB_2U_LIB.S9S_MB_2U(SCH_1):FM_ESPI_PLD_R_EN
  R1748    2      B  Q_RES       I54
  R1749    1      A  Q_RES       I75
  R1750    2      B  Q_RES       I59
  R2132    2      B  Q_RES       I74
  U122    A5  DIFFIO_RX_T19N  10M04SAU324I7G  I155

FM_EUP_LOT6_N   @S9S_MB_2U_LIB.S9S_MB_2U(SCH_1):FM_EUP_LOT6_N
  R1461    1      A  Q_RES       I80
  U4     AR13  GPPC_S_6_SUSWARN_N_SUSPWRDNACK  EMMITSBURG_REV0P9  I27

FM_FAN_ID       @S9S_MB_2U_LIB.S9S_MB_2U(SCH_1):FM_FAN_ID
  R1645    2      B  Q_RES       I20
  R1646    1      A  Q_RES       I27

FM_FLASH_SECURITY_STRAP   @S9S_MB_2U_LIB.S9S_MB_2U(SCH_1):FM_FLASH_SECURITY_STRAP
  R380     2      B  Q_RES       I78
  R381     1      A  Q_RES       I81
  R1337    1      A  Q_RES       I77
  S2       8     B1  SW8S_DHNF04FTVTR  I35
  U4     AJ1  GPP_D_6  EMMITSBURG_REV0P9  I93

FM_FORCE_PWRON_LVC3   @S9S_MB_2U_LIB.S9S_MB_2U(SCH_1):FM_FORCE_PWRON_LVC3
  R1493    1      A  Q_RES       I287
  R1495    1      A  Q_RES       I286
  U122    B2  DIFFIO_RX_T27N  10M04SAU324I7G  I155

FM_HBM2_HBM3_VPP_SEL   @S9S_MB_2U_LIB.S9S_MB_2U(SCH_1):FM_HBM2_HBM3_VPP_SEL
  U73      G   GATE  MOSFET_N    I50
  U74      G   GATE  MOSFET_N    I50
  U122   C10  DIFFIO_RX_T17P  10M04SAU324I7G  I155

FM_HBM_VPP_SEL_CPU0_D   @S9S_MB_2U_LIB.S9S_MB_2U(SCH_1):FM_HBM_VPP_SEL_CPU0_D
  R2336    2      B  Q_RES       I51
  U73      D  DRAIN  MOSFET_N    I50

FM_HBM_VPP_SEL_CPU1_D   @S9S_MB_2U_LIB.S9S_MB_2U(SCH_1):FM_HBM_VPP_SEL_CPU1_D
  R2381    2      B  Q_RES       I51
  U74      D  DRAIN  MOSFET_N    I50

FM_INTRUDER_HDR_PCH_N   @S9S_MB_2U_LIB.S9S_MB_2U(SCH_1):FM_INTRUDER_HDR_PCH_N
  JP8      2      2  CONN3_HFK1030G000LAF  I86
  R989     1      A  Q_RES       I68
  U4     BG8  INTRUDER_N  EMMITSBURG_REV0P9  I36

FM_JTAG_BMC_MUX_SEL   @S9S_MB_2U_LIB.S9S_MB_2U(SCH_1):FM_JTAG_BMC_MUX_SEL
  R1813    2      B  Q_RES       I79
  R1814    1      A  Q_RES       I77
  R1833    1      A  Q_RES       I611
  R1842    2      B  Q_RES       I115
  U96      7    IN2  TS3A24157RSER  I68
  U96      8    IN1  TS3A24157RSER  I68
  U97      7    IN2  TS3A24157RSER  I38
  U97      8    IN1  TS3A24157RSER  I38

FM_JTAG_BMC_PLD_MUX_SEL   @S9S_MB_2U_LIB.S9S_MB_2U(SCH_1):FM_JTAG_BMC_PLD_MUX_SEL
  R1842    1      A  Q_RES       I115
  U122    A2  DIFFIO_RX_T27P  10M04SAU324I7G  I155

FM_JTAG_EDSFF4_SEL   @S9S_MB_2U_LIB.S9S_MB_2U(SCH_1):FM_JTAG_EDSFF4_SEL
  J61    A10  LED_ACTIVITYA10  SCONN84_123318136  I49
  R2185    1      A  Q_RES       I123

FM_JTAG_ODT_DISABLE   @S9S_MB_2U_LIB.S9S_MB_2U(SCH_1):FM_JTAG_ODT_DISABLE
  R613     2      B  Q_RES       I18
  R614     1      A  Q_RES       I23
  U4     AW10  GPPC_S_10  EMMITSBURG_REV0P9  I27

FM_JTAG_TCK_MUX_SEL   @S9S_MB_2U_LIB.S9S_MB_2U(SCH_1):FM_JTAG_TCK_MUX_SEL
  R1365    1      A  Q_RES       I116
  U85      6      S  NC7SB3157   I109
  U122    A3  DIFFIO_RX_T25P  10M04SAU324I7G  I155

FM_LPC_ESPI_SEL   @S9S_MB_2U_LIB.S9S_MB_2U(SCH_1):FM_LPC_ESPI_SEL
  J41     B9  BIF2#  SCONN168_623403212  I115
  R1763    2      B  Q_RES        I7
  R1764    1      A  Q_RES        I8

FM_LT_KEY_DOWNGRADE_N   @S9S_MB_2U_LIB.S9S_MB_2U(SCH_1):FM_LT_KEY_DOWNGRADE_N
  R619     2      B  Q_RES       I48
  U4      L4  GPPC_H_19  EMMITSBURG_REV0P9  I22

FM_M2_SSD_1_PEDET   @S9S_MB_2U_LIB.S9S_MB_2U(SCH_1):FM_M2_SSD_1_PEDET
  J59     69  PEDET  SCONN75K_APCI0155P004A  I178
  R1396    1      A  Q_RES       I167
  U4     AW23  GPP_E_2_SATA1_XPCIE_2  EMMITSBURG_REV0P9  I22
  U4     BA23  GPP_E_1_SATA1_XPCIE_1  EMMITSBURG_REV0P9  I22
  U4     BA26  GPP_E_0_SATA1_XPCIE_0  EMMITSBURG_REV0P9  I22
  U4     BB21  GPP_E_3_SATA1_XPCIE_3  EMMITSBURG_REV0P9  I22

FM_ME_AUTHN_FAIL   @S9S_MB_2U_LIB.S9S_MB_2U(SCH_1):FM_ME_AUTHN_FAIL
  R1554    2      B  Q_RES       I62
  U4     AW20  GPP_E_15_SATA2_SLOAD_SATA2_GP  EMMITSBURG_REV0P9  I22
  U122   R17  DIFFIO_RX_R9N  10M04SAU324I7G  I155

FM_ME_BT_DONE   @S9S_MB_2U_LIB.S9S_MB_2U(SCH_1):FM_ME_BT_DONE
  R71      2      B  Q_RES       I60
  U4     AW29  GPP_E_16_SATA2_SDATAOUT_SATA2_DEVSLP  EMMITSBURG_REV0P9  I22
  U122   R18  DIFFIO_RX_R12P  10M04SAU324I7G  I93

FM_ME_RCVR_N    @S9S_MB_2U_LIB.S9S_MB_2U(SCH_1):FM_ME_RCVR_N
  R1342    2      B  Q_RES       I45
  S2       6     B3  SW8S_DHNF04FTVTR  I35
  U4     AG7  GPP_L_4  EMMITSBURG_REV0P9  I22

FM_MFG_MODE     @S9S_MB_2U_LIB.S9S_MB_2U(SCH_1):FM_MFG_MODE
  R1298    2      B  Q_RES       I22
  R1299    1      A  Q_RES       I21
  U4     AG10  GPP_L_6  EMMITSBURG_REV0P9  I22

FM_OCP_SFF_PWR_GOOD   @S9S_MB_2U_LIB.S9S_MB_2U(SCH_1):FM_OCP_SFF_PWR_GOOD
  J37    OCP_B1  NIC_PWR_GOOD  SCONN168_623403212  I86
  R413     2      B  Q_RES       I362
  R1606    1      A  Q_RES       I183
  U66      2      2  74HC1G126GW  I53

FM_OCP_SFF_PWR_GOOD_R   @S9S_MB_2U_LIB.S9S_MB_2U(SCH_1):FM_OCP_SFF_PWR_GOOD_R
  R1606    2      B  Q_RES       I183
  U122    J3  IO_1B||VREFB1N0  10M04SAU324I7G  I139

FM_OV_ADR_TRIGGER_N   @S9S_MB_2U_LIB.S9S_MB_2U(SCH_1):FM_OV_ADR_TRIGGER_N
  J44      9      9  CONN24_52SH90245BRD  I125
  R473     2      B  Q_RES       I204

FM_P12V_E1S_0_EN   @S9S_MB_2U_LIB.S9S_MB_2U(SCH_1):FM_P12V_E1S_0_EN
  R2036    2      B  Q_RES       I95
  R2160    2      B  Q_RES       I187
  U126     2  EN||UVLO  TPS259540DSGR  I156

FM_P12V_E1S_1_EN   @S9S_MB_2U_LIB.S9S_MB_2U(SCH_1):FM_P12V_E1S_1_EN
  R2042    2      B  Q_RES       I107
  R2161    2      B  Q_RES       I193
  U128     2  EN||UVLO  TPS259540DSGR  I157

FM_P12V_E1S_2_EN   @S9S_MB_2U_LIB.S9S_MB_2U(SCH_1):FM_P12V_E1S_2_EN
  R2037    2      B  Q_RES       I130
  R2159    2      B  Q_RES       I189
  U127     2  EN||UVLO  TPS259540DSGR  I159

FM_P12V_E1S_3_EN   @S9S_MB_2U_LIB.S9S_MB_2U(SCH_1):FM_P12V_E1S_3_EN
  R2043    2      B  Q_RES       I147
  R2162    2      B  Q_RES       I191
  U129     2  EN||UVLO  TPS259540DSGR  I158

FM_P1V05_PCH_AUX_EN   @S9S_MB_2U_LIB.S9S_MB_2U(SCH_1):FM_P1V05_PCH_AUX_EN
  PR1389    1      A  Q_RES       I25
  U122    C9  DIFFIO_RX_T17N  10M04SAU324I7G  I155

FM_P1V05_PCH_AUX_R_EN   @S9S_MB_2U_LIB.S9S_MB_2U(SCH_1):FM_P1V05_PCH_AUX_R_EN
  C1286    1      A  Q_CAP       I30
  PR1388    2      B  Q_RES       I26
  PR1389    2      B  Q_RES       I25
  PR1647    2      B  Q_RES       I27
  PU73     8     EN  MPQ8633BGLEC838Z  I34
  R1649    1      A  Q_RES       I31

FM_P3V3_E1S_0_EN   @S9S_MB_2U_LIB.S9S_MB_2U(SCH_1):FM_P3V3_E1S_0_EN
  R2014    2      B  Q_RES       I36
  R2164    2      B  Q_RES       I70
  U40      2  EN||UVLO  TPS259520DSGR  I42

FM_P3V3_E1S_1_EN   @S9S_MB_2U_LIB.S9S_MB_2U(SCH_1):FM_P3V3_E1S_1_EN
  R2018    2      B  Q_RES       I55
  R2165    2      B  Q_RES       I74
  U124     2  EN||UVLO  TPS259520DSGR  I59

FM_P3V3_E1S_2_EN   @S9S_MB_2U_LIB.S9S_MB_2U(SCH_1):FM_P3V3_E1S_2_EN
  R2015    2      B  Q_RES        I2
  R2163    2      B  Q_RES       I72
  U123     2  EN||UVLO  TPS259520DSGR   I8

FM_P3V3_E1S_3_EN   @S9S_MB_2U_LIB.S9S_MB_2U(SCH_1):FM_P3V3_E1S_3_EN
  R2019    2      B  Q_RES       I21
  R2166    2      B  Q_RES       I76
  U125     2  EN||UVLO  TPS259520DSGR  I25

FM_P5V_EN       @S9S_MB_2U_LIB.S9S_MB_2U(SCH_1):FM_P5V_EN
  R1640    1      A  Q_RES       I84
  U122    C6  DIFFIO_RX_T20P  10M04SAU324I7G  I155

FM_PASSWORD_CLEAR_N   @S9S_MB_2U_LIB.S9S_MB_2U(SCH_1):FM_PASSWORD_CLEAR_N
  R1343    2      B  Q_RES       I44
  S2       5     B4  SW8S_DHNF04FTVTR  I35
  U4     AB8  GPP_L_5  EMMITSBURG_REV0P9  I22

FM_PCHHOT_N     @S9S_MB_2U_LIB.S9S_MB_2U(SCH_1):FM_PCHHOT_N
  R474     1      A  Q_RES       I213
  R1955    2      B  Q_RES       I72
  U4     AH2  GPP_D_12_PCHHOT_N  EMMITSBURG_REV0P9  I93

FM_PCHHOT_R_N   @S9S_MB_2U_LIB.S9S_MB_2U(SCH_1):FM_PCHHOT_R_N
  R474     2      B  Q_RES       I213
  U122    B8  DIFFIO_RX_T16N||DEV_CLRN  10M04SAU324I7G  I139

FM_PCH_BIOS_RCVR_MODE   @S9S_MB_2U_LIB.S9S_MB_2U(SCH_1):FM_PCH_BIOS_RCVR_MODE
  R1338    1      A  Q_RES       I29
  S1       7     B2  SW8S_DHNF04FTVTR   I4
  U4      R7  GPP_M_11  EMMITSBURG_REV0P9  I22

FM_PCH_BMC_THERMTRIP_N   @S9S_MB_2U_LIB.S9S_MB_2U(SCH_1):FM_PCH_BMC_THERMTRIP_N
  R1263    2      B  Q_RES       I29
  U122   U18  DIFFIO_RX_R4P  10M04SAU324I7G  I155

FM_PCH_BOOT_BIOS_STRAP   @S9S_MB_2U_LIB.S9S_MB_2U(SCH_1):FM_PCH_BOOT_BIOS_STRAP
  R371     2      B  Q_RES       I45
  R372     1      A  Q_RES       I46
  U4      W1  GPP_D_23  EMMITSBURG_REV0P9  I93

FM_PCH_CONSENT_STRAP_N   @S9S_MB_2U_LIB.S9S_MB_2U(SCH_1):FM_PCH_CONSENT_STRAP_N
  R502     2      B  Q_RES       I68
  R771     2      B  Q_RES       I120
  R1962    1      A  Q_RES       I90
  U4     AT18  GPPC_S_5_CPU_GP_3  EMMITSBURG_REV0P9  I27

FM_PCH_CPU_PWR_DEBUG_N   @S9S_MB_2U_LIB.S9S_MB_2U(SCH_1):FM_PCH_CPU_PWR_DEBUG_N
  R1247    1      A  Q_RES       I14
  U4      F5  CPU_PWR_DEBUG_N  EMMITSBURG_REV0P9  I36

FM_PCH_CRASHLOG_TRIG_N   @S9S_MB_2U_LIB.S9S_MB_2U(SCH_1):FM_PCH_CRASHLOG_TRIG_N
  R699     2      B  Q_RES       I102
  U4     AE3  GPP_D_8_CRASHLOG_TRIG_N  EMMITSBURG_REV0P9  I93

FM_PCH_CRASHLOG_TRIG_R_N   @S9S_MB_2U_LIB.S9S_MB_2U(SCH_1):FM_PCH_CRASHLOG_TRIG_R_N
  R699     1      A  Q_RES       I102
  U122   E14  DIFFIO_RX_T1P  10M04SAU324I7G  I155

FM_PCH_DFXTESTMODE   @S9S_MB_2U_LIB.S9S_MB_2U(SCH_1):FM_PCH_DFXTESTMODE
  R1496    2      B  Q_RES       I71
  R1497    1      A  Q_RES       I70
  U4      P3  GPP_I_22  EMMITSBURG_REV0P9  I22

FM_PCH_EXTERNALCLKMODE   @S9S_MB_2U_LIB.S9S_MB_2U(SCH_1):FM_PCH_EXTERNALCLKMODE
  R611     2      B  Q_RES       I43
  R612     1      A  Q_RES       I44
  U4      L2  GPPC_H_6  EMMITSBURG_REV0P9  I22

FM_PCH_GLB_RST_WARN_N   @S9S_MB_2U_LIB.S9S_MB_2U(SCH_1):FM_PCH_GLB_RST_WARN_N
  R1258    2      B  Q_RES        I6
  R1313    1      A  Q_RES       I21
  U4     AA1  GPP_D_21_GLB_RST_WARN_N  EMMITSBURG_REV0P9  I93

FM_PCH_IO_EXPANDER   @S9S_MB_2U_LIB.S9S_MB_2U(SCH_1):FM_PCH_IO_EXPANDER
  R617     2      B  Q_RES       I54
  R618     1      A  Q_RES       I53
  U4      K1  GPPC_H_1  EMMITSBURG_REV0P9  I22

FM_PCH_MCRO_LDO   @S9S_MB_2U_LIB.S9S_MB_2U(SCH_1):FM_PCH_MCRO_LDO
  R1220    2      B  Q_RES       I63
  R1221    1      A  Q_RES       I64
  U4      K3  GPPC_H_7  EMMITSBURG_REV0P9  I22

FM_PCH_P1V8_AUX_EN   @S9S_MB_2U_LIB.S9S_MB_2U(SCH_1):FM_PCH_P1V8_AUX_EN
  PR411    1      A  Q_RES       I16
  R1404    1      A  Q_RES       I25
  U122    C8  DIFFIO_RX_T21P  10M04SAU324I7G  I155

FM_PCH_P1V8_AUX_EN_R   @S9S_MB_2U_LIB.S9S_MB_2U(SCH_1):FM_PCH_P1V8_AUX_EN_R
  PR411    2      B  Q_RES       I16
  PR412    2      B  Q_RES       I15
  PU74     5     EN  NB695GDZ    I20
  R1850    2      B  Q_RES       I17

FM_PCH_PLD_GLB_RST_WARN_N   @S9S_MB_2U_LIB.S9S_MB_2U(SCH_1):FM_PCH_PLD_GLB_RST_WARN_N
  R1313    2      B  Q_RES       I21
  U122    J4  IO_1B  10M04SAU324I7G  I155

FM_PCH_PRSNT_N   @S9S_MB_2U_LIB.S9S_MB_2U(SCH_1):FM_PCH_PRSNT_N
  R498     2      B  Q_RES       I24
  U4     A41  VSS_A41  EMMITSBURG_REV0P9  I27
  U122   G11  DIFFIO_RX_R31P  10M04SAU324I7G  I93

FM_PCH_RING_OSC_BYPASS_MGPIO_TE   @S9S_MB_2U_LIB.S9S_MB_2U(SCH_1):FM_PCH_RING_OSC_BYPASS_MGPIO_TEST2
  R1475    2      B  Q_RES       I44
  R1476    1      A  Q_RES       I43
  U4      G2  GPPC_H_16_FLEX_CLK_OUT_1  EMMITSBURG_REV0P9  I22

FM_PCH_SATA_RAID_KEY   @S9S_MB_2U_LIB.S9S_MB_2U(SCH_1):FM_PCH_SATA_RAID_KEY
  R1271    2      B  Q_RES        I5
  R1487    1      A  Q_RES       I125
  U4     BD11  GPPC_A_16_SRCCLKREQ_N_6  EMMITSBURG_REV0P9  I93

FM_PCH_SKIP_RTC_CLOCK   @S9S_MB_2U_LIB.S9S_MB_2U(SCH_1):FM_PCH_SKIP_RTC_CLOCK
  R621     2      B  Q_RES       I55
  R622     1      A  Q_RES       I56
  U4     AU10  GPP_O_7  EMMITSBURG_REV0P9  I36

FM_PCH_SLP_S3_N   @S9S_MB_2U_LIB.S9S_MB_2U(SCH_1):FM_PCH_SLP_S3_N
  R1995    1      A  Q_RES       I86
  U4     AP8  SLP_S3_N  EMMITSBURG_REV0P9  I36

FM_PCH_SLP_S4_N   @S9S_MB_2U_LIB.S9S_MB_2U(SCH_1):FM_PCH_SLP_S4_N
  R1996    1      A  Q_RES       I87
  U4     AL13  SLP_S4_N  EMMITSBURG_REV0P9  I36

FM_PCH_SLP_SUS_N   @S9S_MB_2U_LIB.S9S_MB_2U(SCH_1):FM_PCH_SLP_SUS_N
  R1736    1      A  Q_RES       I89
  U4     AL7  SLP_SUS_N  EMMITSBURG_REV0P9  I36

FM_PCH_SPARE0   @S9S_MB_2U_LIB.S9S_MB_2U(SCH_1):FM_PCH_SPARE0
  R1222    2      B  Q_RES       I57
  U4     AN10  GPP_O_0  EMMITSBURG_REV0P9  I36

FM_PCH_TRIGGER0_N   @S9S_MB_2U_LIB.S9S_MB_2U(SCH_1):FM_PCH_TRIGGER0_N
  R20      2      B  Q_RES       I31
  R1200    1      A  Q_RES       I60

FM_PCH_TRIGGER0_R_N   @S9S_MB_2U_LIB.S9S_MB_2U(SCH_1):FM_PCH_TRIGGER0_R_N
  R1200    2      B  Q_RES       I60
  R1485    2      B  Q_RES       I75
  U4     H11  TRIGGER0_N  EMMITSBURG_REV0P9  I36

FM_PCH_TRIGGER1_N   @S9S_MB_2U_LIB.S9S_MB_2U(SCH_1):FM_PCH_TRIGGER1_N
  R21      2      B  Q_RES       I32
  R1201    1      A  Q_RES       I58

FM_PCH_TRIGGER1_R_N   @S9S_MB_2U_LIB.S9S_MB_2U(SCH_1):FM_PCH_TRIGGER1_R_N
  R1201    2      B  Q_RES       I58
  R1486    2      B  Q_RES       I74
  U4      K8  TRIGGER1_N  EMMITSBURG_REV0P9  I36

FM_PCH_VISA_DEFAULT   @S9S_MB_2U_LIB.S9S_MB_2U(SCH_1):FM_PCH_VISA_DEFAULT
  R615     2      B  Q_RES       I51
  U4      G4  GPPC_H_0  EMMITSBURG_REV0P9  I22

FM_PCH_XTALSEL   @S9S_MB_2U_LIB.S9S_MB_2U(SCH_1):FM_PCH_XTALSEL
  R623     2      B  Q_RES       I13
  R624     1      A  Q_RES       I14
  U4      R4  GPP_I_23  EMMITSBURG_REV0P9  I22

FM_PCH_XTAL_INPUT_MODE_MGPIO_TE   @S9S_MB_2U_LIB.S9S_MB_2U(SCH_1):FM_PCH_XTAL_INPUT_MODE_MGPIO_TEST3
  R1477    2      B  Q_RES       I47
  R1478    1      A  Q_RES       I50
  U4      H3  GPPC_H_17_FLEX_CLK_OUT_2  EMMITSBURG_REV0P9  I22

FM_PCIE_EDSFF1A_PRSNT_1_N   @S9S_MB_2U_LIB.S9S_MB_2U(SCH_1):FM_PCIE_EDSFF1A_PRSNT_1_N
  J62    B42  PRSNT1_N  SCONN84_123318136  I33
  R1968    1      A  Q_RES       I86
  U4      U7  GPP_M_12  EMMITSBURG_REV0P9  I22

FM_PCIE_EDSFF1B_PRSNT_1_N   @S9S_MB_2U_LIB.S9S_MB_2U(SCH_1):FM_PCIE_EDSFF1B_PRSNT_1_N
  J87    B42  PRSNT1_N  SCONN84_123318136  I43
  R1978    1      A  Q_RES       I88
  U4     AC10  GPP_L_2  EMMITSBURG_REV0P9  I22

FM_PCIE_EDSFF2A_PRSNT_1_N   @S9S_MB_2U_LIB.S9S_MB_2U(SCH_1):FM_PCIE_EDSFF2A_PRSNT_1_N
  J33    B42  PRSNT1_N  SCONN84_123318136  I53
  R394     1      A  Q_RES       I71
  U4      T8  GPP_M_15  EMMITSBURG_REV0P9  I22

FM_PCIE_EDSFF2B_PRSNT_1_N   @S9S_MB_2U_LIB.S9S_MB_2U(SCH_1):FM_PCIE_EDSFF2B_PRSNT_1_N
  J34    B42  PRSNT1_N  SCONN84_123318136  I43
  R398     1      A  Q_RES       I71
  U4     AC7  GPP_L_7  EMMITSBURG_REV0P9  I22

FM_PCIE_EDSFF3_PRSNT_1_N   @S9S_MB_2U_LIB.S9S_MB_2U(SCH_1):FM_PCIE_EDSFF3_PRSNT_1_N
  J35    B42  GND_B42  SCONN140_G64V3431BHR  I64
  R402     1      A  Q_RES       I204
  R2148    1      A  Q_RES       I337
  U4     N10  GPP_M_16  EMMITSBURG_REV0P9  I22

FM_PCIE_EDSFF4A_PRSNT_1_N   @S9S_MB_2U_LIB.S9S_MB_2U(SCH_1):FM_PCIE_EDSFF4A_PRSNT_1_N
  J88    B42  PRSNT1_N  SCONN84_123318136  I16
  R1988    1      A  Q_RES       I11
  U4     W13  GPP_M_17  EMMITSBURG_REV0P9  I22

FM_PCIE_EDSFF4B_PRSNT_1_N   @S9S_MB_2U_LIB.S9S_MB_2U(SCH_1):FM_PCIE_EDSFF4B_PRSNT_1_N
  J61    B42  PRSNT1_N  SCONN84_123318136  I49
  R2000    1      A  Q_RES       I11
  U4     AE10  GPP_L_8  EMMITSBURG_REV0P9  I22

FM_PCIE_EV_BIF_EN   @S9S_MB_2U_LIB.S9S_MB_2U(SCH_1):FM_PCIE_EV_BIF_EN
  R1675    1      A  Q_RES       I82
  R1676    1      A  Q_RES       I94
  U4      F8  CPU_CATERR_N  EMMITSBURG_REV0P9  I36

FM_PEHPCPU0_ALERT_N   @S9S_MB_2U_LIB.S9S_MB_2U(SCH_1):FM_PEHPCPU0_ALERT_N
  Q15      3     D2  MOSFET_NCH_DUAL   I9
  R1006    2      B  Q_RES        I8
  U2     BV26  CXPSMBUS_ALERT_N  SOCKET4677_AZIFS054P001C01   I1

FM_PEHPCPU1_ALERT_N   @S9S_MB_2U_LIB.S9S_MB_2U(SCH_1):FM_PEHPCPU1_ALERT_N
  Q16      3     D2  MOSFET_NCH_DUAL  I66
  R1007    2      B  Q_RES       I12
  U1     BV26  CXPSMBUS_ALERT_N  SOCKET4677_AZIFS054P001C01  I29

FM_PFR_DSW_PWROK_N   @S9S_MB_2U_LIB.S9S_MB_2U(SCH_1):FM_PFR_DSW_PWROK_N
  R1399    1      A  Q_RES       I269
  R1745    2      B  Q_RES       I33
  U122   T16  DIFFIO_RX_R2P  10M04SAU324I7G  I93

FM_PLD_CLKS_DEV_EN   @S9S_MB_2U_LIB.S9S_MB_2U(SCH_1):FM_PLD_CLKS_DEV_EN
  R106     2      B  Q_RES       I304
  R110     2      B  Q_RES       I17
  R575     1      A  Q_RES       I199
  R1305    2      B  Q_RES       I272
  R1390    1      A  Q_RES       I275
  U13    A17  PWRGD||PWRDN#  9SQ440NQQI8  I180
  U70      G   GATE  MOSFET_N    I19

FM_PLD_CLKS_DEV_R_EN   @S9S_MB_2U_LIB.S9S_MB_2U(SCH_1):FM_PLD_CLKS_DEV_R_EN
  R110     1      A  Q_RES       I17
  U122    A8  DIFFIO_RX_T15N  10M04SAU324I7G  I155

FM_PLD_CLKS_OE_R_N   @S9S_MB_2U_LIB.S9S_MB_2U(SCH_1):FM_PLD_CLKS_OE_R_N
  R111     2      B  Q_RES       I24
  R113     1      A  Q_RES       I27
  U70      D  DRAIN  MOSFET_N    I19

FM_PLD_CLK_25M_EN   @S9S_MB_2U_LIB.S9S_MB_2U(SCH_1):FM_PLD_CLK_25M_EN
  R109     2      B  Q_RES       I44
  R1680    1      A  Q_RES       I252

FM_PLD_CLK_25M_R_EN   @S9S_MB_2U_LIB.S9S_MB_2U(SCH_1):FM_PLD_CLK_25M_R_EN
  R109     1      A  Q_RES       I44
  R990     1      A  Q_RES       I18
  U122    A9  DIFFIO_RX_T15P  10M04SAU324I7G  I155

FM_PLD_HEARTBEAT_LVC3   @S9S_MB_2U_LIB.S9S_MB_2U(SCH_1):FM_PLD_HEARTBEAT_LVC3
  R1437    1      A  Q_RES       I224
  U89      G   GATE  MOSFET_N    I236
  U122    D5  DIFFIO_RX_T26N  10M04SAU324I7G  I155

FM_PLD_HEARTBEAT_LVC3_D   @S9S_MB_2U_LIB.S9S_MB_2U(SCH_1):FM_PLD_HEARTBEAT_LVC3_D
  D0       C      C  Q_LED       I239
  U89      D  DRAIN  MOSFET_N    I236

FM_PLD_REV_N    @S9S_MB_2U_LIB.S9S_MB_2U(SCH_1):FM_PLD_REV_N
  C1325    1      A  Q_CAP       I412
  R1710    2      B  Q_RES       I414
  U122    D6  DIFFIO_RX_T26P  10M04SAU324I7G  I155

FM_PLD_REV_R_N   @S9S_MB_2U_LIB.S9S_MB_2U(SCH_1):FM_PLD_REV_R_N
  R1106    2      B  Q_RES       I415
  R1710    1      A  Q_RES       I414

FM_PLT_BMC_THERMTRIP_R_N   @S9S_MB_2U_LIB.S9S_MB_2U(SCH_1):FM_PLT_BMC_THERMTRIP_R_N
  R1263    1      A  Q_RES       I29
  R1820    2      B  Q_RES       I35
  U4      Y2  GPP_D_17_THERMTRIP_N  EMMITSBURG_REV0P9  I93

FM_PMBUS_ALERT_B_EN   @S9S_MB_2U_LIB.S9S_MB_2U(SCH_1):FM_PMBUS_ALERT_B_EN
  R1659    1      A  Q_RES       I181
  U4     AV3  GPPC_C_11_ME_SML2ALERT_N  EMMITSBURG_REV0P9  I93

FM_PSU_THROTTLE_L   @S9S_MB_2U_LIB.S9S_MB_2U(SCH_1):FM_PSU_THROTTLE_L
  L12      2      2  Q_INDUCTOR  I57
  R1539    1      A  Q_RES       I37
  U19      G   GATE  MOSFET_N    I34

FM_PSU_THROTTLE_N   @S9S_MB_2U_LIB.S9S_MB_2U(SCH_1):FM_PSU_THROTTLE_N
  R1540    2      B  Q_RES       I33
  U19      D  DRAIN  MOSFET_N    I34
  U122    G1  DIFFIO_RX_L8P||ADC1IN10  10M04SAU324I7G  I93

FM_PS_EN_PLD_R   @S9S_MB_2U_LIB.S9S_MB_2U(SCH_1):FM_PS_EN_PLD_R
  R1607    1      A  Q_RES       I85
  U122   N18  DIFFIO_RX_R13P  10M04SAU324I7G  I93

FM_PS_PWROK_DLY_R_SEL   @S9S_MB_2U_LIB.S9S_MB_2U(SCH_1):FM_PS_PWROK_DLY_R_SEL
  R8       2      B  Q_RES       I59
  R1306    1      A  Q_RES       I13
  U4     BA20  GPP_E_18_ERR1_N  EMMITSBURG_REV0P9  I22

FM_PS_PWROK_DLY_SEL   @S9S_MB_2U_LIB.S9S_MB_2U(SCH_1):FM_PS_PWROK_DLY_SEL
  R1306    2      B  Q_RES       I13
  U122   A10  DIFFIO_RX_T13N  10M04SAU324I7G  I155

FM_PVCCD_HV_CPU0_EN   @S9S_MB_2U_LIB.S9S_MB_2U(SCH_1):FM_PVCCD_HV_CPU0_EN
  PR363    1      A  Q_RES       I40
  R1413    1      A  Q_RES       I59
  U122   A14  DIFFIO_RX_T5N  10M04SAU324I7G  I155

FM_PVCCD_HV_CPU1_EN   @S9S_MB_2U_LIB.S9S_MB_2U(SCH_1):FM_PVCCD_HV_CPU1_EN
  PR208    1      A  Q_RES       I230
  R1414    1      A  Q_RES       I58
  U122   C14  DIFFIO_RX_T6P  10M04SAU324I7G  I155

FM_PVCCFA_EHV_CPU0_EN   @S9S_MB_2U_LIB.S9S_MB_2U(SCH_1):FM_PVCCFA_EHV_CPU0_EN
  PR119    1      A  Q_RES       I32
  R982     2      B  Q_RES       I10

FM_PVCCFA_EHV_CPU0_R_EN   @S9S_MB_2U_LIB.S9S_MB_2U(SCH_1):FM_PVCCFA_EHV_CPU0_R_EN
  R982     1      A  Q_RES       I10
  R1409    1      A  Q_RES       I55
  U122   A13  DIFFIO_RX_T11P  10M04SAU324I7G  I155

FM_PVCCFA_EHV_CPU1_EN   @S9S_MB_2U_LIB.S9S_MB_2U(SCH_1):FM_PVCCFA_EHV_CPU1_EN
  PR272    1      A  Q_RES       I18
  R986     2      B  Q_RES       I25

FM_PVCCFA_EHV_CPU1_R_EN   @S9S_MB_2U_LIB.S9S_MB_2U(SCH_1):FM_PVCCFA_EHV_CPU1_R_EN
  R986     1      A  Q_RES       I25
  R1410    1      A  Q_RES       I54
  U122   C13  DIFFIO_RX_T6N  10M04SAU324I7G  I155

FM_PVCCFA_EHV_FIVRA_CPU0_EN   @S9S_MB_2U_LIB.S9S_MB_2U(SCH_1):FM_PVCCFA_EHV_FIVRA_CPU0_EN
  PR337    1      A  Q_RES       I41
  R984     2      B  Q_RES       I15

FM_PVCCFA_EHV_FIVRA_CPU0_R_EN   @S9S_MB_2U_LIB.S9S_MB_2U(SCH_1):FM_PVCCFA_EHV_FIVRA_CPU0_R_EN
  R984     1      A  Q_RES       I15
  R1411    1      A  Q_RES       I56
  U122   A15  DIFFIO_RX_T5P  10M04SAU324I7G  I155

FM_PVCCFA_EHV_FIVRA_CPU1_EN   @S9S_MB_2U_LIB.S9S_MB_2U(SCH_1):FM_PVCCFA_EHV_FIVRA_CPU1_EN
  PR234    1      A  Q_RES       I204
  R988     2      B  Q_RES       I23

FM_PVCCFA_EHV_FIVRA_CPU1_R_EN   @S9S_MB_2U_LIB.S9S_MB_2U(SCH_1):FM_PVCCFA_EHV_FIVRA_CPU1_R_EN
  R988     1      A  Q_RES       I23
  R1412    1      A  Q_RES       I57
  U122   C15  DIFFIO_RX_T4N  10M04SAU324I7G  I155

FM_PVCCINFAON_CPU0_EN   @S9S_MB_2U_LIB.S9S_MB_2U(SCH_1):FM_PVCCINFAON_CPU0_EN
  PR111    1      A  Q_RES       I64
  R983     2      B  Q_RES       I13

FM_PVCCINFAON_CPU0_R_EN   @S9S_MB_2U_LIB.S9S_MB_2U(SCH_1):FM_PVCCINFAON_CPU0_R_EN
  R983     1      A  Q_RES       I13
  R1407    1      A  Q_RES       I52
  U122   A12  DIFFIO_RX_T11N  10M04SAU324I7G  I155

FM_PVCCINFAON_CPU1_EN   @S9S_MB_2U_LIB.S9S_MB_2U(SCH_1):FM_PVCCINFAON_CPU1_EN
  PR264    1      A  Q_RES       I51
  R987     2      B  Q_RES       I24

FM_PVCCINFAON_CPU1_R_EN   @S9S_MB_2U_LIB.S9S_MB_2U(SCH_1):FM_PVCCINFAON_CPU1_R_EN
  R987     1      A  Q_RES       I24
  R1408    1      A  Q_RES       I53
  U122   C12  DIFFIO_RX_T9P  10M04SAU324I7G  I155

FM_PVCCIN_CPU0_EN   @S9S_MB_2U_LIB.S9S_MB_2U(SCH_1):FM_PVCCIN_CPU0_EN
  PR162    1      A  Q_RES       I69
  R981     2      B  Q_RES        I9

FM_PVCCIN_CPU0_R_EN   @S9S_MB_2U_LIB.S9S_MB_2U(SCH_1):FM_PVCCIN_CPU0_R_EN
  R981     1      A  Q_RES        I9
  R1405    1      A  Q_RES       I26
  U122   A11  DIFFIO_RX_T13P  10M04SAU324I7G  I155

FM_PVCCIN_CPU1_EN   @S9S_MB_2U_LIB.S9S_MB_2U(SCH_1):FM_PVCCIN_CPU1_EN
  PR309    1      A  Q_RES       I196
  R985     2      B  Q_RES       I21

FM_PVCCIN_CPU1_R_EN   @S9S_MB_2U_LIB.S9S_MB_2U(SCH_1):FM_PVCCIN_CPU1_R_EN
  R985     1      A  Q_RES       I21
  R1406    1      A  Q_RES       I51
  U122   C11  DIFFIO_RX_T10P  10M04SAU324I7G  I155

FM_PVNN_MAIN_CPU0_EN   @S9S_MB_2U_LIB.S9S_MB_2U(SCH_1):FM_PVNN_MAIN_CPU0_EN
  C1307    1      A  Q_CAP       I154
  PU81     5     EN  MPQ8626GDZ  I190
  R1445    1      A  Q_RES       I155
  R2338    2      B  Q_RES       I156
  U122   A16  IO_7||VREFB7N0  10M04SAU324I7G  I139

FM_PVNN_MAIN_CPU1_EN   @S9S_MB_2U_LIB.S9S_MB_2U(SCH_1):FM_PVNN_MAIN_CPU1_EN
  C1308    1      A  Q_CAP       I166
  PU82     5     EN  MPQ8626GDZ  I198
  R2384    2      B  Q_RES       I161
  R2385    1      A  Q_RES       I168
  U122   C16  DIFFIO_RX_T4P  10M04SAU324I7G  I155

FM_PVPP_HBM_CPU0_EN   @S9S_MB_2U_LIB.S9S_MB_2U(SCH_1):FM_PVPP_HBM_CPU0_EN
  C1300    1      A  Q_CAP       I14
  PU79     8     EN  MPQ8633AGLEC807Z  I13
  R2330    2      B  Q_RES        I7
  R2332    1      A  Q_RES       I16
  U122    C4  DIFFIO_RX_T22N||CRC_ERROR  10M04SAU324I7G  I139

FM_PVPP_HBM_CPU1_EN   @S9S_MB_2U_LIB.S9S_MB_2U(SCH_1):FM_PVPP_HBM_CPU1_EN
  C2445    1      A  Q_CAP       I11
  PU80     8     EN  MPQ8633AGLEC807Z  I15
  R2367    2      B  Q_RES       I18
  R2374    1      A  Q_RES       I12
  U122    C5  DIFFIO_RX_T22P  10M04SAU324I7G  I155

FM_REMOTE_DEBUG_DET_R   @S9S_MB_2U_LIB.S9S_MB_2U(SCH_1):FM_REMOTE_DEBUG_DET_R
  R1370    2      B  Q_RES       I98
  R1372    1      A  Q_RES       I102
  U87      G   GATE  MOSFET_N    I96

FM_RISER1_JTAG_SEL_PLD_N   @S9S_MB_2U_LIB.S9S_MB_2U(SCH_1):FM_RISER1_JTAG_SEL_PLD_N
  R2185    2      B  Q_RES       I123
  U122   J18  DIFFIO_RX_R17N  10M04SAU324I7G  I93

FM_RISER1_PWRBRK_N   @S9S_MB_2U_LIB.S9S_MB_2U(SCH_1):FM_RISER1_PWRBRK_N
  J55     A8  SIGNAL_A8  SCONN140_G64V3431BHR  I150
  R2169    2      B  Q_RES       I137

FM_RISER2_JTAG_SEL_N   @S9S_MB_2U_LIB.S9S_MB_2U(SCH_1):FM_RISER2_JTAG_SEL_N
  J89    A22    A22  SCONN280_ME1028040102011  I239
  R2139    2      B  Q_RES       I442
  R2140    2      B  Q_RES       I328

FM_RISER2_JTAG_SEL_PLD_N   @S9S_MB_2U_LIB.S9S_MB_2U(SCH_1):FM_RISER2_JTAG_SEL_PLD_N
  R2139    1      A  Q_RES       I442
  U122   B14  DIFFIO_RX_T7P  10M04SAU324I7G  I155

FM_RISER2_PWRBRK_N   @S9S_MB_2U_LIB.S9S_MB_2U(SCH_1):FM_RISER2_PWRBRK_N
  J89    B28    B28  SCONN280_ME1028040102011  I239
  R1573    2      B  Q_RES       I306

FM_RISER3_PWRBRK_N   @S9S_MB_2U_LIB.S9S_MB_2U(SCH_1):FM_RISER3_PWRBRK_N
  J57     A8  SIGNAL_A8  SCONN140_G64V3431BHR  I242
  R1577    2      B  Q_RES       I239

FM_RST_PERST_BIT0   @S9S_MB_2U_LIB.S9S_MB_2U(SCH_1):FM_RST_PERST_BIT0
  R1741    1      A  Q_RES       I330
  R1742    1      A  Q_RES       I329
  U122   E17  DIFFIO_RX_R30N  10M04SAU324I7G  I93

FM_RST_PERST_BIT1   @S9S_MB_2U_LIB.S9S_MB_2U(SCH_1):FM_RST_PERST_BIT1
  R1308    1      A  Q_RES       I252
  R1473    1      A  Q_RES       I261
  U122   E16  DIFFIO_RX_R29P  10M04SAU324I7G  I93

FM_RST_PERST_BIT2   @S9S_MB_2U_LIB.S9S_MB_2U(SCH_1):FM_RST_PERST_BIT2
  R1312    1      A  Q_RES       I260
  R1474    1      A  Q_RES       I262
  U122   E15  DIFFIO_RX_R33P  10M04SAU324I7G  I155

FM_S3M_CPU0_CPLD_CONFIG_N   @S9S_MB_2U_LIB.S9S_MB_2U(SCH_1):FM_S3M_CPU0_CPLD_CONFIG_N
  R321     2      B  Q_RES       I21
  U2     CK65  CPLD_NCONFIG  SOCKET4677_AZIFS054P001C01   I1
  U122   K15  DIFFIO_RX_R10N  10M04SAU324I7G  I93

FM_S3M_CPU0_CPLD_CRC_ERROR   @S9S_MB_2U_LIB.S9S_MB_2U(SCH_1):FM_S3M_CPU0_CPLD_CRC_ERROR
  R1216    2      B  Q_RES       I36
  U2     CY20  CPLD_CRC_ERROR  SOCKET4677_AZIFS054P001C01   I1
  U122    L1  DIFFIO_RX_L17N  10M04SAU324I7G  I93

FM_S3M_CPU0_LVC1_GPIO_0   @S9S_MB_2U_LIB.S9S_MB_2U(SCH_1):FM_S3M_CPU0_LVC1_GPIO_0
  R249     2      B  Q_RES       I27
  U2     BA70  GPIO_0  SOCKET4677_AZIFS054P001C01   I1

FM_S3M_CPU0_LVC1_GPIO_1   @S9S_MB_2U_LIB.S9S_MB_2U(SCH_1):FM_S3M_CPU0_LVC1_GPIO_1
  R250     2      B  Q_RES       I29
  U2     AV71  GPIO_1  SOCKET4677_AZIFS054P001C01   I1

FM_S3M_CPU0_LVC1_GPIO_2   @S9S_MB_2U_LIB.S9S_MB_2U(SCH_1):FM_S3M_CPU0_LVC1_GPIO_2
  R253     2      B  Q_RES       I31
  R1391    2      B  Q_RES       I61
  U2     AV69  GPIO_2  SOCKET4677_AZIFS054P001C01   I1

FM_S3M_CPU0_LVC1_GPIO_3   @S9S_MB_2U_LIB.S9S_MB_2U(SCH_1):FM_S3M_CPU0_LVC1_GPIO_3
  R254     2      B  Q_RES       I32
  R1392    2      B  Q_RES       I62
  U2     AY69  GPIO_3  SOCKET4677_AZIFS054P001C01   I1

FM_S3M_CPU0_LVC1_GPIO_4   @S9S_MB_2U_LIB.S9S_MB_2U(SCH_1):FM_S3M_CPU0_LVC1_GPIO_4
  R251     2      B  Q_RES       I28
  U2     AW70  GPIO_4  SOCKET4677_AZIFS054P001C01   I1

FM_S3M_CPU1_CPLD_CONFIG_N   @S9S_MB_2U_LIB.S9S_MB_2U(SCH_1):FM_S3M_CPU1_CPLD_CONFIG_N
  R327     2      B  Q_RES       I30
  U1     CK65  CPLD_NCONFIG  SOCKET4677_AZIFS054P001C01   I5
  U122   K16  DIFFIO_RX_R11N  10M04SAU324I7G  I93

FM_S3M_CPU1_CPLD_CRC_ERROR   @S9S_MB_2U_LIB.S9S_MB_2U(SCH_1):FM_S3M_CPU1_CPLD_CRC_ERROR
  R1217    2      B  Q_RES       I37
  U1     CY20  CPLD_CRC_ERROR  SOCKET4677_AZIFS054P001C01   I5
  U122    L2  DIFFIO_RX_L17P  10M04SAU324I7G  I93

FM_S3M_CPU1_LVC1_GPIO_0   @S9S_MB_2U_LIB.S9S_MB_2U(SCH_1):FM_S3M_CPU1_LVC1_GPIO_0
  R255     2      B  Q_RES       I42
  U1     BA70  GPIO_0  SOCKET4677_AZIFS054P001C01   I5

FM_S3M_CPU1_LVC1_GPIO_1   @S9S_MB_2U_LIB.S9S_MB_2U(SCH_1):FM_S3M_CPU1_LVC1_GPIO_1
  R256     2      B  Q_RES       I48
  U1     AV71  GPIO_1  SOCKET4677_AZIFS054P001C01   I5

FM_S3M_CPU1_LVC1_GPIO_2   @S9S_MB_2U_LIB.S9S_MB_2U(SCH_1):FM_S3M_CPU1_LVC1_GPIO_2
  R259     2      B  Q_RES       I45
  R1393    2      B  Q_RES       I66
  U1     AV69  GPIO_2  SOCKET4677_AZIFS054P001C01   I5

FM_S3M_CPU1_LVC1_GPIO_3   @S9S_MB_2U_LIB.S9S_MB_2U(SCH_1):FM_S3M_CPU1_LVC1_GPIO_3
  R260     2      B  Q_RES       I46
  R1394    2      B  Q_RES       I67
  U1     AY69  GPIO_3  SOCKET4677_AZIFS054P001C01   I5

FM_S3M_CPU1_LVC1_GPIO_4   @S9S_MB_2U_LIB.S9S_MB_2U(SCH_1):FM_S3M_CPU1_LVC1_GPIO_4
  R257     2      B  Q_RES       I43
  U1     AW70  GPIO_4  SOCKET4677_AZIFS054P001C01   I5

FM_SCM_PRSNT1_N   @S9S_MB_2U_LIB.S9S_MB_2U(SCH_1):FM_SCM_PRSNT1_N
  J41    A57  PERP12  SCONN168_623403212  I115
  R1854    2      B  Q_RES       I43
  R1856    1      A  Q_RES       I34

FM_SCM_PRSNT1_R_N   @S9S_MB_2U_LIB.S9S_MB_2U(SCH_1):FM_SCM_PRSNT1_R_N
  Q39      5     G2  MOSFET_NCH_DUAL  I20
  R1856    2      B  Q_RES       I34

FM_SLPS3_PLD_N   @S9S_MB_2U_LIB.S9S_MB_2U(SCH_1):FM_SLPS3_PLD_N
  R1995    2      B  Q_RES       I86
  U122   L17  DIFFIO_RX_R16P||CLK3P  10M04SAU324I7G  I139

FM_SLPS4_PLD_N   @S9S_MB_2U_LIB.S9S_MB_2U(SCH_1):FM_SLPS4_PLD_N
  R1996    2      B  Q_RES       I87
  U122   L18  DIFFIO_RX_R15N  10M04SAU324I7G  I93

FM_SLP_SUS_RSM_RST_N   @S9S_MB_2U_LIB.S9S_MB_2U(SCH_1):FM_SLP_SUS_RSM_RST_N
  R1660    1      A  Q_RES       I328
  R1736    2      B  Q_RES       I89
  U122   G12  DIFFIO_RX_R31N  10M04SAU324I7G  I93

FM_SMB_CPU0_ALERT   @S9S_MB_2U_LIB.S9S_MB_2U(SCH_1):FM_SMB_CPU0_ALERT
  R1921    1      A  Q_RES       I132
  U51      1   INT*  PCA9555PW   I125

FM_SMB_CPU0_ALERT_R1   @S9S_MB_2U_LIB.S9S_MB_2U(SCH_1):FM_SMB_CPU0_ALERT_R1
  Q15      5     G2  MOSFET_NCH_DUAL   I9
  Q15      6     D1  MOSFET_NCH_DUAL  I36
  R1002    2      B  Q_RES       I34

FM_SMB_CPU1_ALERT_R1   @S9S_MB_2U_LIB.S9S_MB_2U(SCH_1):FM_SMB_CPU1_ALERT_R1
  Q16      5     G2  MOSFET_NCH_DUAL  I66
  Q16      6     D1  MOSFET_NCH_DUAL  I68
  R1003    2      B  Q_RES       I38

FM_SMB_PEHPCPU0_PCIE_ALERT_N   @S9S_MB_2U_LIB.S9S_MB_2U(SCH_1):FM_SMB_PEHPCPU0_PCIE_ALERT_N
  JP7      1      1  CONN3_210HP1030BR1  I64
  R998     1      A  Q_RES       I53
  R1921    2      B  Q_RES       I132

FM_SMB_PEHPCPU0_PCIE_ALERT_R_N   @S9S_MB_2U_LIB.S9S_MB_2U(SCH_1):FM_SMB_PEHPCPU0_PCIE_ALERT_R_N
  Q15      2     G1  MOSFET_NCH_DUAL  I36
  R998     2      B  Q_RES       I53
  R1000    2      B  Q_RES       I52

FM_SMB_PEHPCPU1_PCIE_ALERT_N   @S9S_MB_2U_LIB.S9S_MB_2U(SCH_1):FM_SMB_PEHPCPU1_PCIE_ALERT_N
  JP7      3      3  CONN3_210HP1030BR1  I64
  R999     1      A  Q_RES       I69

FM_SMB_PEHPCPU1_PCIE_ALERT_R_N   @S9S_MB_2U_LIB.S9S_MB_2U(SCH_1):FM_SMB_PEHPCPU1_PCIE_ALERT_R_N
  Q16      2     G1  MOSFET_NCH_DUAL  I68
  R999     2      B  Q_RES       I69
  R1001    2      B  Q_RES       I55

FM_SPD_REMOTE_EN   @S9S_MB_2U_LIB.S9S_MB_2U(SCH_1):FM_SPD_REMOTE_EN
  R87      2      B  Q_RES       I79
  R318     1      A  Q_RES       I81
  R1821    2      B  Q_RES       I90
  U14      1      S  IDTQS3VH257QG  I17
  U15      1      S  IDTQS3VH257QG  I25

FM_SPD_REMOTE_EN_R   @S9S_MB_2U_LIB.S9S_MB_2U(SCH_1):FM_SPD_REMOTE_EN_R
  R1821    1      A  Q_RES       I90
  U122    A7   IO_8  10M04SAU324I7G  I155

FM_SPI_3V3_1V8_VOLTAGE   @S9S_MB_2U_LIB.S9S_MB_2U(SCH_1):FM_SPI_3V3_1V8_VOLTAGE
  R374     2      B  Q_RES       I60
  R375     1      A  Q_RES       I61
  U4     AU13  GPPC_S_4_CPU_GP_2  EMMITSBURG_REV0P9  I27

FM_SUSACK_N     @S9S_MB_2U_LIB.S9S_MB_2U(SCH_1):FM_SUSACK_N
  R1461    2      B  Q_RES       I80
  R2071    2      B  Q_RES       I327
  U4     BA7  GPPC_S_7_SUSACK_N  EMMITSBURG_REV0P9  I27

FM_SYS_THROTTLE_R_N   @S9S_MB_2U_LIB.S9S_MB_2U(SCH_1):FM_SYS_THROTTLE_R_N
  R85      2      B  Q_RES       I310
  R86      2      B  Q_RES       I240
  R1434    1      A  Q_RES       I216
  R1573    1      A  Q_RES       I306
  R1577    1      A  Q_RES       I239
  R1584    2      B  Q_RES       I114
  R1585    1      A  Q_RES       I112
  R1586    2      B  Q_RES       I100
  R1587    1      A  Q_RES       I98
  R1588    2      B  Q_RES       I455
  R1589    1      A  Q_RES       I453
  R1964    2      B  Q_RES       I80
  R1965    1      A  Q_RES       I61
  R1974    2      B  Q_RES       I78
  R1975    1      A  Q_RES       I74
  R1984    2      B  Q_RES       I27
  R1985    1      A  Q_RES       I31
  R2168    2      B  Q_RES       I27
  R2169    1      A  Q_RES       I137
  U104     2      A  74LVC1G07GV  I63
  U122   G18  DIFFIO_RX_R18N  10M04SAU324I7G  I93

FM_THERMTRIP_DLY_LVC1_N   @S9S_MB_2U_LIB.S9S_MB_2U(SCH_1):FM_THERMTRIP_DLY_LVC1_N
  R1249    1      A  Q_RES        I2
  R1318    2      B  Q_RES       I47

FM_THERMTRIP_DLY_LVC1_R_N   @S9S_MB_2U_LIB.S9S_MB_2U(SCH_1):FM_THERMTRIP_DLY_LVC1_R_N
  R1318    1      A  Q_RES       I47
  U122    T4  DIFFIO_TX_RX_B1P  10M04SAU324I7G  I155

FM_THROTTLE_N   @S9S_MB_2U_LIB.S9S_MB_2U(SCH_1):FM_THROTTLE_N
  R1307    1      A  Q_RES        I3
  R1450    2      B  Q_RES       I42
  U4     AW2  GPPC_C_14_ME_SML3ALERT_N  EMMITSBURG_REV0P9  I93

FM_THROTTLE_R_N   @S9S_MB_2U_LIB.S9S_MB_2U(SCH_1):FM_THROTTLE_R_N
  R1307    2      B  Q_RES        I3
  U122   E18   IO_6  10M04SAU324I7G  I155

FM_TPM_PRSNT_N   @S9S_MB_2U_LIB.S9S_MB_2U(SCH_1):FM_TPM_PRSNT_N
  R1547    2      B  Q_RES       I251
  U4     BB31  GPP_E_19_ERR2_N  EMMITSBURG_REV0P9  I22

FM_TPM_PRSNT_R_N   @S9S_MB_2U_LIB.S9S_MB_2U(SCH_1):FM_TPM_PRSNT_R_N
  R1547    1      A  Q_RES       I251
  U122    J6  DIFFIO_RX_L14N  10M04SAU324I7G  I93

FM_UV_ADR_TRIGGER_N   @S9S_MB_2U_LIB.S9S_MB_2U(SCH_1):FM_UV_ADR_TRIGGER_N
  J44     11     11  CONN24_52SH90245BRD  I125
  R948     2      B  Q_RES       I206
  U122   G10  DIFFIO_RX_T14N  10M04SAU324I7G  I155

FM_XTAL_INPUT_FREQUENCY_0_MGPIO   @S9S_MB_2U_LIB.S9S_MB_2U(SCH_1):FM_XTAL_INPUT_FREQUENCY_0_MGPIO_TEST4
  R382     2      B  Q_RES       I32
  R1311    1      A  Q_RES       I31
  U4     BB18  GPPC_S_0_TIME_SYNC_0  EMMITSBURG_REV0P9  I27

FM_XTAL_INPUT_FREQUENCY_1_MGPIO   @S9S_MB_2U_LIB.S9S_MB_2U(SCH_1):FM_XTAL_INPUT_FREQUENCY_1_MGPIO_TEST5
  R1315    2      B  Q_RES       I35
  R1457    1      A  Q_RES       I36
  U4     AR16  GPPC_S_2_CPU_GP_0  EMMITSBURG_REV0P9  I27

FP_DPLD_ANAIN1   @S9S_MB_2U_LIB.S9S_MB_2U(SCH_1):FP_DPLD_ANAIN1
  R509     1      A  Q_RES       I197
  U122    E2  ANAIN1  10M04SAU324I7G  I139

GND             @S9S_MB_2U_LIB.S9S_MB_2U(SCH_1):GND
  BT1      2      2  CONN2_AAABAT029P15  I63
  C1       2      B  Q_CAP       I15
  C2       2      B  Q_CAP       I192
  C3       2      B  Q_CAP       I188
  C4       2      B  Q_CAP       I190
  C5       2      B  Q_CAP       I120
  C6       2      B  Q_CAP       I122
  C7       2      B  Q_CAP       I144
  C8       2      B  Q_CAP       I121
  C9       2      B  Q_CAP       I122
  C10      2      B  Q_CAP       I144
  C11      2      B  Q_CAP       I121
  C12      2      B  Q_CAP       I125
  C13      2      B  Q_CAP       I127
  C14      2      B  Q_CAP       I120
  C15      2      B  Q_CAP       I121
  C16      2      B  Q_CAP       I123
  C17      2      B  Q_CAP       I120
  C18      2      B  Q_CAP       I124
  C19      2      B  Q_CAP       I127
  C20      2      B  Q_CAP       I123
  C21      2      B  Q_CAP       I126
  C22      2      B  Q_CAP       I166
  C23      2      B  Q_CAP       I121
  C24      2      B  Q_CAP       I125
  C25      2      B  Q_CAP       I127
  C26      2      B  Q_CAP       I122
  C27      2      B  Q_CAP       I123
  C28      2      B  Q_CAP       I145
  C29      2      B  Q_CAP       I123
  C30      2      B  Q_CAP       I124
  C31      2      B  Q_CAP       I146
  C32      2      B  Q_CAP       I122
  C33      2      B  Q_CAP       I127
  C34      2      B  Q_CAP       I130
  C35      2      B  Q_CAP       I122
  C36      2      B  Q_CAP       I126
  C37      2      B  Q_CAP       I128
  C38      2      B  Q_CAP       I123
  C39      2      B  Q_CAP       I125
  C40      2      B  Q_CAP       I162
  C41      2      B  Q_CAP       I121
  C42      2      B  Q_CAP       I125
  C43      2      B  Q_CAP       I128
  C44      2      B  Q_CAP       I121
  C45      2      B  Q_CAP       I125
  C46      2      B  Q_CAP       I127
  C47      2      B  Q_CAP       I56
  C48      2      B  Q_CAP       I59
  C49      2      B  Q_CAP       I62
  C50      2      B  Q_CAP       I122
  C51      2      B  Q_CAP       I123
  C52      2      B  Q_CAP       I145
  C53      2      B  Q_CAP       I122
  C54      2      B  Q_CAP       I126
  C55      2      B  Q_CAP       I128
  C56      2      B  Q_CAP       I121
  C57      2      B  Q_CAP       I122
  C58      2      B  Q_CAP       I124
  C59      2      B  Q_CAP       I121
  C60      2      B  Q_CAP       I125
  C61      2      B  Q_CAP       I127
  C62      2      B  Q_CAP       I124
  C63      2      B  Q_CAP       I127
  C64      2      B  Q_CAP       I167
  C65      2      B  Q_CAP       I122
  C66      2      B  Q_CAP       I126
  C67      2      B  Q_CAP       I128
  C68      2      B  Q_CAP       I122
  C69      2      B  Q_CAP       I127
  C70      2      B  Q_CAP       I129
  C71      2      B  Q_CAP        I4
  C72      2      B  Q_CAP       I116
  C73      2      B  Q_CAP       I120
  C74      2      B  Q_CAP       I122
  C75      2      B  Q_CAP       I124
  C76      2      B  Q_CAP       I125
  C77      2      B  Q_CAP       I126
  C78      2      B  Q_CAP       I54
  C79      2      B  Q_CAP       I56
  C80      2      B  Q_CAP       I59
  C81      2      B  Q_CAP       I120
  C82      2      B  Q_CAP       I124
  C83      2      B  Q_CAP       I126
  C84      2      B  Q_CAP       I121
  C85      2      B  Q_CAP       I125
  C86      2      B  Q_CAP       I128
  C87      2      B  Q_CAP       I121
  C88      2      B  Q_CAP       I123
  C89      2      B  Q_CAP       I160
  C90      2      B  Q_CAP       I122
  C91      2      B  Q_CAP       I126
  C92      2      B  Q_CAP       I128
  C93      2      B  Q_CAP       I122
  C94      2      B  Q_CAP       I127
  C95      2      B  Q_CAP       I130
  C96      2      B  Q_CAP       I123
  C97      2      B  Q_CAP       I124
  C98      2      B  Q_CAP       I146
  C101     2      B  Q_CAP       I148
  C103     2      B  Q_CAP       I77
  C104     2      B  Q_CAP       I76
  C108     2      B  Q_CAP       I19
  C109     2      B  Q_CAP       I18
  C110     2      B  Q_CAP       I17
  C111     2      B  Q_CAP       I46
  C112     2      B  Q_CAP       I45
  C113     2      B  Q_CAP       I186
  C114     2      B  Q_CAP       I47
  C115     2      B  Q_CAP       I66
  C116     2      B  Q_CAP       I65
  C117     2      B  Q_CAP       I64
  C118     2      B  Q_CAP       I183
  C119     2      B  Q_CAP       I67
  C120     2      B  Q_CAP       I68
  C127     2      B  Q_CAPP      I50
  C128     2      B  Q_CAP       I52
  C129     2      B  Q_CAPP      I54
  C130     2      B  Q_CAP       I56
  C131     2      B  Q_CAP       I103
  C132     2      B  Q_CAP       I106
  C133     2      B  Q_CAPP      I18
  C134     2      B  Q_CAP       I20
  C135     2      B  Q_CAPP      I21
  C136     2      B  Q_CAP       I23
  C137     2      B  Q_CAP       I24
  C138     2      B  Q_CAP       I26
  C171     2      B  Q_CAP        I2
  C172     2      B  Q_CAP        I6
  C173     2      B  Q_CAP        I4
  C174     2      B  Q_CAP       I151
  C179     2      B  Q_CAP       I38
  C180     2      B  Q_CAP       I77
  C184     2      B  Q_CAP       I45
  C188     2      B  Q_CAP       I44
  C204     2      B  Q_CAP       I171
  C205     2      B  Q_CAP       I172
  C206     2      B  Q_CAP       I173
  C207     2      B  Q_CAP       I174
  C208     2      B  Q_CAP       I167
  C209     2      B  Q_CAP       I164
  C210     2      B  Q_CAP       I168
  C211     2      B  Q_CAP       I165
  C212     2      B  Q_CAP       I159
  C213     2      B  Q_CAP       I149
  C214     2      B  Q_CAP       I151
  C215     2      B  Q_CAP       I152
  C216     2      B  Q_CAP       I153
  C217     2      B  Q_CAP       I154
  C218     2      B  Q_CAP       I155
  C219     2      B  Q_CAP       I156
  C220     2      B  Q_CAP       I158
  C221     2      B  Q_CAP       I27
  C222     2      B  Q_CAP       I25
  C223     2      B  Q_CAP       I23
  C224     2      B  Q_CAP       I15
  C225     2      B  Q_CAP       I13
  C226     2      B  Q_CAP       I31
  C227     2      B  Q_CAP       I30
  C228     2      B  Q_CAP       I28
  C229     2      B  Q_CAP       I21
  C230     2      B  Q_CAP       I18
  C231     2      B  Q_CAP       I33
  C232     2      B  Q_CAP       I32
  C233     2      B  Q_CAP       I29
  C234     2      B  Q_CAP       I22
  C235     2      B  Q_CAP       I20
  C236     2      B  Q_CAP       I52
  C237     2      B  Q_CAP       I51
  C238     2      B  Q_CAP       I49
  C239     2      B  Q_CAP       I37
  C240     2      B  Q_CAP       I35
  C241     2      B  Q_CAP       I54
  C242     2      B  Q_CAP       I53
  C243     2      B  Q_CAP       I50
  C244     2      B  Q_CAP       I38
  C245     2      B  Q_CAP       I36
  C246     2      B  Q_CAP       I59
  C247     2      B  Q_CAP       I58
  C248     2      B  Q_CAP       I55
  C249     2      B  Q_CAP       I46
  C250     2      B  Q_CAP       I41
  C251     2      B  Q_CAP       I61
  C252     2      B  Q_CAP       I60
  C253     2      B  Q_CAP       I56
  C254     2      B  Q_CAP       I47
  C255     2      B  Q_CAP       I44
  C256     2      B  Q_CAP       I63
  C257     2      B  Q_CAP       I62
  C258     2      B  Q_CAP       I57
  C259     2      B  Q_CAP       I48
  C260     2      B  Q_CAP       I45
  C261     2      B  Q_CAP       I89
  C262     2      B  Q_CAP       I88
  C263     2      B  Q_CAP       I84
  C264     2      B  Q_CAP       I76
  C265     2      B  Q_CAP       I72
  C266     2      B  Q_CAP       I92
  C267     2      B  Q_CAP       I90
  C268     2      B  Q_CAP       I86
  C269     2      B  Q_CAP       I78
  C270     2      B  Q_CAP       I75
  C271     2      B  Q_CAP       I98
  C272     2      B  Q_CAP       I96
  C273     2      B  Q_CAP       I93
  C274     2      B  Q_CAP       I81
  C275     2      B  Q_CAP       I100
  C276     2      B  Q_CAP       I99
  C277     2      B  Q_CAP       I95
  C278     2      B  Q_CAP       I83
  C279     2      B  Q_CAP       I112
  C280     2      B  Q_CAP       I111
  C281     2      B  Q_CAP       I109
  C282     2      B  Q_CAP       I103
  C283     2      B  Q_CAP       I114
  C284     2      B  Q_CAP       I113
  C285     2      B  Q_CAP       I110
  C286     2      B  Q_CAP       I104
  C287     2      B  Q_CAP       I120
  C288     2      B  Q_CAP       I118
  C289     2      B  Q_CAP       I115
  C290     2      B  Q_CAP       I106
  C291     2      B  Q_CAP       I121
  C292     2      B  Q_CAP       I119
  C293     2      B  Q_CAP       I116
  C294     2      B  Q_CAP       I107
  C295     2      B  Q_CAP       I123
  C296     2      B  Q_CAP       I122
  C297     2      B  Q_CAP       I117
  C298     2      B  Q_CAP       I108
  C299     2      B  Q_CAP       I132
  C300     2      B  Q_CAP       I131
  C301     2      B  Q_CAP       I129
  C302     2      B  Q_CAP       I125
  C303     2      B  Q_CAP       I134
  C304     2      B  Q_CAP       I133
  C305     2      B  Q_CAP       I130
  C306     2      B  Q_CAP       I126
  C307     2      B  Q_CAP       I140
  C308     2      B  Q_CAP       I138
  C309     2      B  Q_CAP       I136
  C310     2      B  Q_CAP       I148
  C311     2      B  Q_CAP       I35
  C312     2      B  Q_CAP       I32
  C313     2      B  Q_CAP       I128
  C314     2      B  Q_CAP       I40
  C315     2      B  Q_CAP       I37
  C316     2      B  Q_CAP       I129
  C317     2      B  Q_CAP       I41
  C318     2      B  Q_CAP       I39
  C319     2      B  Q_CAP       I361
  C320     2      B  Q_CAP       I59
  C321     2      B  Q_CAP       I56
  C322     2      B  Q_CAP       I115
  C323     2      B  Q_CAP       I60
  C324     2      B  Q_CAP       I58
  C325     2      B  Q_CAP       I114
  C326     2      B  Q_CAP       I67
  C327     2      B  Q_CAP       I62
  C328     2      B  Q_CAP       I112
  C329     2      B  Q_CAP       I68
  C330     2      B  Q_CAP       I65
  C331     2      B  Q_CAP       I360
  C332     2      B  Q_CAP       I69
  C333     2      B  Q_CAP       I66
  C335     2      B  Q_CAP       I80
  C336     2      B  Q_CAP       I76
  C337     2      B  Q_CAP       I121
  C338     2      B  Q_CAP       I82
  C339     2      B  Q_CAP       I79
  C340     2      B  Q_CAP       I120
  C341     2      B  Q_CAP       I125
  C342     2      B  Q_CAP       I109
  C343     2      B  Q_CAP       I124
  C344     2      B  Q_CAP       I110
  C345     2      B  Q_CAP       I123
  C346     2      B  Q_CAP       I111
  C347     2      B  Q_CAP       I122
  C348     2      B  Q_CAP       I119
  C349     2      B  Q_CAP       I124
  C350     2      B  Q_CAP       I118
  C351     2      B  Q_CAP       I126
  C352     2      B  Q_CAP       I117
  C353     2      B  Q_CAP       I125
  C354     2      B  Q_CAP       I116
  C355     2      B  Q_CAP       I22
  C356     2      B  Q_CAP       I20
  C357     2      B  Q_CAP       I237
  C358     2      B  Q_CAP       I26
  C359     2      B  Q_CAP       I25
  C360     2      B  Q_CAP       I234
  C361     2      B  Q_CAP       I28
  C362     2      B  Q_CAP       I27
  C363     2      B  Q_CAP       I232
  C364     2      B  Q_CAP       I43
  C365     2      B  Q_CAP       I42
  C366     2      B  Q_CAP       I70
  C367     2      B  Q_CAP       I45
  C368     2      B  Q_CAP       I44
  C369     2      B  Q_CAP       I82
  C370     2      B  Q_CAP       I50
  C371     2      B  Q_CAP       I49
  C372     2      B  Q_CAP       I83
  C373     2      B  Q_CAP       I52
  C374     2      B  Q_CAP       I88
  C376     2      B  Q_CAP       I54
  C377     2      B  Q_CAP       I90
  C379     2      B  Q_CAP       I77
  C380     2      B  Q_CAP       I95
  C381     2      B  Q_CAP       I189
  C382     2      B  Q_CAP       I80
  C383     2      B  Q_CAP       I97
  C384     2      B  Q_CAP       I187
  C385     2      B  Q_CAP       I113
  C386     2      B  Q_CAP       I41
  C387     2      B  Q_CAP       I112
  C388     2      B  Q_CAP       I46
  C389     2      B  Q_CAP       I217
  C390     2      B  Q_CAP       I47
  C391     2      B  Q_CAP       I216
  C392     2      B  Q_CAP       I62
  C393     2      B  Q_CAP       I215
  C394     2      B  Q_CAP       I63
  C395     2      B  Q_CAP       I108
  C396     2      B  Q_CAP       I68
  C397     2      B  Q_CAP       I236
  C398     2      B  Q_CAP       I69
  C399     2      B  Q_CAP       I102
  C400     2      B  Q_CAP       I134
  C401     2      B  Q_CAP       I105
  C402     2      B  Q_CAP       I133
  C403     2      B  Q_CAP       I104
  C404     2      B  Q_CAP       I132
  C405     2      B  Q_CAP       I103
  C406     2      B  Q_CAP       I131
  C407     2      B  Q_CAP       I135
  C408     2      B  Q_CAP       I115
  C409     2      B  Q_CAP       I136
  C410     2      B  Q_CAP       I114
  C411     2      B  Q_CAP       I137
  C412     2      B  Q_CAP       I113
  C413     2      B  Q_CAP       I138
  C414     2      B  Q_CAP       I112
  C415     2      B  Q_CAP       I139
  C416     2      B  Q_CAP       I111
  C417     2      B  Q_CAP       I140
  C418     2      B  Q_CAP       I141
  C419     2      B  Q_CAP       I142
  C420     2      B  Q_CAP       I146
  C421     2      B  Q_CAP       I145
  C422     2      B  Q_CAP       I143
  C423     2      B  Q_CAP       I11
  C424     2      B  Q_CAP        I1
  C425     2      B  Q_CAP       I17
  C426     2      B  Q_CAP        I3
  C427     2      B  Q_CAP       I19
  C428     2      B  Q_CAP        I4
  C429     2      B  Q_CAP       I34
  C430     2      B  Q_CAP        I5
  C431     2      B  Q_CAP        I7
  C432     2      B  Q_CAP       I39
  C433     2      B  Q_CAP        I8
  C434     2      B  Q_CAP       I42
  C435     2      B  Q_CAP        I9
  C436     2      B  Q_CAP       I43
  C437     2      B  Q_CAP       I10
  C438     2      B  Q_CAP       I71
  C439     2      B  Q_CAP       I65
  C440     2      B  Q_CAP       I73
  C441     2      B  Q_CAP       I66
  C442     2      B  Q_CAP       I69
  C443     2      B  Q_CAP       I79
  C444     2      B  Q_CAP       I101
  C445     2      B  Q_CAP       I102
  C446     2      B  Q_CAP       I105
  C447     2      B  Q_CAP       I24
  C448     2      B  Q_CAP       I23
  C449     2      B  Q_CAP        I3
  C450     2      B  Q_CAP        I1
  C451     2      B  Q_CAP       I29
  C452     2      B  Q_CAP       I27
  C453     2      B  Q_CAP        I5
  C454     2      B  Q_CAP        I3
  C455     2      B  Q_CAP       I129
  C456     2      B  Q_CAP       I136
  C457     2      B  Q_CAP        I7
  C458     2      B  Q_CAP        I4
  C459     2      B  Q_CAP       I128
  C460     2      B  Q_CAP       I135
  C461     2      B  Q_CAP        I9
  C462     2      B  Q_CAP        I5
  C463     2      B  Q_CAP       I127
  C464     2      B  Q_CAP       I134
  C465     2      B  Q_CAP       I11
  C466     2      B  Q_CAP        I6
  C467     2      B  Q_CAP       I126
  C468     2      B  Q_CAP       I133
  C470     2      B  Q_CAP        I7
  C471     2      B  Q_CAP       I52
  C472     2      B  Q_CAP       I132
  C473     2      B  Q_CAP        I8
  C474     2      B  Q_CAP       I54
  C475     2      B  Q_CAP       I131
  C476     2      B  Q_CAP        I9
  C477     2      B  Q_CAP       I10
  C478     2      B  Q_CAP       I70
  C479     2      B  Q_CAP       I11
  C480     2      B  Q_CAP       I119
  C481     2      B  Q_CAP       I77
  C482     2      B  Q_CAP       I74
  C483     2      B  Q_CAP       I118
  C484     2      B  Q_CAP       I78
  C485     2      B  Q_CAP       I76
  C486     2      B  Q_CAP       I79
  C487     2      B  Q_CAP       I80
  C488     2      B  Q_CAP       I134
  C489     2      B  Q_CAP       I133
  C490     2      B  Q_CAP       I132
  C491     2      B  Q_CAP       I10
  C492     2      B  Q_CAP       I66
  C493     2      B  Q_CAP        I1
  C494     2      B  Q_CAP        I1
  C495     2      B  Q_CAP       I14
  C496     2      B  Q_CAP       I67
  C497     2      B  Q_CAP        I2
  C498     2      B  Q_CAP        I6
  C499     2      B  Q_CAP       I107
  C500     2      B  Q_CAP       I55
  C501     2      B  Q_CAP        I3
  C502     2      B  Q_CAP        I7
  C503     2      B  Q_CAP       I110
  C504     2      B  Q_CAP       I56
  C505     2      B  Q_CAP        I4
  C506     2      B  Q_CAP       I12
  C507     2      B  Q_CAP       I109
  C508     2      B  Q_CAP       I77
  C509     2      B  Q_CAP       I105
  C510     2      B  Q_CAP       I13
  C511     2      B  Q_CAP       I108
  C512     2      B  Q_CAP       I78
  C513     2      B  Q_CAP        I5
  C514     2      B  Q_CAP       I18
  C515     2      B  Q_CAP       I126
  C516     2      B  Q_CAP       I79
  C517     2      B  Q_CAP       I19
  C518     2      B  Q_CAP       I130
  C519     2      B  Q_CAP       I81
  C520     2      B  Q_CAP       I20
  C521     2      B  Q_CAP       I27
  C522     2      B  Q_CAP       I33
  C523     2      B  Q_CAP       I28
  C524     2      B  Q_CAP       I186
  C525     2      B  Q_CAP       I114
  C526     2      B  Q_CAP       I29
  C527     2      B  Q_CAP       I185
  C528     2      B  Q_CAP       I118
  C529     2      B  Q_CAP       I31
  C530     2      B  Q_CAP       I117
  C531     2      B  Q_CAP       I115
  C532     2      B  Q_CAP       I163
  C533     2      B  Q_CAP       I164
  C534     2      B  Q_CAP       I165
  C535     2      B  Q_CAP        I4
  C536     2      B  Q_CAP       I182
  C537     2      B  Q_CAP       I24
  C538     2      B  Q_CAP       I84
  C539     2      B  Q_CAP       I70
  C540     2      B  Q_CAP       I81
  C541     2      B  Q_CAP       I61
  C542     2      B  Q_CAP       I80
  C543     2      B  Q_CAP       I100
  C544     2      B  Q_CAP       I94
  C545     2      B  Q_CAP       I93
  C546     2      B  Q_CAP       I135
  C547     2      B  Q_CAP       I100
  C548     2      B  Q_CAP       I130
  C549     2      B  Q_CAP       I129
  C550     2      B  Q_CAP       I99
  C551     2      B  Q_CAP       I105
  C552     2      B  Q_CAP       I96
  C553     2      B  Q_CAP       I40
  C554     2      B  Q_CAP       I52
  C559     2      B  Q_CAP       I20
  C560     2      B  Q_CAP       I42
  C561     2      B  Q_CAP       I18
  C562     2      B  Q_CAP       I31
  C563     2      B  Q_CAP       I50
  C564     2      B  Q_CAP        I9
  C567     2      B  Q_CAP       I25
  C568     2      B  Q_CAP       I35
  C569     2      B  Q_CAP       I22
  C570     2      B  Q_CAP       I33
  C575     2      B  Q_CAP       I19
  C578     2      B  Q_CAP       I169
  C579     2      B  Q_CAP       I123
  C580     2      B  Q_CAP       I165
  C581     2      B  Q_CAP       I148
  C582     2      B  Q_CAP       I353
  C583     2      B  Q_CAP       I382
  C586     2      B  Q_CAP       I381
  C587     2      B  Q_CAP       I347
  C588     2      B  Q_CAP       I373
  C589     2      B  Q_CAP       I369
  C590     2      B  Q_CAP       I171
  C591     2      B  Q_CAP       I371
  C592     2      B  Q_CAP       I393
  C593     2      B  Q_CAP       I395
  C605     2      B  Q_CAP       I37
  C606     2      B  Q_CAP       I45
  C607     2      B  Q_CAP       I36
  C608     2      B  Q_CAP       I43
  C609     2      B  Q_CAP       I89
  C610     2      B  Q_CAP       I68
  C611     2      B  Q_CAP       I65
  C613     2      B  Q_CAP       I68
  C614     2      B  Q_CAP       I65
  C615     2      B  Q_CAP       I62
  C616     2      B  Q_CAP       I59
  C621     2      B  Q_CAP       I102
  C622     2      B  Q_CAP       I91
  C623     2      B  Q_CAP       I94
  C624     2      B  Q_CAP       I99
  C629     2      B  Q_CAP       I55
  C630     2      B  Q_CAP       I10
  C631     2      B  Q_CAP       I75
  C632     2      B  Q_CAP       I59
  C633     2      B  Q_CAP       I61
  C638     2      B  Q_CAP       I63
  C639     2      B  Q_CAP       I59
  C640     2      B  Q_CAP       I47
  C641     2      B  Q_CAP       I16
  C966     2      B  Q_CAP        I7
  C967     2      B  Q_CAP       I53
  C968     2      B  Q_CAP       I99
  C969     2      B  Q_CAP       I101
  C970     2      B  Q_CAP        I8
  C971     2      B  Q_CAP       I52
  C972     2      B  Q_CAP       I97
  C973     2      B  Q_CAP       I98
  C974     2      B  Q_CAP        I9
  C975     2      B  Q_CAP       I51
  C976     2      B  Q_CAP       I95
  C977     2      B  Q_CAP       I96
  C978     2      B  Q_CAP       I10
  C979     2      B  Q_CAP       I50
  C980     2      B  Q_CAP       I93
  C981     2      B  Q_CAP       I94
  C982     2      B  Q_CAP       I12
  C983     2      B  Q_CAP       I49
  C984     2      B  Q_CAP       I91
  C985     2      B  Q_CAP       I92
  C986     2      B  Q_CAP       I14
  C987     2      B  Q_CAP       I48
  C988     2      B  Q_CAP       I89
  C989     2      B  Q_CAP       I90
  C990     2      B  Q_CAP       I13
  C991     2      B  Q_CAP       I47
  C992     2      B  Q_CAP       I88
  C993     2      B  Q_CAP       I87
  C994     2      B  Q_CAP       I17
  C995     2      B  Q_CAP       I46
  C996     2      B  Q_CAP       I85
  C997     2      B  Q_CAP       I86
  C998     2      B  Q_CAP       I15
  C999     2      B  Q_CAP       I44
  C1000    2      B  Q_CAP       I81
  C1001    2      B  Q_CAP       I82
  C1002    2      B  Q_CAP       I16
  C1003    2      B  Q_CAP       I42
  C1004    2      B  Q_CAP       I78
  C1005    2      B  Q_CAP       I80
  C1006    2      B  Q_CAP       I29
  C1007    2      B  Q_CAP       I41
  C1008    2      B  Q_CAP       I75
  C1009    2      B  Q_CAP       I77
  C1010    2      B  Q_CAP       I18
  C1011    2      B  Q_CAP       I40
  C1012    2      B  Q_CAP       I73
  C1013    2      B  Q_CAP       I74
  C1014    2      B  Q_CAP       I19
  C1015    2      B  Q_CAP       I39
  C1016    2      B  Q_CAP       I71
  C1017    2      B  Q_CAP       I72
  C1018    2      B  Q_CAP       I20
  C1019    2      B  Q_CAP       I38
  C1020    2      B  Q_CAP       I69
  C1021    2      B  Q_CAP       I70
  C1022    2      B  Q_CAP       I21
  C1023    2      B  Q_CAP       I37
  C1024    2      B  Q_CAP       I66
  C1025    2      B  Q_CAP       I68
  C1026    2      B  Q_CAP       I22
  C1027    2      B  Q_CAP       I36
  C1028    2      B  Q_CAP       I65
  C1029    2      B  Q_CAP       I67
  C1030    2      B  Q_CAP       I23
  C1031    2      B  Q_CAP       I35
  C1032    2      B  Q_CAP       I63
  C1033    2      B  Q_CAP       I64
  C1034    2      B  Q_CAP       I24
  C1035    2      B  Q_CAP       I33
  C1036    2      B  Q_CAP       I60
  C1037    2      B  Q_CAP       I61
  C1038    2      B  Q_CAP       I26
  C1039    2      B  Q_CAP       I32
  C1040    2      B  Q_CAP       I58
  C1041    2      B  Q_CAP       I59
  C1042    2      B  Q_CAP       I79
  C1043    2      B  Q_CAP       I30
  C1044    2      B  Q_CAP       I54
  C1045    2      B  Q_CAP       I56
  C1046    2      B  Q_CAP       I40
  C1047    2      B  Q_CAP       I37
  C1048    2      B  Q_CAP       I36
  C1049    2      B  Q_CAP       I35
  C1050    2      B  Q_CAP       I34
  C1051    2      B  Q_CAP       I33
  C1052    2      B  Q_CAP       I31
  C1053    2      B  Q_CAP       I29
  C1054    2      B  Q_CAP       I30
  C1055    2      B  Q_CAP       I60
  C1056    2      B  Q_CAP       I59
  C1057    2      B  Q_CAP       I58
  C1058    2      B  Q_CAP       I57
  C1059    2      B  Q_CAP       I56
  C1060    2      B  Q_CAP       I54
  C1061    2      B  Q_CAP       I53
  C1063    2      B  Q_CAP       I200
  C1064    2      B  Q_CAP       I198
  C1065    2      B  Q_CAP       I197
  C1066    2      B  Q_CAP       I196
  C1067    2      B  Q_CAP       I195
  C1068    2      B  Q_CAP       I193
  C1069    2      B  Q_CAP       I191
  C1078    2      B  Q_CAP       I88
  C1080    2      B  Q_CAP       I90
  C1082    2      B  Q_CAP       I96
  C1084    2      B  Q_CAP       I97
  C1086    2      B  Q_CAP       I98
  C1088    2      B  Q_CAP       I100
  C1107    2      B  Q_CAP       I248
  C1108    2      B  Q_CAP       I251
  C1110    2      B  Q_CAP       I240
  C1111    2      B  Q_CAP       I244
  C1113    2      B  Q_CAP       I239
  C1114    2      B  Q_CAP       I243
  C1115    2      B  Q_CAP       I227
  C1118    2      B  Q_CAP       I236
  C1119    2      B  Q_CAP       I242
  C1120    2      B  Q_CAP       I265
  C1122    2      B  Q_CAP       I235
  C1123    2      B  Q_CAP       I241
  C1124    2      B  Q_CAP       I200
  C1127    2      B  Q_CAP       I222
  C1128    2      B  Q_CAP       I226
  C1129    2      B  Q_CAP       I263
  C1130    2      B  Q_CAP       I199
  C1133    2      B  Q_CAP       I221
  C1134    2      B  Q_CAP       I225
  C1135    2      B  Q_CAP       I262
  C1136    2      B  Q_CAP       I198
  C1138    2      B  Q_CAP       I218
  C1139    2      B  Q_CAP       I224
  C1140    2      B  Q_CAP       I197
  C1142    2      B  Q_CAP       I217
  C1143    2      B  Q_CAP       I223
  C1144    2      B  Q_CAP       I195
  C1146    2      B  Q_CAP       I210
  C1147    2      B  Q_CAP       I214
  C1148    2      B  Q_CAP       I194
  C1150    2      B  Q_CAP       I209
  C1151    2      B  Q_CAP       I213
  C1152    2      B  Q_CAP       I206
  C1153    2      B  Q_CAP       I212
  C1154    2      B  Q_CAP       I205
  C1155    2      B  Q_CAP       I211
  C1156    2      B  Q_CAP       I184
  C1157    2      B  Q_CAP       I187
  C1158    2      B  Q_CAP       I191
  C1159    2      B  Q_CAP       I183
  C1160    2      B  Q_CAP       I256
  C1161    2      B  Q_CAP       I186
  C1162    2      B  Q_CAP       I190
  C1163    2      B  Q_CAP       I180
  C1164    2      B  Q_CAP       I182
  C1165    2      B  Q_CAP       I189
  C1166    2      B  Q_CAP       I255
  C1167    2      B  Q_CAP       I181
  C1168    2      B  Q_CAP       I188
  C1169    2      B  Q_CAP       I254
  C1170    2      B  Q_CAP       I80
  C1171    2      B  Q_CAP       I81
  C1172    2      B  Q_CAP       I72
  C1173    2      B  Q_CAP        I4
  C1175    2      B  Q_CAP       I24
  C1177    2      B  Q_CAP       I67
  C1178    2      B  Q_CAP        I6
  C1181    2      B  Q_CAP       I27
  C1182    2      B  Q_CAP       I42
  C1183    2      B  Q_CAP       I51
  C1184    2      B  Q_CAP       I91
  C1185    2      B  Q_CAP        I7
  C1186    2      B  Q_CAP       I25
  C1187    2      B  Q_CAP       I40
  C1189    2      B  Q_CAP       I58
  C1191    2      B  Q_CAP       I89
  C1192    2      B  Q_CAP        I8
  C1197    2      B  Q_CAP       I30
  C1198    2      B  Q_CAP       I43
  C1200    2      B  Q_CAP       I59
  C1201    2      B  Q_CAP       I87
  C1202    2      B  Q_CAP       I29
  C1203    2      B  Q_CAP       I48
  C1204    2      B  Q_CAP       I60
  C1205    2      B  Q_CAP       I12
  C1206    2      B  Q_CAP       I78
  C1207    2      B  Q_CAP       I32
  C1208    2      B  Q_CAP       I94
  C1209    2      B  Q_CAP       I236
  C1210    2      B  Q_CAP       I45
  C1211    2      B  Q_CAP       I240
  C1213    2      B  Q_CAP       I316
  C1214    2      B  Q_CAP       I61
  C1215    2      B  Q_CAP       I92
  C1216    2      B  Q_CAP       I91
  C1217    2      B  Q_CAP       I89
  C1218    2      B  Q_CAP       I189
  C1219    2      B  Q_CAP       I187
  C1226    2      B  Q_CAP       I78
  C1227    2      B  Q_CAP       I82
  C1228    2      B  Q_CAP       I13
  C1229    2      B  Q_CAP       I168
  C1231    2      B  Q_CAP       I49
  C1232    2      B  Q_CAP       I331
  C1233    2      B  Q_CAP       I319
  C1234    2      B  Q_CAP       I332
  C1235    2      B  Q_CAP       I333
  C1236    2      B  Q_CAP       I322
  C1237    2      B  Q_CAP       I334
  C1238    2      B  Q_CAP       I338
  C1239    2      B  Q_CAP       I337
  C1240    2      B  Q_CAP       I335
  C1241    2      B  Q_CAP       I115
  C1242    2      B  Q_CAP       I63
  C1243    2      B  Q_CAP       I83
  C1244    2      B  Q_CAP       I15
  C1245    2      B  Q_CAP       I81
  C1246    2      B  Q_CAP       I21
  C1247    2      B  Q_CAP       I65
  C1248    2      B  Q_CAP       I22
  C1249    2      B  Q_CAP       I66
  C1250    2      B  Q_CAP       I137
  C1251    2      B  Q_CAP       I110
  C1252    2      B  Q_CAP       I125
  C1253    2      B  Q_CAP       I147
  C1254    2      B  Q_CAP       I111
  C1255    2      B  Q_CAP       I123
  C1256    2      B  Q_CAP       I136
  C1257    2      B  Q_CAP       I146
  C1258    2      B  Q_CAP       I112
  C1259    2      B  Q_CAP       I121
  C1260    2      B  Q_CAP       I131
  C1261    2      B  Q_CAP       I142
  C1262    2      B  Q_CAP       I104
  C1263    2      B  Q_CAP       I119
  C1264    2      B  Q_CAP       I133
  C1265    2      B  Q_CAP       I140
  C1266    2      B  Q_CAP       I127
  C1272    2      B  Q_CAP       I100
  C1273    2      B  Q_CAP       I116
  C1274    2      B  Q_CAP       I59
  C1275    2      B  Q_CAP       I49
  C1276    2      B  Q_CAP       I45
  C1277    2      B  Q_CAP       I44
  C1278    2      B  Q_CAP       I15
  C1279    2      B  Q_CAP       I14
  C1280    2      B  Q_CAP       I32
  C1281    2      B  Q_CAP       I30
  C1282    2      B  Q_CAP        I8
  C1283    2      B  Q_CAP        I7
  C1284    2      B  Q_CAP       I29
  C1285    2      B  Q_CAP       I27
  C1286    2      B  Q_CAP       I30
  C1288    2      B  Q_CAP       I112
  C1289    2      B  Q_CAP       I110
  C1290    2      B  Q_CAP       I43
  C1291    2      B  Q_CAP       I16
  C1292    2      B  Q_CAP       I90
  C1293    2      B  Q_CAP       I95
  C1296    2      B  Q_CAP       I178
  C1297    2      B  Q_CAP       I186
  C1300    2      B  Q_CAP       I14
  C1301    2      B  Q_CAP       I27
  C1302    2      B  Q_CAP       I101
  C1305    2      B  Q_CAP       I52
  C1307    2      B  Q_CAP       I154
  C1308    2      B  Q_CAP       I166
  C1309    2      B  Q_CAP       I44
  C1310    2      B  Q_CAP       I59
  C1311    2      B  Q_CAP       I43
  C1312    2      B  Q_CAP       I58
  C1313    2      B  Q_CAP       I48
  C1314    2      B  Q_CAP       I53
  C1315    2      B  Q_CAP        I8
  C1316    2      B  Q_CAP       I60
  C1317    2      B  Q_CAP       I51
  C1318    2      B  Q_CAP       I54
  C1319    2      B  Q_CAP       I47
  C1320    2      B  Q_CAP       I134
  C1321    2      B  Q_CAP       I55
  C1322    2      B  Q_CAP       I27
  C1323    2      B  Q_CAP       I28
  C1324    2      B  Q_CAP       I286
  C1325    2      B  Q_CAP       I412
  C1326    2      B  Q_CAP       I73
  C1331    2      B  Q_CAP       I83
  C1332    2      B  Q_CAP       I63
  C1333    2      B  Q_CAP       I64
  C1337    2      B  Q_CAP       I13
  C1338    2      B  Q_CAP       I65
  C1339    2      B  Q_CAP       I66
  C1340    2      B  Q_CAP       I67
  C1341    2      B  Q_CAP       I14
  C1342    2      B  Q_CAP       I50
  C1343    2      B  Q_CAP       I51
  C1344    2      B  Q_CAP       I37
  C1345    2      B  Q_CAP       I39
  C1346    2      B  Q_CAP       I42
  C1347    2      B  Q_CAP        I3
  C1351    2      B  Q_CAP       I45
  C1353    2      B  Q_CAP       I149
  C1358    2      B  Q_CAP       I148
  C1359    2      B  Q_CAP       I147
  C1360    2      B  Q_CAP       I144
  C1361    2      B  Q_CAP       I145
  C1362    2      B  Q_CAP       I119
  C1363    2      B  Q_CAP       I51
  C1364    2      B  Q_CAP       I53
  C1365    2      B  Q_CAP       I47
  C1366    2      B  Q_CAP       I49
  C1387    2      B  Q_CAP       I141
  C1388    2      B  Q_CAP       I139
  C1389    2      B  Q_CAP       I143
  C1390    2      B  Q_CAP       I140
  C1391    2      B  Q_CAP       I147
  C1392    2      B  Q_CAP       I145
  C1393    2      B  Q_CAP       I148
  C1396    2      B  Q_CAP       I227
  C1397    2      B  Q_CAP       I229
  C1398    2      B  Q_CAP       I230
  C1399    2      B  Q_CAP       I111
  C1400    2      B  Q_CAP       I112
  C1403    2      B  Q_CAP       I146
  C1404    2      B  Q_CAP       I147
  C1405    2      B  Q_CAP       I238
  C1406    2      B  Q_CAP       I239
  C1407    2      B  Q_CAP       I240
  C1408    2      B  Q_CAP       I206
  C1409    2      B  Q_CAP       I419
  C1430    2      B  Q_CAP       I101
  C1431    2      B  Q_CAP       I100
  C1432    2      B  Q_CAP       I97
  C1433    2      B  Q_CAP       I98
  C1436    2      B  Q_CAP       I242
  C1437    2      B  Q_CAP       I149
  C1438    2      B  Q_CAP       I49
  C1439    2      B  Q_CAP       I46
  C1440    2      B  Q_CAP       I45
  C1441    2      B  Q_CAP       I44
  C1442    2      B  Q_CAP       I43
  C1443    2      B  Q_CAP       I42
  C1444    2      B  Q_CAP       I40
  C1445    2      B  Q_CAP       I38
  C1446    2      B  Q_CAP       I37
  C1447    2      B  Q_CAP       I35
  C1448    2      B  Q_CAP       I31
  C1449    2      B  Q_CAP       I66
  C1450    2      B  Q_CAP       I65
  C1451    2      B  Q_CAP       I64
  C1452    2      B  Q_CAP       I63
  C1453    2      B  Q_CAP       I62
  C1454    2      B  Q_CAP       I60
  C1455    2      B  Q_CAP       I58
  C1456    2      B  Q_CAP       I57
  C1457    2      B  Q_CAP       I55
  C1459    2      B  Q_CAP       I50
  C1460    2      B  Q_CAP       I52
  C1461    2      B  Q_CAP       I53
  C1462    2      B  Q_CAP       I63
  C1463    2      B  Q_CAP       I64
  C1464    2      B  Q_CAP       I66
  C1465    2      B  Q_CAP       I68
  C1466    2      B  Q_CAP       I88
  C1467    2      B  Q_CAP       I90
  C1469    2      B  Q_CAP       I50
  C1470    2      B  Q_CAP       I52
  C1471    2      B  Q_CAP       I54
  C1472    2      B  Q_CAP       I55
  C1473    2      B  Q_CAP       I57
  C1474    2      B  Q_CAP       I58
  C1475    2      B  Q_CAP       I87
  C1476    2      B  Q_CAP       I88
  C1477    2      B  Q_CAP       I91
  C1480    2      B  Q_CAP        I3
  C1481    2      B  Q_CAP       I41
  C1482    2      B  Q_CAP        I7
  C1483    2      B  Q_CAP       I12
  C1484    2      B  Q_CAP       I54
  C1485    2      B  Q_CAP       I58
  C1486    2      B  Q_CAP       I24
  C1487    2      B  Q_CAP       I63
  C1488    2      B  Q_CAP       I29
  C1489    2      B  Q_CAP       I77
  C1490    2      B  Q_CAP       I76
  C1491    2      B  Q_CAP       I47
  C1492    2      B  Q_CAP       I88
  C1493    2      B  Q_CAP       I46
  C1494    2      B  Q_CAP       I86
  C1495    2      B  Q_CAP       I45
  C1496    2      B  Q_CAP       I85
  C1497    2      B  Q_CAP       I13
  C1498    2      B  Q_CAP       I27
  C1499    2      B  Q_CAP        I8
  C1500    2      B  Q_CAP       I25
  C1501    2      B  Q_CAP        I6
  C1502    2      B  Q_CAP       I23
  C1503    2      B  Q_CAP       I160
  C1504    2      B  Q_CAP       I161
  C1505    2      B  Q_CAP       I127
  C1506    2      B  Q_CAP       I164
  C1507    2      B  Q_CAP       I10
  C1508    2      B  Q_CAP       I17
  C1509    2      B  Q_CAP       I123
  C1510    2      B  Q_CAP       I162
  C1511    2      B  Q_CAP       I163
  C1512    2      B  Q_CAP       I108
  C1513    2      B  Q_CAP       I144
  C1514    2      B  Q_CAP       I114
  C1515    2      B  Q_CAP       I140
  C1580    2      B  Q_CAP       I120
  C1581    2      B  Q_CAP       I124
  C1582    2      B  Q_CAP       I142
  C1583    2      B  Q_CAP       I140
  C1584    2      B  Q_CAP       I68
  C1585    2      B  Q_CAP       I105
  C1586    2      B  Q_CAP       I91
  C1587    2      B  Q_CAP       I99
  C1588    2      B  Q_CAP       I39
  C1589    2      B  Q_CAP       I62
  C1590    2      B  Q_CAP       I82
  C1591    2      B  Q_CAP       I89
  C1592    2      B  Q_CAP        I2
  C1593    2      B  Q_CAP       I22
  C1594    2      B  Q_CAP       I39
  C1595    2      B  Q_CAP       I44
  C1596    2      B  Q_CAP       I46
  C1597    2      B  Q_CAP       I47
  C1598    2      B  Q_CAP       I48
  C1599    2      B  Q_CAP       I41
  C1600    2      B  Q_CAP       I44
  C1601    2      B  Q_CAPP      I138
  C1602    2      B  Q_CAP       I139
  C1603    2      B  Q_CAPP      I140
  C1604    2      B  Q_CAP       I141
  C1605    2      B  Q_CAP       I142
  C1606    2      B  Q_CAP       I143
  C1607    2      B  Q_CAP       I105
  C2443    2      B  Q_CAP       I20
  C2444    2      B  Q_CAP       I24
  C2445    2      B  Q_CAP       I11
  C2446    2      B  Q_CAP       I39
  D4       A      A  SCHOTTKY_AC  I370
  D6       C      C  Q_LED       I248
  D8       A      A  DIODE_TVS   I174
  D9       A      A  DIODE_TVS   I177
  D10      A      A  DIODE_TVS   I181
  D11      A      A  DIODE_TVS   I179
  D12      A      A  DIODE_TVS   I45
  H1       1      1  HOLE        I12
  H2       1      1  HOLE        I14
  H3       1      1  HOLE        I11
  H4       1      1  HOLE        I13
  H5       1      1  HOLE         I9
  H6       1      1  HOLE        I10
  H7       1      1  HOLE         I7
  H8       1      1  HOLE         I8
  H9       1      1  HOLE         I5
  H10      1      1  HOLE         I6
  H11      1      1  HOLE         I3
  H12      1      1  HOLE         I4
  H13      1      1  HOLE         I2
  H31      1      1  HOLE        I31
  H32      1      1  HOLE        I32
  H35      1      1  HOLE        I35
  H37      1      1  HOLE        I36
  H39      1      1  HOLE        I41
  H40      1      1  HOLE        I43
  H44      1      1  HOLE        I49
  H45      1      1  HOLE        I48
  H47      1      1  HOLE        I52
  H49      1      1  HOLE        I53
  H54      1      1  HOLE        I58
  H55      1      1  HOLE        I59
  J1       6   VSS0  SCONN288_ADR50001P013C01  I200
  J1       8   VSS1  SCONN288_ADR50001P013C01  I200
  J1      10   VSS2  SCONN288_ADR50001P013C01  I200
  J1      13   VSS3  SCONN288_ADR50001P013C01  I200
  J1      15   VSS4  SCONN288_ADR50001P013C01  I200
  J1      17   VSS5  SCONN288_ADR50001P013C01  I200
  J1      19   VSS6  SCONN288_ADR50001P013C01  I200
  J1      21   VSS7  SCONN288_ADR50001P013C01  I200
  J1      24   VSS8  SCONN288_ADR50001P013C01  I200
  J1      26   VSS9  SCONN288_ADR50001P013C01  I200
  J1      28  VSS10  SCONN288_ADR50001P013C01  I200
  J1      30  VSS11  SCONN288_ADR50001P013C01  I200
  J1      32  VSS12  SCONN288_ADR50001P013C01  I200
  J1      35  VSS13  SCONN288_ADR50001P013C01  I200
  J1      37  VSS14  SCONN288_ADR50001P013C01  I200
  J1      39  VSS15  SCONN288_ADR50001P013C01  I200
  J1      41  VSS16  SCONN288_ADR50001P013C01  I200
  J1      43  VSS17  SCONN288_ADR50001P013C01  I200
  J1      46  VSS18  SCONN288_ADR50001P013C01  I200
  J1      48  VSS19  SCONN288_ADR50001P013C01  I200
  J1      50  VSS20  SCONN288_ADR50001P013C01  I200
  J1      52  VSS21  SCONN288_ADR50001P013C01  I200
  J1      54  VSS22  SCONN288_ADR50001P013C01  I200
  J1      57  VSS23  SCONN288_ADR50001P013C01  I200
  J1      59  VSS24  SCONN288_ADR50001P013C01  I200
  J1      61  VSS25  SCONN288_ADR50001P013C01  I200
  J1      63  VSS26  SCONN288_ADR50001P013C01  I200
  J1      65  VSS27  SCONN288_ADR50001P013C01  I200
  J1      67  VSS28  SCONN288_ADR50001P013C01  I200
  J1      69  VSS29  SCONN288_ADR50001P013C01  I200
  J1      71  VSS30  SCONN288_ADR50001P013C01  I200
  J1      73  VSS31  SCONN288_ADR50001P013C01  I200
  J1      75  VSS32  SCONN288_ADR50001P013C01  I200
  J1      77  VSS33  SCONN288_ADR50001P013C01  I200
  J1      79  VSS34  SCONN288_ADR50001P013C01  I200
  J1      81  VSS35  SCONN288_ADR50001P013C01  I200
  J1      83  VSS36  SCONN288_ADR50001P013C01  I200
  J1      85  VSS37  SCONN288_ADR50001P013C01  I200
  J1      88  VSS38  SCONN288_ADR50001P013C01  I200
  J1      90  VSS39  SCONN288_ADR50001P013C01  I200
  J1      92  VSS40  SCONN288_ADR50001P013C01  I200
  J1      95  VSS41  SCONN288_ADR50001P013C01  I200
  J1      97  VSS42  SCONN288_ADR50001P013C01  I200
  J1      99  VSS43  SCONN288_ADR50001P013C01  I200
  J1     101  VSS44  SCONN288_ADR50001P013C01  I200
  J1     103  VSS45  SCONN288_ADR50001P013C01  I200
  J1     106  VSS46  SCONN288_ADR50001P013C01  I200
  J1     108  VSS47  SCONN288_ADR50001P013C01  I200
  J1     110  VSS48  SCONN288_ADR50001P013C01  I200
  J1     112  VSS49  SCONN288_ADR50001P013C01  I200
  J1     114  VSS50  SCONN288_ADR50001P013C01  I200
  J1     117  VSS51  SCONN288_ADR50001P013C01  I200
  J1     119  VSS52  SCONN288_ADR50001P013C01  I200
  J1     121  VSS53  SCONN288_ADR50001P013C01  I200
  J1     123  VSS54  SCONN288_ADR50001P013C01  I200
  J1     125  VSS55  SCONN288_ADR50001P013C01  I200
  J1     128  VSS56  SCONN288_ADR50001P013C01  I200
  J1     130  VSS57  SCONN288_ADR50001P013C01  I200
  J1     132  VSS58  SCONN288_ADR50001P013C01  I200
  J1     134  VSS59  SCONN288_ADR50001P013C01  I200
  J1     136  VSS60  SCONN288_ADR50001P013C01  I200
  J1     139  VSS61  SCONN288_ADR50001P013C01  I200
  J1     141  VSS62  SCONN288_ADR50001P013C01  I200
  J1     143  VSS63  SCONN288_ADR50001P013C01  I200
  J1     151  VSS64  SCONN288_ADR50001P013C01  I200
  J1     153  VSS65  SCONN288_ADR50001P013C01  I200
  J1     155  VSS66  SCONN288_ADR50001P013C01  I200
  J1     158  VSS67  SCONN288_ADR50001P013C01  I200
  J1     160  VSS68  SCONN288_ADR50001P013C01  I200
  J1     162  VSS69  SCONN288_ADR50001P013C01  I200
  J1     164  VSS70  SCONN288_ADR50001P013C01  I200
  J1     166  VSS71  SCONN288_ADR50001P013C01  I200
  J1     169  VSS72  SCONN288_ADR50001P013C01  I200
  J1     171  VSS73  SCONN288_ADR50001P013C01  I200
  J1     173  VSS74  SCONN288_ADR50001P013C01  I200
  J1     175  VSS75  SCONN288_ADR50001P013C01  I200
  J1     177  VSS76  SCONN288_ADR50001P013C01  I200
  J1     180  VSS77  SCONN288_ADR50001P013C01  I200
  J1     182  VSS78  SCONN288_ADR50001P013C01  I200
  J1     184  VSS79  SCONN288_ADR50001P013C01  I200
  J1     186  VSS80  SCONN288_ADR50001P013C01  I200
  J1     188  VSS81  SCONN288_ADR50001P013C01  I200
  J1     191  VSS82  SCONN288_ADR50001P013C01  I200
  J1     193  VSS83  SCONN288_ADR50001P013C01  I200
  J1     195  VSS84  SCONN288_ADR50001P013C01  I200
  J1     197  VSS85  SCONN288_ADR50001P013C01  I200
  J1     199  VSS86  SCONN288_ADR50001P013C01  I200
  J1     202  VSS87  SCONN288_ADR50001P013C01  I200
  J1     204  VSS88  SCONN288_ADR50001P013C01  I200
  J1     206  VSS89  SCONN288_ADR50001P013C01  I200
  J1     208  VSS90  SCONN288_ADR50001P013C01  I200
  J1     210  VSS91  SCONN288_ADR50001P013C01  I200
  J1     212  VSS92  SCONN288_ADR50001P013C01  I200
  J1     214  VSS93  SCONN288_ADR50001P013C01  I200
  J1     216  VSS94  SCONN288_ADR50001P013C01  I200
  J1     219  VSS95  SCONN288_ADR50001P013C01  I200
  J1     222  VSS96  SCONN288_ADR50001P013C01  I200
  J1     224  VSS97  SCONN288_ADR50001P013C01  I200
  J1     226  VSS98  SCONN288_ADR50001P013C01  I200
  J1     228  VSS99  SCONN288_ADR50001P013C01  I200
  J1     230  VSS100  SCONN288_ADR50001P013C01  I200
  J1     233  VSS101  SCONN288_ADR50001P013C01  I200
  J1     235  VSS102  SCONN288_ADR50001P013C01  I200
  J1     237  VSS103  SCONN288_ADR50001P013C01  I200
  J1     240  VSS104  SCONN288_ADR50001P013C01  I200
  J1     242  VSS105  SCONN288_ADR50001P013C01  I200
  J1     244  VSS106  SCONN288_ADR50001P013C01  I200
  J1     246  VSS107  SCONN288_ADR50001P013C01  I200
  J1     248  VSS108  SCONN288_ADR50001P013C01  I200
  J1     251  VSS109  SCONN288_ADR50001P013C01  I200
  J1     253  VSS110  SCONN288_ADR50001P013C01  I200
  J1     255  VSS111  SCONN288_ADR50001P013C01  I200
  J1     257  VSS112  SCONN288_ADR50001P013C01  I200
  J1     259  VSS113  SCONN288_ADR50001P013C01  I200
  J1     262  VSS114  SCONN288_ADR50001P013C01  I200
  J1     264  VSS115  SCONN288_ADR50001P013C01  I200
  J1     266  VSS116  SCONN288_ADR50001P013C01  I200
  J1     268  VSS117  SCONN288_ADR50001P013C01  I200
  J1     270  VSS118  SCONN288_ADR50001P013C01  I200
  J1     273  VSS119  SCONN288_ADR50001P013C01  I200
  J1     275  VSS120  SCONN288_ADR50001P013C01  I200
  J1     277  VSS121  SCONN288_ADR50001P013C01  I200
  J1     279  VSS122  SCONN288_ADR50001P013C01  I200
  J1     281  VSS123  SCONN288_ADR50001P013C01  I200
  J1     284  VSS124  SCONN288_ADR50001P013C01  I200
  J1     286  VSS125  SCONN288_ADR50001P013C01  I200
  J1     288  VSS126  SCONN288_ADR50001P013C01  I200
  J1      G1     G1  SCONN288_ADR50001P013C01  I200
  J1      G2     G2  SCONN288_ADR50001P013C01  I200
  J1      G3     G3  SCONN288_ADR50001P013C01  I200
  J2       6   VSS0  SCONN288_ADR50001P003C01  I179
  J2       8   VSS1  SCONN288_ADR50001P003C01  I179
  J2      10   VSS2  SCONN288_ADR50001P003C01  I179
  J2      13   VSS3  SCONN288_ADR50001P003C01  I179
  J2      15   VSS4  SCONN288_ADR50001P003C01  I179
  J2      17   VSS5  SCONN288_ADR50001P003C01  I179
  J2      19   VSS6  SCONN288_ADR50001P003C01  I179
  J2      21   VSS7  SCONN288_ADR50001P003C01  I179
  J2      24   VSS8  SCONN288_ADR50001P003C01  I179
  J2      26   VSS9  SCONN288_ADR50001P003C01  I179
  J2      28  VSS10  SCONN288_ADR50001P003C01  I179
  J2      30  VSS11  SCONN288_ADR50001P003C01  I179
  J2      32  VSS12  SCONN288_ADR50001P003C01  I179
  J2      35  VSS13  SCONN288_ADR50001P003C01  I179
  J2      37  VSS14  SCONN288_ADR50001P003C01  I179
  J2      39  VSS15  SCONN288_ADR50001P003C01  I179
  J2      41  VSS16  SCONN288_ADR50001P003C01  I179
  J2      43  VSS17  SCONN288_ADR50001P003C01  I179
  J2      46  VSS18  SCONN288_ADR50001P003C01  I179
  J2      48  VSS19  SCONN288_ADR50001P003C01  I179
  J2      50  VSS20  SCONN288_ADR50001P003C01  I179
  J2      52  VSS21  SCONN288_ADR50001P003C01  I179
  J2      54  VSS22  SCONN288_ADR50001P003C01  I179
  J2      57  VSS23  SCONN288_ADR50001P003C01  I179
  J2      59  VSS24  SCONN288_ADR50001P003C01  I179
  J2      61  VSS25  SCONN288_ADR50001P003C01  I179
  J2      63  VSS26  SCONN288_ADR50001P003C01  I179
  J2      65  VSS27  SCONN288_ADR50001P003C01  I179
  J2      67  VSS28  SCONN288_ADR50001P003C01  I179
  J2      69  VSS29  SCONN288_ADR50001P003C01  I179
  J2      71  VSS30  SCONN288_ADR50001P003C01  I179
  J2      73  VSS31  SCONN288_ADR50001P003C01  I179
  J2      75  VSS32  SCONN288_ADR50001P003C01  I179
  J2      77  VSS33  SCONN288_ADR50001P003C01  I179
  J2      79  VSS34  SCONN288_ADR50001P003C01  I179
  J2      81  VSS35  SCONN288_ADR50001P003C01  I179
  J2      83  VSS36  SCONN288_ADR50001P003C01  I179
  J2      85  VSS37  SCONN288_ADR50001P003C01  I179
  J2      88  VSS38  SCONN288_ADR50001P003C01  I179
  J2      90  VSS39  SCONN288_ADR50001P003C01  I179
  J2      92  VSS40  SCONN288_ADR50001P003C01  I179
  J2      95  VSS41  SCONN288_ADR50001P003C01  I179
  J2      97  VSS42  SCONN288_ADR50001P003C01  I179
  J2      99  VSS43  SCONN288_ADR50001P003C01  I179
  J2     101  VSS44  SCONN288_ADR50001P003C01  I179
  J2     103  VSS45  SCONN288_ADR50001P003C01  I179
  J2     106  VSS46  SCONN288_ADR50001P003C01  I179
  J2     108  VSS47  SCONN288_ADR50001P003C01  I179
  J2     110  VSS48  SCONN288_ADR50001P003C01  I179
  J2     112  VSS49  SCONN288_ADR50001P003C01  I179
  J2     114  VSS50  SCONN288_ADR50001P003C01  I179
  J2     117  VSS51  SCONN288_ADR50001P003C01  I179
  J2     119  VSS52  SCONN288_ADR50001P003C01  I179
  J2     121  VSS53  SCONN288_ADR50001P003C01  I179
  J2     123  VSS54  SCONN288_ADR50001P003C01  I179
  J2     125  VSS55  SCONN288_ADR50001P003C01  I179
  J2     128  VSS56  SCONN288_ADR50001P003C01  I179
  J2     130  VSS57  SCONN288_ADR50001P003C01  I179
  J2     132  VSS58  SCONN288_ADR50001P003C01  I179
  J2     134  VSS59  SCONN288_ADR50001P003C01  I179
  J2     136  VSS60  SCONN288_ADR50001P003C01  I179
  J2     139  VSS61  SCONN288_ADR50001P003C01  I179
  J2     141  VSS62  SCONN288_ADR50001P003C01  I179
  J2     143  VSS63  SCONN288_ADR50001P003C01  I179
  J2     151  VSS64  SCONN288_ADR50001P003C01  I179
  J2     153  VSS65  SCONN288_ADR50001P003C01  I179
  J2     155  VSS66  SCONN288_ADR50001P003C01  I179
  J2     158  VSS67  SCONN288_ADR50001P003C01  I179
  J2     160  VSS68  SCONN288_ADR50001P003C01  I179
  J2     162  VSS69  SCONN288_ADR50001P003C01  I179
  J2     164  VSS70  SCONN288_ADR50001P003C01  I179
  J2     166  VSS71  SCONN288_ADR50001P003C01  I179
  J2     169  VSS72  SCONN288_ADR50001P003C01  I179
  J2     171  VSS73  SCONN288_ADR50001P003C01  I179
  J2     173  VSS74  SCONN288_ADR50001P003C01  I179
  J2     175  VSS75  SCONN288_ADR50001P003C01  I179
  J2     177  VSS76  SCONN288_ADR50001P003C01  I179
  J2     180  VSS77  SCONN288_ADR50001P003C01  I179
  J2     182  VSS78  SCONN288_ADR50001P003C01  I179
  J2     184  VSS79  SCONN288_ADR50001P003C01  I179
  J2     186  VSS80  SCONN288_ADR50001P003C01  I179
  J2     188  VSS81  SCONN288_ADR50001P003C01  I179
  J2     191  VSS82  SCONN288_ADR50001P003C01  I179
  J2     193  VSS83  SCONN288_ADR50001P003C01  I179
  J2     195  VSS84  SCONN288_ADR50001P003C01  I179
  J2     197  VSS85  SCONN288_ADR50001P003C01  I179
  J2     199  VSS86  SCONN288_ADR50001P003C01  I179
  J2     202  VSS87  SCONN288_ADR50001P003C01  I179
  J2     204  VSS88  SCONN288_ADR50001P003C01  I179
  J2     206  VSS89  SCONN288_ADR50001P003C01  I179
  J2     208  VSS90  SCONN288_ADR50001P003C01  I179
  J2     210  VSS91  SCONN288_ADR50001P003C01  I179
  J2     212  VSS92  SCONN288_ADR50001P003C01  I179
  J2     214  VSS93  SCONN288_ADR50001P003C01  I179
  J2     216  VSS94  SCONN288_ADR50001P003C01  I179
  J2     219  VSS95  SCONN288_ADR50001P003C01  I179
  J2     222  VSS96  SCONN288_ADR50001P003C01  I179
  J2     224  VSS97  SCONN288_ADR50001P003C01  I179
  J2     226  VSS98  SCONN288_ADR50001P003C01  I179
  J2     228  VSS99  SCONN288_ADR50001P003C01  I179
  J2     230  VSS100  SCONN288_ADR50001P003C01  I179
  J2     233  VSS101  SCONN288_ADR50001P003C01  I179
  J2     235  VSS102  SCONN288_ADR50001P003C01  I179
  J2     237  VSS103  SCONN288_ADR50001P003C01  I179
  J2     240  VSS104  SCONN288_ADR50001P003C01  I179
  J2     242  VSS105  SCONN288_ADR50001P003C01  I179
  J2     244  VSS106  SCONN288_ADR50001P003C01  I179
  J2     246  VSS107  SCONN288_ADR50001P003C01  I179
  J2     248  VSS108  SCONN288_ADR50001P003C01  I179
  J2     251  VSS109  SCONN288_ADR50001P003C01  I179
  J2     253  VSS110  SCONN288_ADR50001P003C01  I179
  J2     255  VSS111  SCONN288_ADR50001P003C01  I179
  J2     257  VSS112  SCONN288_ADR50001P003C01  I179
  J2     259  VSS113  SCONN288_ADR50001P003C01  I179
  J2     262  VSS114  SCONN288_ADR50001P003C01  I179
  J2     264  VSS115  SCONN288_ADR50001P003C01  I179
  J2     266  VSS116  SCONN288_ADR50001P003C01  I179
  J2     268  VSS117  SCONN288_ADR50001P003C01  I179
  J2     270  VSS118  SCONN288_ADR50001P003C01  I179
  J2     273  VSS119  SCONN288_ADR50001P003C01  I179
  J2     275  VSS120  SCONN288_ADR50001P003C01  I179
  J2     277  VSS121  SCONN288_ADR50001P003C01  I179
  J2     279  VSS122  SCONN288_ADR50001P003C01  I179
  J2     281  VSS123  SCONN288_ADR50001P003C01  I179
  J2     284  VSS124  SCONN288_ADR50001P003C01  I179
  J2     286  VSS125  SCONN288_ADR50001P003C01  I179
  J2     288  VSS126  SCONN288_ADR50001P003C01  I179
  J2      G1     G1  SCONN288_ADR50001P003C01  I179
  J2      G2     G2  SCONN288_ADR50001P003C01  I179
  J2      G3     G3  SCONN288_ADR50001P003C01  I179
  J3       6   VSS0  SCONN288_ADR50001P013C01  I146
  J3       8   VSS1  SCONN288_ADR50001P013C01  I146
  J3      10   VSS2  SCONN288_ADR50001P013C01  I146
  J3      13   VSS3  SCONN288_ADR50001P013C01  I146
  J3      15   VSS4  SCONN288_ADR50001P013C01  I146
  J3      17   VSS5  SCONN288_ADR50001P013C01  I146
  J3      19   VSS6  SCONN288_ADR50001P013C01  I146
  J3      21   VSS7  SCONN288_ADR50001P013C01  I146
  J3      24   VSS8  SCONN288_ADR50001P013C01  I146
  J3      26   VSS9  SCONN288_ADR50001P013C01  I146
  J3      28  VSS10  SCONN288_ADR50001P013C01  I146
  J3      30  VSS11  SCONN288_ADR50001P013C01  I146
  J3      32  VSS12  SCONN288_ADR50001P013C01  I146
  J3      35  VSS13  SCONN288_ADR50001P013C01  I146
  J3      37  VSS14  SCONN288_ADR50001P013C01  I146
  J3      39  VSS15  SCONN288_ADR50001P013C01  I146
  J3      41  VSS16  SCONN288_ADR50001P013C01  I146
  J3      43  VSS17  SCONN288_ADR50001P013C01  I146
  J3      46  VSS18  SCONN288_ADR50001P013C01  I146
  J3      48  VSS19  SCONN288_ADR50001P013C01  I146
  J3      50  VSS20  SCONN288_ADR50001P013C01  I146
  J3      52  VSS21  SCONN288_ADR50001P013C01  I146
  J3      54  VSS22  SCONN288_ADR50001P013C01  I146
  J3      57  VSS23  SCONN288_ADR50001P013C01  I146
  J3      59  VSS24  SCONN288_ADR50001P013C01  I146
  J3      61  VSS25  SCONN288_ADR50001P013C01  I146
  J3      63  VSS26  SCONN288_ADR50001P013C01  I146
  J3      65  VSS27  SCONN288_ADR50001P013C01  I146
  J3      67  VSS28  SCONN288_ADR50001P013C01  I146
  J3      69  VSS29  SCONN288_ADR50001P013C01  I146
  J3      71  VSS30  SCONN288_ADR50001P013C01  I146
  J3      73  VSS31  SCONN288_ADR50001P013C01  I146
  J3      75  VSS32  SCONN288_ADR50001P013C01  I146
  J3      77  VSS33  SCONN288_ADR50001P013C01  I146
  J3      79  VSS34  SCONN288_ADR50001P013C01  I146
  J3      81  VSS35  SCONN288_ADR50001P013C01  I146
  J3      83  VSS36  SCONN288_ADR50001P013C01  I146
  J3      85  VSS37  SCONN288_ADR50001P013C01  I146
  J3      88  VSS38  SCONN288_ADR50001P013C01  I146
  J3      90  VSS39  SCONN288_ADR50001P013C01  I146
  J3      92  VSS40  SCONN288_ADR50001P013C01  I146
  J3      95  VSS41  SCONN288_ADR50001P013C01  I146
  J3      97  VSS42  SCONN288_ADR50001P013C01  I146
  J3      99  VSS43  SCONN288_ADR50001P013C01  I146
  J3     101  VSS44  SCONN288_ADR50001P013C01  I146
  J3     103  VSS45  SCONN288_ADR50001P013C01  I146
  J3     106  VSS46  SCONN288_ADR50001P013C01  I146
  J3     108  VSS47  SCONN288_ADR50001P013C01  I146
  J3     110  VSS48  SCONN288_ADR50001P013C01  I146
  J3     112  VSS49  SCONN288_ADR50001P013C01  I146
  J3     114  VSS50  SCONN288_ADR50001P013C01  I146
  J3     117  VSS51  SCONN288_ADR50001P013C01  I146
  J3     119  VSS52  SCONN288_ADR50001P013C01  I146
  J3     121  VSS53  SCONN288_ADR50001P013C01  I146
  J3     123  VSS54  SCONN288_ADR50001P013C01  I146
  J3     125  VSS55  SCONN288_ADR50001P013C01  I146
  J3     128  VSS56  SCONN288_ADR50001P013C01  I146
  J3     130  VSS57  SCONN288_ADR50001P013C01  I146
  J3     132  VSS58  SCONN288_ADR50001P013C01  I146
  J3     134  VSS59  SCONN288_ADR50001P013C01  I146
  J3     136  VSS60  SCONN288_ADR50001P013C01  I146
  J3     139  VSS61  SCONN288_ADR50001P013C01  I146
  J3     141  VSS62  SCONN288_ADR50001P013C01  I146
  J3     143  VSS63  SCONN288_ADR50001P013C01  I146
  J3     151  VSS64  SCONN288_ADR50001P013C01  I146
  J3     153  VSS65  SCONN288_ADR50001P013C01  I146
  J3     155  VSS66  SCONN288_ADR50001P013C01  I146
  J3     158  VSS67  SCONN288_ADR50001P013C01  I146
  J3     160  VSS68  SCONN288_ADR50001P013C01  I146
  J3     162  VSS69  SCONN288_ADR50001P013C01  I146
  J3     164  VSS70  SCONN288_ADR50001P013C01  I146
  J3     166  VSS71  SCONN288_ADR50001P013C01  I146
  J3     169  VSS72  SCONN288_ADR50001P013C01  I146
  J3     171  VSS73  SCONN288_ADR50001P013C01  I146
  J3     173  VSS74  SCONN288_ADR50001P013C01  I146
  J3     175  VSS75  SCONN288_ADR50001P013C01  I146
  J3     177  VSS76  SCONN288_ADR50001P013C01  I146
  J3     180  VSS77  SCONN288_ADR50001P013C01  I146
  J3     182  VSS78  SCONN288_ADR50001P013C01  I146
  J3     184  VSS79  SCONN288_ADR50001P013C01  I146
  J3     186  VSS80  SCONN288_ADR50001P013C01  I146
  J3     188  VSS81  SCONN288_ADR50001P013C01  I146
  J3     191  VSS82  SCONN288_ADR50001P013C01  I146
  J3     193  VSS83  SCONN288_ADR50001P013C01  I146
  J3     195  VSS84  SCONN288_ADR50001P013C01  I146
  J3     197  VSS85  SCONN288_ADR50001P013C01  I146
  J3     199  VSS86  SCONN288_ADR50001P013C01  I146
  J3     202  VSS87  SCONN288_ADR50001P013C01  I146
  J3     204  VSS88  SCONN288_ADR50001P013C01  I146
  J3     206  VSS89  SCONN288_ADR50001P013C01  I146
  J3     208  VSS90  SCONN288_ADR50001P013C01  I146
  J3     210  VSS91  SCONN288_ADR50001P013C01  I146
  J3     212  VSS92  SCONN288_ADR50001P013C01  I146
  J3     214  VSS93  SCONN288_ADR50001P013C01  I146
  J3     216  VSS94  SCONN288_ADR50001P013C01  I146
  J3     219  VSS95  SCONN288_ADR50001P013C01  I146
  J3     222  VSS96  SCONN288_ADR50001P013C01  I146
  J3     224  VSS97  SCONN288_ADR50001P013C01  I146
  J3     226  VSS98  SCONN288_ADR50001P013C01  I146
  J3     228  VSS99  SCONN288_ADR50001P013C01  I146
  J3     230  VSS100  SCONN288_ADR50001P013C01  I146
  J3     233  VSS101  SCONN288_ADR50001P013C01  I146
  J3     235  VSS102  SCONN288_ADR50001P013C01  I146
  J3     237  VSS103  SCONN288_ADR50001P013C01  I146
  J3     240  VSS104  SCONN288_ADR50001P013C01  I146
  J3     242  VSS105  SCONN288_ADR50001P013C01  I146
  J3     244  VSS106  SCONN288_ADR50001P013C01  I146
  J3     246  VSS107  SCONN288_ADR50001P013C01  I146
  J3     248  VSS108  SCONN288_ADR50001P013C01  I146
  J3     251  VSS109  SCONN288_ADR50001P013C01  I146
  J3     253  VSS110  SCONN288_ADR50001P013C01  I146
  J3     255  VSS111  SCONN288_ADR50001P013C01  I146
  J3     257  VSS112  SCONN288_ADR50001P013C01  I146
  J3     259  VSS113  SCONN288_ADR50001P013C01  I146
  J3     262  VSS114  SCONN288_ADR50001P013C01  I146
  J3     264  VSS115  SCONN288_ADR50001P013C01  I146
  J3     266  VSS116  SCONN288_ADR50001P013C01  I146
  J3     268  VSS117  SCONN288_ADR50001P013C01  I146
  J3     270  VSS118  SCONN288_ADR50001P013C01  I146
  J3     273  VSS119  SCONN288_ADR50001P013C01  I146
  J3     275  VSS120  SCONN288_ADR50001P013C01  I146
  J3     277  VSS121  SCONN288_ADR50001P013C01  I146
  J3     279  VSS122  SCONN288_ADR50001P013C01  I146
  J3     281  VSS123  SCONN288_ADR50001P013C01  I146
  J3     284  VSS124  SCONN288_ADR50001P013C01  I146
  J3     286  VSS125  SCONN288_ADR50001P013C01  I146
  J3     288  VSS126  SCONN288_ADR50001P013C01  I146
  J3      G1     G1  SCONN288_ADR50001P013C01  I146
  J3      G2     G2  SCONN288_ADR50001P013C01  I146
  J3      G3     G3  SCONN288_ADR50001P013C01  I146
  J4       6   VSS0  SCONN288_ADR50001P003C01  I174
  J4       8   VSS1  SCONN288_ADR50001P003C01  I174
  J4      10   VSS2  SCONN288_ADR50001P003C01  I174
  J4      13   VSS3  SCONN288_ADR50001P003C01  I174
  J4      15   VSS4  SCONN288_ADR50001P003C01  I174
  J4      17   VSS5  SCONN288_ADR50001P003C01  I174
  J4      19   VSS6  SCONN288_ADR50001P003C01  I174
  J4      21   VSS7  SCONN288_ADR50001P003C01  I174
  J4      24   VSS8  SCONN288_ADR50001P003C01  I174
  J4      26   VSS9  SCONN288_ADR50001P003C01  I174
  J4      28  VSS10  SCONN288_ADR50001P003C01  I174
  J4      30  VSS11  SCONN288_ADR50001P003C01  I174
  J4      32  VSS12  SCONN288_ADR50001P003C01  I174
  J4      35  VSS13  SCONN288_ADR50001P003C01  I174
  J4      37  VSS14  SCONN288_ADR50001P003C01  I174
  J4      39  VSS15  SCONN288_ADR50001P003C01  I174
  J4      41  VSS16  SCONN288_ADR50001P003C01  I174
  J4      43  VSS17  SCONN288_ADR50001P003C01  I174
  J4      46  VSS18  SCONN288_ADR50001P003C01  I174
  J4      48  VSS19  SCONN288_ADR50001P003C01  I174
  J4      50  VSS20  SCONN288_ADR50001P003C01  I174
  J4      52  VSS21  SCONN288_ADR50001P003C01  I174
  J4      54  VSS22  SCONN288_ADR50001P003C01  I174
  J4      57  VSS23  SCONN288_ADR50001P003C01  I174
  J4      59  VSS24  SCONN288_ADR50001P003C01  I174
  J4      61  VSS25  SCONN288_ADR50001P003C01  I174
  J4      63  VSS26  SCONN288_ADR50001P003C01  I174
  J4      65  VSS27  SCONN288_ADR50001P003C01  I174
  J4      67  VSS28  SCONN288_ADR50001P003C01  I174
  J4      69  VSS29  SCONN288_ADR50001P003C01  I174
  J4      71  VSS30  SCONN288_ADR50001P003C01  I174
  J4      73  VSS31  SCONN288_ADR50001P003C01  I174
  J4      75  VSS32  SCONN288_ADR50001P003C01  I174
  J4      77  VSS33  SCONN288_ADR50001P003C01  I174
  J4      79  VSS34  SCONN288_ADR50001P003C01  I174
  J4      81  VSS35  SCONN288_ADR50001P003C01  I174
  J4      83  VSS36  SCONN288_ADR50001P003C01  I174
  J4      85  VSS37  SCONN288_ADR50001P003C01  I174
  J4      88  VSS38  SCONN288_ADR50001P003C01  I174
  J4      90  VSS39  SCONN288_ADR50001P003C01  I174
  J4      92  VSS40  SCONN288_ADR50001P003C01  I174
  J4      95  VSS41  SCONN288_ADR50001P003C01  I174
  J4      97  VSS42  SCONN288_ADR50001P003C01  I174
  J4      99  VSS43  SCONN288_ADR50001P003C01  I174
  J4     101  VSS44  SCONN288_ADR50001P003C01  I174
  J4     103  VSS45  SCONN288_ADR50001P003C01  I174
  J4     106  VSS46  SCONN288_ADR50001P003C01  I174
  J4     108  VSS47  SCONN288_ADR50001P003C01  I174
  J4     110  VSS48  SCONN288_ADR50001P003C01  I174
  J4     112  VSS49  SCONN288_ADR50001P003C01  I174
  J4     114  VSS50  SCONN288_ADR50001P003C01  I174
  J4     117  VSS51  SCONN288_ADR50001P003C01  I174
  J4     119  VSS52  SCONN288_ADR50001P003C01  I174
  J4     121  VSS53  SCONN288_ADR50001P003C01  I174
  J4     123  VSS54  SCONN288_ADR50001P003C01  I174
  J4     125  VSS55  SCONN288_ADR50001P003C01  I174
  J4     128  VSS56  SCONN288_ADR50001P003C01  I174
  J4     130  VSS57  SCONN288_ADR50001P003C01  I174
  J4     132  VSS58  SCONN288_ADR50001P003C01  I174
  J4     134  VSS59  SCONN288_ADR50001P003C01  I174
  J4     136  VSS60  SCONN288_ADR50001P003C01  I174
  J4     139  VSS61  SCONN288_ADR50001P003C01  I174
  J4     141  VSS62  SCONN288_ADR50001P003C01  I174
  J4     143  VSS63  SCONN288_ADR50001P003C01  I174
  J4     151  VSS64  SCONN288_ADR50001P003C01  I174
  J4     153  VSS65  SCONN288_ADR50001P003C01  I174
  J4     155  VSS66  SCONN288_ADR50001P003C01  I174
  J4     158  VSS67  SCONN288_ADR50001P003C01  I174
  J4     160  VSS68  SCONN288_ADR50001P003C01  I174
  J4     162  VSS69  SCONN288_ADR50001P003C01  I174
  J4     164  VSS70  SCONN288_ADR50001P003C01  I174
  J4     166  VSS71  SCONN288_ADR50001P003C01  I174
  J4     169  VSS72  SCONN288_ADR50001P003C01  I174
  J4     171  VSS73  SCONN288_ADR50001P003C01  I174
  J4     173  VSS74  SCONN288_ADR50001P003C01  I174
  J4     175  VSS75  SCONN288_ADR50001P003C01  I174
  J4     177  VSS76  SCONN288_ADR50001P003C01  I174
  J4     180  VSS77  SCONN288_ADR50001P003C01  I174
  J4     182  VSS78  SCONN288_ADR50001P003C01  I174
  J4     184  VSS79  SCONN288_ADR50001P003C01  I174
  J4     186  VSS80  SCONN288_ADR50001P003C01  I174
  J4     188  VSS81  SCONN288_ADR50001P003C01  I174
  J4     191  VSS82  SCONN288_ADR50001P003C01  I174
  J4     193  VSS83  SCONN288_ADR50001P003C01  I174
  J4     195  VSS84  SCONN288_ADR50001P003C01  I174
  J4     197  VSS85  SCONN288_ADR50001P003C01  I174
  J4     199  VSS86  SCONN288_ADR50001P003C01  I174
  J4     202  VSS87  SCONN288_ADR50001P003C01  I174
  J4     204  VSS88  SCONN288_ADR50001P003C01  I174
  J4     206  VSS89  SCONN288_ADR50001P003C01  I174
  J4     208  VSS90  SCONN288_ADR50001P003C01  I174
  J4     210  VSS91  SCONN288_ADR50001P003C01  I174
  J4     212  VSS92  SCONN288_ADR50001P003C01  I174
  J4     214  VSS93  SCONN288_ADR50001P003C01  I174
  J4     216  VSS94  SCONN288_ADR50001P003C01  I174
  J4     219  VSS95  SCONN288_ADR50001P003C01  I174
  J4     222  VSS96  SCONN288_ADR50001P003C01  I174
  J4     224  VSS97  SCONN288_ADR50001P003C01  I174
  J4     226  VSS98  SCONN288_ADR50001P003C01  I174
  J4     228  VSS99  SCONN288_ADR50001P003C01  I174
  J4     230  VSS100  SCONN288_ADR50001P003C01  I174
  J4     233  VSS101  SCONN288_ADR50001P003C01  I174
  J4     235  VSS102  SCONN288_ADR50001P003C01  I174
  J4     237  VSS103  SCONN288_ADR50001P003C01  I174
  J4     240  VSS104  SCONN288_ADR50001P003C01  I174
  J4     242  VSS105  SCONN288_ADR50001P003C01  I174
  J4     244  VSS106  SCONN288_ADR50001P003C01  I174
  J4     246  VSS107  SCONN288_ADR50001P003C01  I174
  J4     248  VSS108  SCONN288_ADR50001P003C01  I174
  J4     251  VSS109  SCONN288_ADR50001P003C01  I174
  J4     253  VSS110  SCONN288_ADR50001P003C01  I174
  J4     255  VSS111  SCONN288_ADR50001P003C01  I174
  J4     257  VSS112  SCONN288_ADR50001P003C01  I174
  J4     259  VSS113  SCONN288_ADR50001P003C01  I174
  J4     262  VSS114  SCONN288_ADR50001P003C01  I174
  J4     264  VSS115  SCONN288_ADR50001P003C01  I174
  J4     266  VSS116  SCONN288_ADR50001P003C01  I174
  J4     268  VSS117  SCONN288_ADR50001P003C01  I174
  J4     270  VSS118  SCONN288_ADR50001P003C01  I174
  J4     273  VSS119  SCONN288_ADR50001P003C01  I174
  J4     275  VSS120  SCONN288_ADR50001P003C01  I174
  J4     277  VSS121  SCONN288_ADR50001P003C01  I174
  J4     279  VSS122  SCONN288_ADR50001P003C01  I174
  J4     281  VSS123  SCONN288_ADR50001P003C01  I174
  J4     284  VSS124  SCONN288_ADR50001P003C01  I174
  J4     286  VSS125  SCONN288_ADR50001P003C01  I174
  J4     288  VSS126  SCONN288_ADR50001P003C01  I174
  J4      G1     G1  SCONN288_ADR50001P003C01  I174
  J4      G2     G2  SCONN288_ADR50001P003C01  I174
  J4      G3     G3  SCONN288_ADR50001P003C01  I174
  J5       6   VSS0  SCONN288_ADR50001P013C01  I174
  J5       8   VSS1  SCONN288_ADR50001P013C01  I174
  J5      10   VSS2  SCONN288_ADR50001P013C01  I174
  J5      13   VSS3  SCONN288_ADR50001P013C01  I174
  J5      15   VSS4  SCONN288_ADR50001P013C01  I174
  J5      17   VSS5  SCONN288_ADR50001P013C01  I174
  J5      19   VSS6  SCONN288_ADR50001P013C01  I174
  J5      21   VSS7  SCONN288_ADR50001P013C01  I174
  J5      24   VSS8  SCONN288_ADR50001P013C01  I174
  J5      26   VSS9  SCONN288_ADR50001P013C01  I174
  J5      28  VSS10  SCONN288_ADR50001P013C01  I174
  J5      30  VSS11  SCONN288_ADR50001P013C01  I174
  J5      32  VSS12  SCONN288_ADR50001P013C01  I174
  J5      35  VSS13  SCONN288_ADR50001P013C01  I174
  J5      37  VSS14  SCONN288_ADR50001P013C01  I174
  J5      39  VSS15  SCONN288_ADR50001P013C01  I174
  J5      41  VSS16  SCONN288_ADR50001P013C01  I174
  J5      43  VSS17  SCONN288_ADR50001P013C01  I174
  J5      46  VSS18  SCONN288_ADR50001P013C01  I174
  J5      48  VSS19  SCONN288_ADR50001P013C01  I174
  J5      50  VSS20  SCONN288_ADR50001P013C01  I174
  J5      52  VSS21  SCONN288_ADR50001P013C01  I174
  J5      54  VSS22  SCONN288_ADR50001P013C01  I174
  J5      57  VSS23  SCONN288_ADR50001P013C01  I174
  J5      59  VSS24  SCONN288_ADR50001P013C01  I174
  J5      61  VSS25  SCONN288_ADR50001P013C01  I174
  J5      63  VSS26  SCONN288_ADR50001P013C01  I174
  J5      65  VSS27  SCONN288_ADR50001P013C01  I174
  J5      67  VSS28  SCONN288_ADR50001P013C01  I174
  J5      69  VSS29  SCONN288_ADR50001P013C01  I174
  J5      71  VSS30  SCONN288_ADR50001P013C01  I174
  J5      73  VSS31  SCONN288_ADR50001P013C01  I174
  J5      75  VSS32  SCONN288_ADR50001P013C01  I174
  J5      77  VSS33  SCONN288_ADR50001P013C01  I174
  J5      79  VSS34  SCONN288_ADR50001P013C01  I174
  J5      81  VSS35  SCONN288_ADR50001P013C01  I174
  J5      83  VSS36  SCONN288_ADR50001P013C01  I174
  J5      85  VSS37  SCONN288_ADR50001P013C01  I174
  J5      88  VSS38  SCONN288_ADR50001P013C01  I174
  J5      90  VSS39  SCONN288_ADR50001P013C01  I174
  J5      92  VSS40  SCONN288_ADR50001P013C01  I174
  J5      95  VSS41  SCONN288_ADR50001P013C01  I174
  J5      97  VSS42  SCONN288_ADR50001P013C01  I174
  J5      99  VSS43  SCONN288_ADR50001P013C01  I174
  J5     101  VSS44  SCONN288_ADR50001P013C01  I174
  J5     103  VSS45  SCONN288_ADR50001P013C01  I174
  J5     106  VSS46  SCONN288_ADR50001P013C01  I174
  J5     108  VSS47  SCONN288_ADR50001P013C01  I174
  J5     110  VSS48  SCONN288_ADR50001P013C01  I174
  J5     112  VSS49  SCONN288_ADR50001P013C01  I174
  J5     114  VSS50  SCONN288_ADR50001P013C01  I174
  J5     117  VSS51  SCONN288_ADR50001P013C01  I174
  J5     119  VSS52  SCONN288_ADR50001P013C01  I174
  J5     121  VSS53  SCONN288_ADR50001P013C01  I174
  J5     123  VSS54  SCONN288_ADR50001P013C01  I174
  J5     125  VSS55  SCONN288_ADR50001P013C01  I174
  J5     128  VSS56  SCONN288_ADR50001P013C01  I174
  J5     130  VSS57  SCONN288_ADR50001P013C01  I174
  J5     132  VSS58  SCONN288_ADR50001P013C01  I174
  J5     134  VSS59  SCONN288_ADR50001P013C01  I174
  J5     136  VSS60  SCONN288_ADR50001P013C01  I174
  J5     139  VSS61  SCONN288_ADR50001P013C01  I174
  J5     141  VSS62  SCONN288_ADR50001P013C01  I174
  J5     143  VSS63  SCONN288_ADR50001P013C01  I174
  J5     151  VSS64  SCONN288_ADR50001P013C01  I174
  J5     153  VSS65  SCONN288_ADR50001P013C01  I174
  J5     155  VSS66  SCONN288_ADR50001P013C01  I174
  J5     158  VSS67  SCONN288_ADR50001P013C01  I174
  J5     160  VSS68  SCONN288_ADR50001P013C01  I174
  J5     162  VSS69  SCONN288_ADR50001P013C01  I174
  J5     164  VSS70  SCONN288_ADR50001P013C01  I174
  J5     166  VSS71  SCONN288_ADR50001P013C01  I174
  J5     169  VSS72  SCONN288_ADR50001P013C01  I174
  J5     171  VSS73  SCONN288_ADR50001P013C01  I174
  J5     173  VSS74  SCONN288_ADR50001P013C01  I174
  J5     175  VSS75  SCONN288_ADR50001P013C01  I174
  J5     177  VSS76  SCONN288_ADR50001P013C01  I174
  J5     180  VSS77  SCONN288_ADR50001P013C01  I174
  J5     182  VSS78  SCONN288_ADR50001P013C01  I174
  J5     184  VSS79  SCONN288_ADR50001P013C01  I174
  J5     186  VSS80  SCONN288_ADR50001P013C01  I174
  J5     188  VSS81  SCONN288_ADR50001P013C01  I174
  J5     191  VSS82  SCONN288_ADR50001P013C01  I174
  J5     193  VSS83  SCONN288_ADR50001P013C01  I174
  J5     195  VSS84  SCONN288_ADR50001P013C01  I174
  J5     197  VSS85  SCONN288_ADR50001P013C01  I174
  J5     199  VSS86  SCONN288_ADR50001P013C01  I174
  J5     202  VSS87  SCONN288_ADR50001P013C01  I174
  J5     204  VSS88  SCONN288_ADR50001P013C01  I174
  J5     206  VSS89  SCONN288_ADR50001P013C01  I174
  J5     208  VSS90  SCONN288_ADR50001P013C01  I174
  J5     210  VSS91  SCONN288_ADR50001P013C01  I174
  J5     212  VSS92  SCONN288_ADR50001P013C01  I174
  J5     214  VSS93  SCONN288_ADR50001P013C01  I174
  J5     216  VSS94  SCONN288_ADR50001P013C01  I174
  J5     219  VSS95  SCONN288_ADR50001P013C01  I174
  J5     222  VSS96  SCONN288_ADR50001P013C01  I174
  J5     224  VSS97  SCONN288_ADR50001P013C01  I174
  J5     226  VSS98  SCONN288_ADR50001P013C01  I174
  J5     228  VSS99  SCONN288_ADR50001P013C01  I174
  J5     230  VSS100  SCONN288_ADR50001P013C01  I174
  J5     233  VSS101  SCONN288_ADR50001P013C01  I174
  J5     235  VSS102  SCONN288_ADR50001P013C01  I174
  J5     237  VSS103  SCONN288_ADR50001P013C01  I174
  J5     240  VSS104  SCONN288_ADR50001P013C01  I174
  J5     242  VSS105  SCONN288_ADR50001P013C01  I174
  J5     244  VSS106  SCONN288_ADR50001P013C01  I174
  J5     246  VSS107  SCONN288_ADR50001P013C01  I174
  J5     248  VSS108  SCONN288_ADR50001P013C01  I174
  J5     251  VSS109  SCONN288_ADR50001P013C01  I174
  J5     253  VSS110  SCONN288_ADR50001P013C01  I174
  J5     255  VSS111  SCONN288_ADR50001P013C01  I174
  J5     257  VSS112  SCONN288_ADR50001P013C01  I174
  J5     259  VSS113  SCONN288_ADR50001P013C01  I174
  J5     262  VSS114  SCONN288_ADR50001P013C01  I174
  J5     264  VSS115  SCONN288_ADR50001P013C01  I174
  J5     266  VSS116  SCONN288_ADR50001P013C01  I174
  J5     268  VSS117  SCONN288_ADR50001P013C01  I174
  J5     270  VSS118  SCONN288_ADR50001P013C01  I174
  J5     273  VSS119  SCONN288_ADR50001P013C01  I174
  J5     275  VSS120  SCONN288_ADR50001P013C01  I174
  J5     277  VSS121  SCONN288_ADR50001P013C01  I174
  J5     279  VSS122  SCONN288_ADR50001P013C01  I174
  J5     281  VSS123  SCONN288_ADR50001P013C01  I174
  J5     284  VSS124  SCONN288_ADR50001P013C01  I174
  J5     286  VSS125  SCONN288_ADR50001P013C01  I174
  J5     288  VSS126  SCONN288_ADR50001P013C01  I174
  J5      G1     G1  SCONN288_ADR50001P013C01  I174
  J5      G2     G2  SCONN288_ADR50001P013C01  I174
  J5      G3     G3  SCONN288_ADR50001P013C01  I174
  J6       6   VSS0  SCONN288_ADR50001P003C01  I175
  J6       8   VSS1  SCONN288_ADR50001P003C01  I175
  J6      10   VSS2  SCONN288_ADR50001P003C01  I175
  J6      13   VSS3  SCONN288_ADR50001P003C01  I175
  J6      15   VSS4  SCONN288_ADR50001P003C01  I175
  J6      17   VSS5  SCONN288_ADR50001P003C01  I175
  J6      19   VSS6  SCONN288_ADR50001P003C01  I175
  J6      21   VSS7  SCONN288_ADR50001P003C01  I175
  J6      24   VSS8  SCONN288_ADR50001P003C01  I175
  J6      26   VSS9  SCONN288_ADR50001P003C01  I175
  J6      28  VSS10  SCONN288_ADR50001P003C01  I175
  J6      30  VSS11  SCONN288_ADR50001P003C01  I175
  J6      32  VSS12  SCONN288_ADR50001P003C01  I175
  J6      35  VSS13  SCONN288_ADR50001P003C01  I175
  J6      37  VSS14  SCONN288_ADR50001P003C01  I175
  J6      39  VSS15  SCONN288_ADR50001P003C01  I175
  J6      41  VSS16  SCONN288_ADR50001P003C01  I175
  J6      43  VSS17  SCONN288_ADR50001P003C01  I175
  J6      46  VSS18  SCONN288_ADR50001P003C01  I175
  J6      48  VSS19  SCONN288_ADR50001P003C01  I175
  J6      50  VSS20  SCONN288_ADR50001P003C01  I175
  J6      52  VSS21  SCONN288_ADR50001P003C01  I175
  J6      54  VSS22  SCONN288_ADR50001P003C01  I175
  J6      57  VSS23  SCONN288_ADR50001P003C01  I175
  J6      59  VSS24  SCONN288_ADR50001P003C01  I175
  J6      61  VSS25  SCONN288_ADR50001P003C01  I175
  J6      63  VSS26  SCONN288_ADR50001P003C01  I175
  J6      65  VSS27  SCONN288_ADR50001P003C01  I175
  J6      67  VSS28  SCONN288_ADR50001P003C01  I175
  J6      69  VSS29  SCONN288_ADR50001P003C01  I175
  J6      71  VSS30  SCONN288_ADR50001P003C01  I175
  J6      73  VSS31  SCONN288_ADR50001P003C01  I175
  J6      75  VSS32  SCONN288_ADR50001P003C01  I175
  J6      77  VSS33  SCONN288_ADR50001P003C01  I175
  J6      79  VSS34  SCONN288_ADR50001P003C01  I175
  J6      81  VSS35  SCONN288_ADR50001P003C01  I175
  J6      83  VSS36  SCONN288_ADR50001P003C01  I175
  J6      85  VSS37  SCONN288_ADR50001P003C01  I175
  J6      88  VSS38  SCONN288_ADR50001P003C01  I175
  J6      90  VSS39  SCONN288_ADR50001P003C01  I175
  J6      92  VSS40  SCONN288_ADR50001P003C01  I175
  J6      95  VSS41  SCONN288_ADR50001P003C01  I175
  J6      97  VSS42  SCONN288_ADR50001P003C01  I175
  J6      99  VSS43  SCONN288_ADR50001P003C01  I175
  J6     101  VSS44  SCONN288_ADR50001P003C01  I175
  J6     103  VSS45  SCONN288_ADR50001P003C01  I175
  J6     106  VSS46  SCONN288_ADR50001P003C01  I175
  J6     108  VSS47  SCONN288_ADR50001P003C01  I175
  J6     110  VSS48  SCONN288_ADR50001P003C01  I175
  J6     112  VSS49  SCONN288_ADR50001P003C01  I175
  J6     114  VSS50  SCONN288_ADR50001P003C01  I175
  J6     117  VSS51  SCONN288_ADR50001P003C01  I175
  J6     119  VSS52  SCONN288_ADR50001P003C01  I175
  J6     121  VSS53  SCONN288_ADR50001P003C01  I175
  J6     123  VSS54  SCONN288_ADR50001P003C01  I175
  J6     125  VSS55  SCONN288_ADR50001P003C01  I175
  J6     128  VSS56  SCONN288_ADR50001P003C01  I175
  J6     130  VSS57  SCONN288_ADR50001P003C01  I175
  J6     132  VSS58  SCONN288_ADR50001P003C01  I175
  J6     134  VSS59  SCONN288_ADR50001P003C01  I175
  J6     136  VSS60  SCONN288_ADR50001P003C01  I175
  J6     139  VSS61  SCONN288_ADR50001P003C01  I175
  J6     141  VSS62  SCONN288_ADR50001P003C01  I175
  J6     143  VSS63  SCONN288_ADR50001P003C01  I175
  J6     151  VSS64  SCONN288_ADR50001P003C01  I175
  J6     153  VSS65  SCONN288_ADR50001P003C01  I175
  J6     155  VSS66  SCONN288_ADR50001P003C01  I175
  J6     158  VSS67  SCONN288_ADR50001P003C01  I175
  J6     160  VSS68  SCONN288_ADR50001P003C01  I175
  J6     162  VSS69  SCONN288_ADR50001P003C01  I175
  J6     164  VSS70  SCONN288_ADR50001P003C01  I175
  J6     166  VSS71  SCONN288_ADR50001P003C01  I175
  J6     169  VSS72  SCONN288_ADR50001P003C01  I175
  J6     171  VSS73  SCONN288_ADR50001P003C01  I175
  J6     173  VSS74  SCONN288_ADR50001P003C01  I175
  J6     175  VSS75  SCONN288_ADR50001P003C01  I175
  J6     177  VSS76  SCONN288_ADR50001P003C01  I175
  J6     180  VSS77  SCONN288_ADR50001P003C01  I175
  J6     182  VSS78  SCONN288_ADR50001P003C01  I175
  J6     184  VSS79  SCONN288_ADR50001P003C01  I175
  J6     186  VSS80  SCONN288_ADR50001P003C01  I175
  J6     188  VSS81  SCONN288_ADR50001P003C01  I175
  J6     191  VSS82  SCONN288_ADR50001P003C01  I175
  J6     193  VSS83  SCONN288_ADR50001P003C01  I175
  J6     195  VSS84  SCONN288_ADR50001P003C01  I175
  J6     197  VSS85  SCONN288_ADR50001P003C01  I175
  J6     199  VSS86  SCONN288_ADR50001P003C01  I175
  J6     202  VSS87  SCONN288_ADR50001P003C01  I175
  J6     204  VSS88  SCONN288_ADR50001P003C01  I175
  J6     206  VSS89  SCONN288_ADR50001P003C01  I175
  J6     208  VSS90  SCONN288_ADR50001P003C01  I175
  J6     210  VSS91  SCONN288_ADR50001P003C01  I175
  J6     212  VSS92  SCONN288_ADR50001P003C01  I175
  J6     214  VSS93  SCONN288_ADR50001P003C01  I175
  J6     216  VSS94  SCONN288_ADR50001P003C01  I175
  J6     219  VSS95  SCONN288_ADR50001P003C01  I175
  J6     222  VSS96  SCONN288_ADR50001P003C01  I175
  J6     224  VSS97  SCONN288_ADR50001P003C01  I175
  J6     226  VSS98  SCONN288_ADR50001P003C01  I175
  J6     228  VSS99  SCONN288_ADR50001P003C01  I175
  J6     230  VSS100  SCONN288_ADR50001P003C01  I175
  J6     233  VSS101  SCONN288_ADR50001P003C01  I175
  J6     235  VSS102  SCONN288_ADR50001P003C01  I175
  J6     237  VSS103  SCONN288_ADR50001P003C01  I175
  J6     240  VSS104  SCONN288_ADR50001P003C01  I175
  J6     242  VSS105  SCONN288_ADR50001P003C01  I175
  J6     244  VSS106  SCONN288_ADR50001P003C01  I175
  J6     246  VSS107  SCONN288_ADR50001P003C01  I175
  J6     248  VSS108  SCONN288_ADR50001P003C01  I175
  J6     251  VSS109  SCONN288_ADR50001P003C01  I175
  J6     253  VSS110  SCONN288_ADR50001P003C01  I175
  J6     255  VSS111  SCONN288_ADR50001P003C01  I175
  J6     257  VSS112  SCONN288_ADR50001P003C01  I175
  J6     259  VSS113  SCONN288_ADR50001P003C01  I175
  J6     262  VSS114  SCONN288_ADR50001P003C01  I175
  J6     264  VSS115  SCONN288_ADR50001P003C01  I175
  J6     266  VSS116  SCONN288_ADR50001P003C01  I175
  J6     268  VSS117  SCONN288_ADR50001P003C01  I175
  J6     270  VSS118  SCONN288_ADR50001P003C01  I175
  J6     273  VSS119  SCONN288_ADR50001P003C01  I175
  J6     275  VSS120  SCONN288_ADR50001P003C01  I175
  J6     277  VSS121  SCONN288_ADR50001P003C01  I175
  J6     279  VSS122  SCONN288_ADR50001P003C01  I175
  J6     281  VSS123  SCONN288_ADR50001P003C01  I175
  J6     284  VSS124  SCONN288_ADR50001P003C01  I175
  J6     286  VSS125  SCONN288_ADR50001P003C01  I175
  J6     288  VSS126  SCONN288_ADR50001P003C01  I175
  J6      G1     G1  SCONN288_ADR50001P003C01  I175
  J6      G2     G2  SCONN288_ADR50001P003C01  I175
  J6      G3     G3  SCONN288_ADR50001P003C01  I175
  J7       6   VSS0  SCONN288_ADR50001P013C01  I168
  J7       8   VSS1  SCONN288_ADR50001P013C01  I168
  J7      10   VSS2  SCONN288_ADR50001P013C01  I168
  J7      13   VSS3  SCONN288_ADR50001P013C01  I168
  J7      15   VSS4  SCONN288_ADR50001P013C01  I168
  J7      17   VSS5  SCONN288_ADR50001P013C01  I168
  J7      19   VSS6  SCONN288_ADR50001P013C01  I168
  J7      21   VSS7  SCONN288_ADR50001P013C01  I168
  J7      24   VSS8  SCONN288_ADR50001P013C01  I168
  J7      26   VSS9  SCONN288_ADR50001P013C01  I168
  J7      28  VSS10  SCONN288_ADR50001P013C01  I168
  J7      30  VSS11  SCONN288_ADR50001P013C01  I168
  J7      32  VSS12  SCONN288_ADR50001P013C01  I168
  J7      35  VSS13  SCONN288_ADR50001P013C01  I168
  J7      37  VSS14  SCONN288_ADR50001P013C01  I168
  J7      39  VSS15  SCONN288_ADR50001P013C01  I168
  J7      41  VSS16  SCONN288_ADR50001P013C01  I168
  J7      43  VSS17  SCONN288_ADR50001P013C01  I168
  J7      46  VSS18  SCONN288_ADR50001P013C01  I168
  J7      48  VSS19  SCONN288_ADR50001P013C01  I168
  J7      50  VSS20  SCONN288_ADR50001P013C01  I168
  J7      52  VSS21  SCONN288_ADR50001P013C01  I168
  J7      54  VSS22  SCONN288_ADR50001P013C01  I168
  J7      57  VSS23  SCONN288_ADR50001P013C01  I168
  J7      59  VSS24  SCONN288_ADR50001P013C01  I168
  J7      61  VSS25  SCONN288_ADR50001P013C01  I168
  J7      63  VSS26  SCONN288_ADR50001P013C01  I168
  J7      65  VSS27  SCONN288_ADR50001P013C01  I168
  J7      67  VSS28  SCONN288_ADR50001P013C01  I168
  J7      69  VSS29  SCONN288_ADR50001P013C01  I168
  J7      71  VSS30  SCONN288_ADR50001P013C01  I168
  J7      73  VSS31  SCONN288_ADR50001P013C01  I168
  J7      75  VSS32  SCONN288_ADR50001P013C01  I168
  J7      77  VSS33  SCONN288_ADR50001P013C01  I168
  J7      79  VSS34  SCONN288_ADR50001P013C01  I168
  J7      81  VSS35  SCONN288_ADR50001P013C01  I168
  J7      83  VSS36  SCONN288_ADR50001P013C01  I168
  J7      85  VSS37  SCONN288_ADR50001P013C01  I168
  J7      88  VSS38  SCONN288_ADR50001P013C01  I168
  J7      90  VSS39  SCONN288_ADR50001P013C01  I168
  J7      92  VSS40  SCONN288_ADR50001P013C01  I168
  J7      95  VSS41  SCONN288_ADR50001P013C01  I168
  J7      97  VSS42  SCONN288_ADR50001P013C01  I168
  J7      99  VSS43  SCONN288_ADR50001P013C01  I168
  J7     101  VSS44  SCONN288_ADR50001P013C01  I168
  J7     103  VSS45  SCONN288_ADR50001P013C01  I168
  J7     106  VSS46  SCONN288_ADR50001P013C01  I168
  J7     108  VSS47  SCONN288_ADR50001P013C01  I168
  J7     110  VSS48  SCONN288_ADR50001P013C01  I168
  J7     112  VSS49  SCONN288_ADR50001P013C01  I168
  J7     114  VSS50  SCONN288_ADR50001P013C01  I168
  J7     117  VSS51  SCONN288_ADR50001P013C01  I168
  J7     119  VSS52  SCONN288_ADR50001P013C01  I168
  J7     121  VSS53  SCONN288_ADR50001P013C01  I168
  J7     123  VSS54  SCONN288_ADR50001P013C01  I168
  J7     125  VSS55  SCONN288_ADR50001P013C01  I168
  J7     128  VSS56  SCONN288_ADR50001P013C01  I168
  J7     130  VSS57  SCONN288_ADR50001P013C01  I168
  J7     132  VSS58  SCONN288_ADR50001P013C01  I168
  J7     134  VSS59  SCONN288_ADR50001P013C01  I168
  J7     136  VSS60  SCONN288_ADR50001P013C01  I168
  J7     139  VSS61  SCONN288_ADR50001P013C01  I168
  J7     141  VSS62  SCONN288_ADR50001P013C01  I168
  J7     143  VSS63  SCONN288_ADR50001P013C01  I168
  J7     151  VSS64  SCONN288_ADR50001P013C01  I168
  J7     153  VSS65  SCONN288_ADR50001P013C01  I168
  J7     155  VSS66  SCONN288_ADR50001P013C01  I168
  J7     158  VSS67  SCONN288_ADR50001P013C01  I168
  J7     160  VSS68  SCONN288_ADR50001P013C01  I168
  J7     162  VSS69  SCONN288_ADR50001P013C01  I168
  J7     164  VSS70  SCONN288_ADR50001P013C01  I168
  J7     166  VSS71  SCONN288_ADR50001P013C01  I168
  J7     169  VSS72  SCONN288_ADR50001P013C01  I168
  J7     171  VSS73  SCONN288_ADR50001P013C01  I168
  J7     173  VSS74  SCONN288_ADR50001P013C01  I168
  J7     175  VSS75  SCONN288_ADR50001P013C01  I168
  J7     177  VSS76  SCONN288_ADR50001P013C01  I168
  J7     180  VSS77  SCONN288_ADR50001P013C01  I168
  J7     182  VSS78  SCONN288_ADR50001P013C01  I168
  J7     184  VSS79  SCONN288_ADR50001P013C01  I168
  J7     186  VSS80  SCONN288_ADR50001P013C01  I168
  J7     188  VSS81  SCONN288_ADR50001P013C01  I168
  J7     191  VSS82  SCONN288_ADR50001P013C01  I168
  J7     193  VSS83  SCONN288_ADR50001P013C01  I168
  J7     195  VSS84  SCONN288_ADR50001P013C01  I168
  J7     197  VSS85  SCONN288_ADR50001P013C01  I168
  J7     199  VSS86  SCONN288_ADR50001P013C01  I168
  J7     202  VSS87  SCONN288_ADR50001P013C01  I168
  J7     204  VSS88  SCONN288_ADR50001P013C01  I168
  J7     206  VSS89  SCONN288_ADR50001P013C01  I168
  J7     208  VSS90  SCONN288_ADR50001P013C01  I168
  J7     210  VSS91  SCONN288_ADR50001P013C01  I168
  J7     212  VSS92  SCONN288_ADR50001P013C01  I168
  J7     214  VSS93  SCONN288_ADR50001P013C01  I168
  J7     216  VSS94  SCONN288_ADR50001P013C01  I168
  J7     219  VSS95  SCONN288_ADR50001P013C01  I168
  J7     222  VSS96  SCONN288_ADR50001P013C01  I168
  J7     224  VSS97  SCONN288_ADR50001P013C01  I168
  J7     226  VSS98  SCONN288_ADR50001P013C01  I168
  J7     228  VSS99  SCONN288_ADR50001P013C01  I168
  J7     230  VSS100  SCONN288_ADR50001P013C01  I168
  J7     233  VSS101  SCONN288_ADR50001P013C01  I168
  J7     235  VSS102  SCONN288_ADR50001P013C01  I168
  J7     237  VSS103  SCONN288_ADR50001P013C01  I168
  J7     240  VSS104  SCONN288_ADR50001P013C01  I168
  J7     242  VSS105  SCONN288_ADR50001P013C01  I168
  J7     244  VSS106  SCONN288_ADR50001P013C01  I168
  J7     246  VSS107  SCONN288_ADR50001P013C01  I168
  J7     248  VSS108  SCONN288_ADR50001P013C01  I168
  J7     251  VSS109  SCONN288_ADR50001P013C01  I168
  J7     253  VSS110  SCONN288_ADR50001P013C01  I168
  J7     255  VSS111  SCONN288_ADR50001P013C01  I168
  J7     257  VSS112  SCONN288_ADR50001P013C01  I168
  J7     259  VSS113  SCONN288_ADR50001P013C01  I168
  J7     262  VSS114  SCONN288_ADR50001P013C01  I168
  J7     264  VSS115  SCONN288_ADR50001P013C01  I168
  J7     266  VSS116  SCONN288_ADR50001P013C01  I168
  J7     268  VSS117  SCONN288_ADR50001P013C01  I168
  J7     270  VSS118  SCONN288_ADR50001P013C01  I168
  J7     273  VSS119  SCONN288_ADR50001P013C01  I168
  J7     275  VSS120  SCONN288_ADR50001P013C01  I168
  J7     277  VSS121  SCONN288_ADR50001P013C01  I168
  J7     279  VSS122  SCONN288_ADR50001P013C01  I168
  J7     281  VSS123  SCONN288_ADR50001P013C01  I168
  J7     284  VSS124  SCONN288_ADR50001P013C01  I168
  J7     286  VSS125  SCONN288_ADR50001P013C01  I168
  J7     288  VSS126  SCONN288_ADR50001P013C01  I168
  J7      G1     G1  SCONN288_ADR50001P013C01  I168
  J7      G2     G2  SCONN288_ADR50001P013C01  I168
  J7      G3     G3  SCONN288_ADR50001P013C01  I168
  J8       6   VSS0  SCONN288_ADR50001P003C01  I175
  J8       8   VSS1  SCONN288_ADR50001P003C01  I175
  J8      10   VSS2  SCONN288_ADR50001P003C01  I175
  J8      13   VSS3  SCONN288_ADR50001P003C01  I175
  J8      15   VSS4  SCONN288_ADR50001P003C01  I175
  J8      17   VSS5  SCONN288_ADR50001P003C01  I175
  J8      19   VSS6  SCONN288_ADR50001P003C01  I175
  J8      21   VSS7  SCONN288_ADR50001P003C01  I175
  J8      24   VSS8  SCONN288_ADR50001P003C01  I175
  J8      26   VSS9  SCONN288_ADR50001P003C01  I175
  J8      28  VSS10  SCONN288_ADR50001P003C01  I175
  J8      30  VSS11  SCONN288_ADR50001P003C01  I175
  J8      32  VSS12  SCONN288_ADR50001P003C01  I175
  J8      35  VSS13  SCONN288_ADR50001P003C01  I175
  J8      37  VSS14  SCONN288_ADR50001P003C01  I175
  J8      39  VSS15  SCONN288_ADR50001P003C01  I175
  J8      41  VSS16  SCONN288_ADR50001P003C01  I175
  J8      43  VSS17  SCONN288_ADR50001P003C01  I175
  J8      46  VSS18  SCONN288_ADR50001P003C01  I175
  J8      48  VSS19  SCONN288_ADR50001P003C01  I175
  J8      50  VSS20  SCONN288_ADR50001P003C01  I175
  J8      52  VSS21  SCONN288_ADR50001P003C01  I175
  J8      54  VSS22  SCONN288_ADR50001P003C01  I175
  J8      57  VSS23  SCONN288_ADR50001P003C01  I175
  J8      59  VSS24  SCONN288_ADR50001P003C01  I175
  J8      61  VSS25  SCONN288_ADR50001P003C01  I175
  J8      63  VSS26  SCONN288_ADR50001P003C01  I175
  J8      65  VSS27  SCONN288_ADR50001P003C01  I175
  J8      67  VSS28  SCONN288_ADR50001P003C01  I175
  J8      69  VSS29  SCONN288_ADR50001P003C01  I175
  J8      71  VSS30  SCONN288_ADR50001P003C01  I175
  J8      73  VSS31  SCONN288_ADR50001P003C01  I175
  J8      75  VSS32  SCONN288_ADR50001P003C01  I175
  J8      77  VSS33  SCONN288_ADR50001P003C01  I175
  J8      79  VSS34  SCONN288_ADR50001P003C01  I175
  J8      81  VSS35  SCONN288_ADR50001P003C01  I175
  J8      83  VSS36  SCONN288_ADR50001P003C01  I175
  J8      85  VSS37  SCONN288_ADR50001P003C01  I175
  J8      88  VSS38  SCONN288_ADR50001P003C01  I175
  J8      90  VSS39  SCONN288_ADR50001P003C01  I175
  J8      92  VSS40  SCONN288_ADR50001P003C01  I175
  J8      95  VSS41  SCONN288_ADR50001P003C01  I175
  J8      97  VSS42  SCONN288_ADR50001P003C01  I175
  J8      99  VSS43  SCONN288_ADR50001P003C01  I175
  J8     101  VSS44  SCONN288_ADR50001P003C01  I175
  J8     103  VSS45  SCONN288_ADR50001P003C01  I175
  J8     106  VSS46  SCONN288_ADR50001P003C01  I175
  J8     108  VSS47  SCONN288_ADR50001P003C01  I175
  J8     110  VSS48  SCONN288_ADR50001P003C01  I175
  J8     112  VSS49  SCONN288_ADR50001P003C01  I175
  J8     114  VSS50  SCONN288_ADR50001P003C01  I175
  J8     117  VSS51  SCONN288_ADR50001P003C01  I175
  J8     119  VSS52  SCONN288_ADR50001P003C01  I175
  J8     121  VSS53  SCONN288_ADR50001P003C01  I175
  J8     123  VSS54  SCONN288_ADR50001P003C01  I175
  J8     125  VSS55  SCONN288_ADR50001P003C01  I175
  J8     128  VSS56  SCONN288_ADR50001P003C01  I175
  J8     130  VSS57  SCONN288_ADR50001P003C01  I175
  J8     132  VSS58  SCONN288_ADR50001P003C01  I175
  J8     134  VSS59  SCONN288_ADR50001P003C01  I175
  J8     136  VSS60  SCONN288_ADR50001P003C01  I175
  J8     139  VSS61  SCONN288_ADR50001P003C01  I175
  J8     141  VSS62  SCONN288_ADR50001P003C01  I175
  J8     143  VSS63  SCONN288_ADR50001P003C01  I175
  J8     151  VSS64  SCONN288_ADR50001P003C01  I175
  J8     153  VSS65  SCONN288_ADR50001P003C01  I175
  J8     155  VSS66  SCONN288_ADR50001P003C01  I175
  J8     158  VSS67  SCONN288_ADR50001P003C01  I175
  J8     160  VSS68  SCONN288_ADR50001P003C01  I175
  J8     162  VSS69  SCONN288_ADR50001P003C01  I175
  J8     164  VSS70  SCONN288_ADR50001P003C01  I175
  J8     166  VSS71  SCONN288_ADR50001P003C01  I175
  J8     169  VSS72  SCONN288_ADR50001P003C01  I175
  J8     171  VSS73  SCONN288_ADR50001P003C01  I175
  J8     173  VSS74  SCONN288_ADR50001P003C01  I175
  J8     175  VSS75  SCONN288_ADR50001P003C01  I175
  J8     177  VSS76  SCONN288_ADR50001P003C01  I175
  J8     180  VSS77  SCONN288_ADR50001P003C01  I175
  J8     182  VSS78  SCONN288_ADR50001P003C01  I175
  J8     184  VSS79  SCONN288_ADR50001P003C01  I175
  J8     186  VSS80  SCONN288_ADR50001P003C01  I175
  J8     188  VSS81  SCONN288_ADR50001P003C01  I175
  J8     191  VSS82  SCONN288_ADR50001P003C01  I175
  J8     193  VSS83  SCONN288_ADR50001P003C01  I175
  J8     195  VSS84  SCONN288_ADR50001P003C01  I175
  J8     197  VSS85  SCONN288_ADR50001P003C01  I175
  J8     199  VSS86  SCONN288_ADR50001P003C01  I175
  J8     202  VSS87  SCONN288_ADR50001P003C01  I175
  J8     204  VSS88  SCONN288_ADR50001P003C01  I175
  J8     206  VSS89  SCONN288_ADR50001P003C01  I175
  J8     208  VSS90  SCONN288_ADR50001P003C01  I175
  J8     210  VSS91  SCONN288_ADR50001P003C01  I175
  J8     212  VSS92  SCONN288_ADR50001P003C01  I175
  J8     214  VSS93  SCONN288_ADR50001P003C01  I175
  J8     216  VSS94  SCONN288_ADR50001P003C01  I175
  J8     219  VSS95  SCONN288_ADR50001P003C01  I175
  J8     222  VSS96  SCONN288_ADR50001P003C01  I175
  J8     224  VSS97  SCONN288_ADR50001P003C01  I175
  J8     226  VSS98  SCONN288_ADR50001P003C01  I175
  J8     228  VSS99  SCONN288_ADR50001P003C01  I175
  J8     230  VSS100  SCONN288_ADR50001P003C01  I175
  J8     233  VSS101  SCONN288_ADR50001P003C01  I175
  J8     235  VSS102  SCONN288_ADR50001P003C01  I175
  J8     237  VSS103  SCONN288_ADR50001P003C01  I175
  J8     240  VSS104  SCONN288_ADR50001P003C01  I175
  J8     242  VSS105  SCONN288_ADR50001P003C01  I175
  J8     244  VSS106  SCONN288_ADR50001P003C01  I175
  J8     246  VSS107  SCONN288_ADR50001P003C01  I175
  J8     248  VSS108  SCONN288_ADR50001P003C01  I175
  J8     251  VSS109  SCONN288_ADR50001P003C01  I175
  J8     253  VSS110  SCONN288_ADR50001P003C01  I175
  J8     255  VSS111  SCONN288_ADR50001P003C01  I175
  J8     257  VSS112  SCONN288_ADR50001P003C01  I175
  J8     259  VSS113  SCONN288_ADR50001P003C01  I175
  J8     262  VSS114  SCONN288_ADR50001P003C01  I175
  J8     264  VSS115  SCONN288_ADR50001P003C01  I175
  J8     266  VSS116  SCONN288_ADR50001P003C01  I175
  J8     268  VSS117  SCONN288_ADR50001P003C01  I175
  J8     270  VSS118  SCONN288_ADR50001P003C01  I175
  J8     273  VSS119  SCONN288_ADR50001P003C01  I175
  J8     275  VSS120  SCONN288_ADR50001P003C01  I175
  J8     277  VSS121  SCONN288_ADR50001P003C01  I175
  J8     279  VSS122  SCONN288_ADR50001P003C01  I175
  J8     281  VSS123  SCONN288_ADR50001P003C01  I175
  J8     284  VSS124  SCONN288_ADR50001P003C01  I175
  J8     286  VSS125  SCONN288_ADR50001P003C01  I175
  J8     288  VSS126  SCONN288_ADR50001P003C01  I175
  J8      G1     G1  SCONN288_ADR50001P003C01  I175
  J8      G2     G2  SCONN288_ADR50001P003C01  I175
  J8      G3     G3  SCONN288_ADR50001P003C01  I175
  J9       6   VSS0  SCONN288_ADR50001P013C01  I147
  J9       8   VSS1  SCONN288_ADR50001P013C01  I147
  J9      10   VSS2  SCONN288_ADR50001P013C01  I147
  J9      13   VSS3  SCONN288_ADR50001P013C01  I147
  J9      15   VSS4  SCONN288_ADR50001P013C01  I147
  J9      17   VSS5  SCONN288_ADR50001P013C01  I147
  J9      19   VSS6  SCONN288_ADR50001P013C01  I147
  J9      21   VSS7  SCONN288_ADR50001P013C01  I147
  J9      24   VSS8  SCONN288_ADR50001P013C01  I147
  J9      26   VSS9  SCONN288_ADR50001P013C01  I147
  J9      28  VSS10  SCONN288_ADR50001P013C01  I147
  J9      30  VSS11  SCONN288_ADR50001P013C01  I147
  J9      32  VSS12  SCONN288_ADR50001P013C01  I147
  J9      35  VSS13  SCONN288_ADR50001P013C01  I147
  J9      37  VSS14  SCONN288_ADR50001P013C01  I147
  J9      39  VSS15  SCONN288_ADR50001P013C01  I147
  J9      41  VSS16  SCONN288_ADR50001P013C01  I147
  J9      43  VSS17  SCONN288_ADR50001P013C01  I147
  J9      46  VSS18  SCONN288_ADR50001P013C01  I147
  J9      48  VSS19  SCONN288_ADR50001P013C01  I147
  J9      50  VSS20  SCONN288_ADR50001P013C01  I147
  J9      52  VSS21  SCONN288_ADR50001P013C01  I147
  J9      54  VSS22  SCONN288_ADR50001P013C01  I147
  J9      57  VSS23  SCONN288_ADR50001P013C01  I147
  J9      59  VSS24  SCONN288_ADR50001P013C01  I147
  J9      61  VSS25  SCONN288_ADR50001P013C01  I147
  J9      63  VSS26  SCONN288_ADR50001P013C01  I147
  J9      65  VSS27  SCONN288_ADR50001P013C01  I147
  J9      67  VSS28  SCONN288_ADR50001P013C01  I147
  J9      69  VSS29  SCONN288_ADR50001P013C01  I147
  J9      71  VSS30  SCONN288_ADR50001P013C01  I147
  J9      73  VSS31  SCONN288_ADR50001P013C01  I147
  J9      75  VSS32  SCONN288_ADR50001P013C01  I147
  J9      77  VSS33  SCONN288_ADR50001P013C01  I147
  J9      79  VSS34  SCONN288_ADR50001P013C01  I147
  J9      81  VSS35  SCONN288_ADR50001P013C01  I147
  J9      83  VSS36  SCONN288_ADR50001P013C01  I147
  J9      85  VSS37  SCONN288_ADR50001P013C01  I147
  J9      88  VSS38  SCONN288_ADR50001P013C01  I147
  J9      90  VSS39  SCONN288_ADR50001P013C01  I147
  J9      92  VSS40  SCONN288_ADR50001P013C01  I147
  J9      95  VSS41  SCONN288_ADR50001P013C01  I147
  J9      97  VSS42  SCONN288_ADR50001P013C01  I147
  J9      99  VSS43  SCONN288_ADR50001P013C01  I147
  J9     101  VSS44  SCONN288_ADR50001P013C01  I147
  J9     103  VSS45  SCONN288_ADR50001P013C01  I147
  J9     106  VSS46  SCONN288_ADR50001P013C01  I147
  J9     108  VSS47  SCONN288_ADR50001P013C01  I147
  J9     110  VSS48  SCONN288_ADR50001P013C01  I147
  J9     112  VSS49  SCONN288_ADR50001P013C01  I147
  J9     114  VSS50  SCONN288_ADR50001P013C01  I147
  J9     117  VSS51  SCONN288_ADR50001P013C01  I147
  J9     119  VSS52  SCONN288_ADR50001P013C01  I147
  J9     121  VSS53  SCONN288_ADR50001P013C01  I147
  J9     123  VSS54  SCONN288_ADR50001P013C01  I147
  J9     125  VSS55  SCONN288_ADR50001P013C01  I147
  J9     128  VSS56  SCONN288_ADR50001P013C01  I147
  J9     130  VSS57  SCONN288_ADR50001P013C01  I147
  J9     132  VSS58  SCONN288_ADR50001P013C01  I147
  J9     134  VSS59  SCONN288_ADR50001P013C01  I147
  J9     136  VSS60  SCONN288_ADR50001P013C01  I147
  J9     139  VSS61  SCONN288_ADR50001P013C01  I147
  J9     141  VSS62  SCONN288_ADR50001P013C01  I147
  J9     143  VSS63  SCONN288_ADR50001P013C01  I147
  J9     151  VSS64  SCONN288_ADR50001P013C01  I147
  J9     153  VSS65  SCONN288_ADR50001P013C01  I147
  J9     155  VSS66  SCONN288_ADR50001P013C01  I147
  J9     158  VSS67  SCONN288_ADR50001P013C01  I147
  J9     160  VSS68  SCONN288_ADR50001P013C01  I147
  J9     162  VSS69  SCONN288_ADR50001P013C01  I147
  J9     164  VSS70  SCONN288_ADR50001P013C01  I147
  J9     166  VSS71  SCONN288_ADR50001P013C01  I147
  J9     169  VSS72  SCONN288_ADR50001P013C01  I147
  J9     171  VSS73  SCONN288_ADR50001P013C01  I147
  J9     173  VSS74  SCONN288_ADR50001P013C01  I147
  J9     175  VSS75  SCONN288_ADR50001P013C01  I147
  J9     177  VSS76  SCONN288_ADR50001P013C01  I147
  J9     180  VSS77  SCONN288_ADR50001P013C01  I147
  J9     182  VSS78  SCONN288_ADR50001P013C01  I147
  J9     184  VSS79  SCONN288_ADR50001P013C01  I147
  J9     186  VSS80  SCONN288_ADR50001P013C01  I147
  J9     188  VSS81  SCONN288_ADR50001P013C01  I147
  J9     191  VSS82  SCONN288_ADR50001P013C01  I147
  J9     193  VSS83  SCONN288_ADR50001P013C01  I147
  J9     195  VSS84  SCONN288_ADR50001P013C01  I147
  J9     197  VSS85  SCONN288_ADR50001P013C01  I147
  J9     199  VSS86  SCONN288_ADR50001P013C01  I147
  J9     202  VSS87  SCONN288_ADR50001P013C01  I147
  J9     204  VSS88  SCONN288_ADR50001P013C01  I147
  J9     206  VSS89  SCONN288_ADR50001P013C01  I147
  J9     208  VSS90  SCONN288_ADR50001P013C01  I147
  J9     210  VSS91  SCONN288_ADR50001P013C01  I147
  J9     212  VSS92  SCONN288_ADR50001P013C01  I147
  J9     214  VSS93  SCONN288_ADR50001P013C01  I147
  J9     216  VSS94  SCONN288_ADR50001P013C01  I147
  J9     219  VSS95  SCONN288_ADR50001P013C01  I147
  J9     222  VSS96  SCONN288_ADR50001P013C01  I147
  J9     224  VSS97  SCONN288_ADR50001P013C01  I147
  J9     226  VSS98  SCONN288_ADR50001P013C01  I147
  J9     228  VSS99  SCONN288_ADR50001P013C01  I147
  J9     230  VSS100  SCONN288_ADR50001P013C01  I147
  J9     233  VSS101  SCONN288_ADR50001P013C01  I147
  J9     235  VSS102  SCONN288_ADR50001P013C01  I147
  J9     237  VSS103  SCONN288_ADR50001P013C01  I147
  J9     240  VSS104  SCONN288_ADR50001P013C01  I147
  J9     242  VSS105  SCONN288_ADR50001P013C01  I147
  J9     244  VSS106  SCONN288_ADR50001P013C01  I147
  J9     246  VSS107  SCONN288_ADR50001P013C01  I147
  J9     248  VSS108  SCONN288_ADR50001P013C01  I147
  J9     251  VSS109  SCONN288_ADR50001P013C01  I147
  J9     253  VSS110  SCONN288_ADR50001P013C01  I147
  J9     255  VSS111  SCONN288_ADR50001P013C01  I147
  J9     257  VSS112  SCONN288_ADR50001P013C01  I147
  J9     259  VSS113  SCONN288_ADR50001P013C01  I147
  J9     262  VSS114  SCONN288_ADR50001P013C01  I147
  J9     264  VSS115  SCONN288_ADR50001P013C01  I147
  J9     266  VSS116  SCONN288_ADR50001P013C01  I147
  J9     268  VSS117  SCONN288_ADR50001P013C01  I147
  J9     270  VSS118  SCONN288_ADR50001P013C01  I147
  J9     273  VSS119  SCONN288_ADR50001P013C01  I147
  J9     275  VSS120  SCONN288_ADR50001P013C01  I147
  J9     277  VSS121  SCONN288_ADR50001P013C01  I147
  J9     279  VSS122  SCONN288_ADR50001P013C01  I147
  J9     281  VSS123  SCONN288_ADR50001P013C01  I147
  J9     284  VSS124  SCONN288_ADR50001P013C01  I147
  J9     286  VSS125  SCONN288_ADR50001P013C01  I147
  J9     288  VSS126  SCONN288_ADR50001P013C01  I147
  J9      G1     G1  SCONN288_ADR50001P013C01  I147
  J9      G2     G2  SCONN288_ADR50001P013C01  I147
  J9      G3     G3  SCONN288_ADR50001P013C01  I147
  J10      6   VSS0  SCONN288_ADR50001P003C01  I148
  J10      8   VSS1  SCONN288_ADR50001P003C01  I148
  J10     10   VSS2  SCONN288_ADR50001P003C01  I148
  J10     13   VSS3  SCONN288_ADR50001P003C01  I148
  J10     15   VSS4  SCONN288_ADR50001P003C01  I148
  J10     17   VSS5  SCONN288_ADR50001P003C01  I148
  J10     19   VSS6  SCONN288_ADR50001P003C01  I148
  J10     21   VSS7  SCONN288_ADR50001P003C01  I148
  J10     24   VSS8  SCONN288_ADR50001P003C01  I148
  J10     26   VSS9  SCONN288_ADR50001P003C01  I148
  J10     28  VSS10  SCONN288_ADR50001P003C01  I148
  J10     30  VSS11  SCONN288_ADR50001P003C01  I148
  J10     32  VSS12  SCONN288_ADR50001P003C01  I148
  J10     35  VSS13  SCONN288_ADR50001P003C01  I148
  J10     37  VSS14  SCONN288_ADR50001P003C01  I148
  J10     39  VSS15  SCONN288_ADR50001P003C01  I148
  J10     41  VSS16  SCONN288_ADR50001P003C01  I148
  J10     43  VSS17  SCONN288_ADR50001P003C01  I148
  J10     46  VSS18  SCONN288_ADR50001P003C01  I148
  J10     48  VSS19  SCONN288_ADR50001P003C01  I148
  J10     50  VSS20  SCONN288_ADR50001P003C01  I148
  J10     52  VSS21  SCONN288_ADR50001P003C01  I148
  J10     54  VSS22  SCONN288_ADR50001P003C01  I148
  J10     57  VSS23  SCONN288_ADR50001P003C01  I148
  J10     59  VSS24  SCONN288_ADR50001P003C01  I148
  J10     61  VSS25  SCONN288_ADR50001P003C01  I148
  J10     63  VSS26  SCONN288_ADR50001P003C01  I148
  J10     65  VSS27  SCONN288_ADR50001P003C01  I148
  J10     67  VSS28  SCONN288_ADR50001P003C01  I148
  J10     69  VSS29  SCONN288_ADR50001P003C01  I148
  J10     71  VSS30  SCONN288_ADR50001P003C01  I148
  J10     73  VSS31  SCONN288_ADR50001P003C01  I148
  J10     75  VSS32  SCONN288_ADR50001P003C01  I148
  J10     77  VSS33  SCONN288_ADR50001P003C01  I148
  J10     79  VSS34  SCONN288_ADR50001P003C01  I148
  J10     81  VSS35  SCONN288_ADR50001P003C01  I148
  J10     83  VSS36  SCONN288_ADR50001P003C01  I148
  J10     85  VSS37  SCONN288_ADR50001P003C01  I148
  J10     88  VSS38  SCONN288_ADR50001P003C01  I148
  J10     90  VSS39  SCONN288_ADR50001P003C01  I148
  J10     92  VSS40  SCONN288_ADR50001P003C01  I148
  J10     95  VSS41  SCONN288_ADR50001P003C01  I148
  J10     97  VSS42  SCONN288_ADR50001P003C01  I148
  J10     99  VSS43  SCONN288_ADR50001P003C01  I148
  J10    101  VSS44  SCONN288_ADR50001P003C01  I148
  J10    103  VSS45  SCONN288_ADR50001P003C01  I148
  J10    106  VSS46  SCONN288_ADR50001P003C01  I148
  J10    108  VSS47  SCONN288_ADR50001P003C01  I148
  J10    110  VSS48  SCONN288_ADR50001P003C01  I148
  J10    112  VSS49  SCONN288_ADR50001P003C01  I148
  J10    114  VSS50  SCONN288_ADR50001P003C01  I148
  J10    117  VSS51  SCONN288_ADR50001P003C01  I148
  J10    119  VSS52  SCONN288_ADR50001P003C01  I148
  J10    121  VSS53  SCONN288_ADR50001P003C01  I148
  J10    123  VSS54  SCONN288_ADR50001P003C01  I148
  J10    125  VSS55  SCONN288_ADR50001P003C01  I148
  J10    128  VSS56  SCONN288_ADR50001P003C01  I148
  J10    130  VSS57  SCONN288_ADR50001P003C01  I148
  J10    132  VSS58  SCONN288_ADR50001P003C01  I148
  J10    134  VSS59  SCONN288_ADR50001P003C01  I148
  J10    136  VSS60  SCONN288_ADR50001P003C01  I148
  J10    139  VSS61  SCONN288_ADR50001P003C01  I148
  J10    141  VSS62  SCONN288_ADR50001P003C01  I148
  J10    143  VSS63  SCONN288_ADR50001P003C01  I148
  J10    151  VSS64  SCONN288_ADR50001P003C01  I148
  J10    153  VSS65  SCONN288_ADR50001P003C01  I148
  J10    155  VSS66  SCONN288_ADR50001P003C01  I148
  J10    158  VSS67  SCONN288_ADR50001P003C01  I148
  J10    160  VSS68  SCONN288_ADR50001P003C01  I148
  J10    162  VSS69  SCONN288_ADR50001P003C01  I148
  J10    164  VSS70  SCONN288_ADR50001P003C01  I148
  J10    166  VSS71  SCONN288_ADR50001P003C01  I148
  J10    169  VSS72  SCONN288_ADR50001P003C01  I148
  J10    171  VSS73  SCONN288_ADR50001P003C01  I148
  J10    173  VSS74  SCONN288_ADR50001P003C01  I148
  J10    175  VSS75  SCONN288_ADR50001P003C01  I148
  J10    177  VSS76  SCONN288_ADR50001P003C01  I148
  J10    180  VSS77  SCONN288_ADR50001P003C01  I148
  J10    182  VSS78  SCONN288_ADR50001P003C01  I148
  J10    184  VSS79  SCONN288_ADR50001P003C01  I148
  J10    186  VSS80  SCONN288_ADR50001P003C01  I148
  J10    188  VSS81  SCONN288_ADR50001P003C01  I148
  J10    191  VSS82  SCONN288_ADR50001P003C01  I148
  J10    193  VSS83  SCONN288_ADR50001P003C01  I148
  J10    195  VSS84  SCONN288_ADR50001P003C01  I148
  J10    197  VSS85  SCONN288_ADR50001P003C01  I148
  J10    199  VSS86  SCONN288_ADR50001P003C01  I148
  J10    202  VSS87  SCONN288_ADR50001P003C01  I148
  J10    204  VSS88  SCONN288_ADR50001P003C01  I148
  J10    206  VSS89  SCONN288_ADR50001P003C01  I148
  J10    208  VSS90  SCONN288_ADR50001P003C01  I148
  J10    210  VSS91  SCONN288_ADR50001P003C01  I148
  J10    212  VSS92  SCONN288_ADR50001P003C01  I148
  J10    214  VSS93  SCONN288_ADR50001P003C01  I148
  J10    216  VSS94  SCONN288_ADR50001P003C01  I148
  J10    219  VSS95  SCONN288_ADR50001P003C01  I148
  J10    222  VSS96  SCONN288_ADR50001P003C01  I148
  J10    224  VSS97  SCONN288_ADR50001P003C01  I148
  J10    226  VSS98  SCONN288_ADR50001P003C01  I148
  J10    228  VSS99  SCONN288_ADR50001P003C01  I148
  J10    230  VSS100  SCONN288_ADR50001P003C01  I148
  J10    233  VSS101  SCONN288_ADR50001P003C01  I148
  J10    235  VSS102  SCONN288_ADR50001P003C01  I148
  J10    237  VSS103  SCONN288_ADR50001P003C01  I148
  J10    240  VSS104  SCONN288_ADR50001P003C01  I148
  J10    242  VSS105  SCONN288_ADR50001P003C01  I148
  J10    244  VSS106  SCONN288_ADR50001P003C01  I148
  J10    246  VSS107  SCONN288_ADR50001P003C01  I148
  J10    248  VSS108  SCONN288_ADR50001P003C01  I148
  J10    251  VSS109  SCONN288_ADR50001P003C01  I148
  J10    253  VSS110  SCONN288_ADR50001P003C01  I148
  J10    255  VSS111  SCONN288_ADR50001P003C01  I148
  J10    257  VSS112  SCONN288_ADR50001P003C01  I148
  J10    259  VSS113  SCONN288_ADR50001P003C01  I148
  J10    262  VSS114  SCONN288_ADR50001P003C01  I148
  J10    264  VSS115  SCONN288_ADR50001P003C01  I148
  J10    266  VSS116  SCONN288_ADR50001P003C01  I148
  J10    268  VSS117  SCONN288_ADR50001P003C01  I148
  J10    270  VSS118  SCONN288_ADR50001P003C01  I148
  J10    273  VSS119  SCONN288_ADR50001P003C01  I148
  J10    275  VSS120  SCONN288_ADR50001P003C01  I148
  J10    277  VSS121  SCONN288_ADR50001P003C01  I148
  J10    279  VSS122  SCONN288_ADR50001P003C01  I148
  J10    281  VSS123  SCONN288_ADR50001P003C01  I148
  J10    284  VSS124  SCONN288_ADR50001P003C01  I148
  J10    286  VSS125  SCONN288_ADR50001P003C01  I148
  J10    288  VSS126  SCONN288_ADR50001P003C01  I148
  J10     G1     G1  SCONN288_ADR50001P003C01  I148
  J10     G2     G2  SCONN288_ADR50001P003C01  I148
  J10     G3     G3  SCONN288_ADR50001P003C01  I148
  J11      6   VSS0  SCONN288_ADR50001P013C01  I175
  J11      8   VSS1  SCONN288_ADR50001P013C01  I175
  J11     10   VSS2  SCONN288_ADR50001P013C01  I175
  J11     13   VSS3  SCONN288_ADR50001P013C01  I175
  J11     15   VSS4  SCONN288_ADR50001P013C01  I175
  J11     17   VSS5  SCONN288_ADR50001P013C01  I175
  J11     19   VSS6  SCONN288_ADR50001P013C01  I175
  J11     21   VSS7  SCONN288_ADR50001P013C01  I175
  J11     24   VSS8  SCONN288_ADR50001P013C01  I175
  J11     26   VSS9  SCONN288_ADR50001P013C01  I175
  J11     28  VSS10  SCONN288_ADR50001P013C01  I175
  J11     30  VSS11  SCONN288_ADR50001P013C01  I175
  J11     32  VSS12  SCONN288_ADR50001P013C01  I175
  J11     35  VSS13  SCONN288_ADR50001P013C01  I175
  J11     37  VSS14  SCONN288_ADR50001P013C01  I175
  J11     39  VSS15  SCONN288_ADR50001P013C01  I175
  J11     41  VSS16  SCONN288_ADR50001P013C01  I175
  J11     43  VSS17  SCONN288_ADR50001P013C01  I175
  J11     46  VSS18  SCONN288_ADR50001P013C01  I175
  J11     48  VSS19  SCONN288_ADR50001P013C01  I175
  J11     50  VSS20  SCONN288_ADR50001P013C01  I175
  J11     52  VSS21  SCONN288_ADR50001P013C01  I175
  J11     54  VSS22  SCONN288_ADR50001P013C01  I175
  J11     57  VSS23  SCONN288_ADR50001P013C01  I175
  J11     59  VSS24  SCONN288_ADR50001P013C01  I175
  J11     61  VSS25  SCONN288_ADR50001P013C01  I175
  J11     63  VSS26  SCONN288_ADR50001P013C01  I175
  J11     65  VSS27  SCONN288_ADR50001P013C01  I175
  J11     67  VSS28  SCONN288_ADR50001P013C01  I175
  J11     69  VSS29  SCONN288_ADR50001P013C01  I175
  J11     71  VSS30  SCONN288_ADR50001P013C01  I175
  J11     73  VSS31  SCONN288_ADR50001P013C01  I175
  J11     75  VSS32  SCONN288_ADR50001P013C01  I175
  J11     77  VSS33  SCONN288_ADR50001P013C01  I175
  J11     79  VSS34  SCONN288_ADR50001P013C01  I175
  J11     81  VSS35  SCONN288_ADR50001P013C01  I175
  J11     83  VSS36  SCONN288_ADR50001P013C01  I175
  J11     85  VSS37  SCONN288_ADR50001P013C01  I175
  J11     88  VSS38  SCONN288_ADR50001P013C01  I175
  J11     90  VSS39  SCONN288_ADR50001P013C01  I175
  J11     92  VSS40  SCONN288_ADR50001P013C01  I175
  J11     95  VSS41  SCONN288_ADR50001P013C01  I175
  J11     97  VSS42  SCONN288_ADR50001P013C01  I175
  J11     99  VSS43  SCONN288_ADR50001P013C01  I175
  J11    101  VSS44  SCONN288_ADR50001P013C01  I175
  J11    103  VSS45  SCONN288_ADR50001P013C01  I175
  J11    106  VSS46  SCONN288_ADR50001P013C01  I175
  J11    108  VSS47  SCONN288_ADR50001P013C01  I175
  J11    110  VSS48  SCONN288_ADR50001P013C01  I175
  J11    112  VSS49  SCONN288_ADR50001P013C01  I175
  J11    114  VSS50  SCONN288_ADR50001P013C01  I175
  J11    117  VSS51  SCONN288_ADR50001P013C01  I175
  J11    119  VSS52  SCONN288_ADR50001P013C01  I175
  J11    121  VSS53  SCONN288_ADR50001P013C01  I175
  J11    123  VSS54  SCONN288_ADR50001P013C01  I175
  J11    125  VSS55  SCONN288_ADR50001P013C01  I175
  J11    128  VSS56  SCONN288_ADR50001P013C01  I175
  J11    130  VSS57  SCONN288_ADR50001P013C01  I175
  J11    132  VSS58  SCONN288_ADR50001P013C01  I175
  J11    134  VSS59  SCONN288_ADR50001P013C01  I175
  J11    136  VSS60  SCONN288_ADR50001P013C01  I175
  J11    139  VSS61  SCONN288_ADR50001P013C01  I175
  J11    141  VSS62  SCONN288_ADR50001P013C01  I175
  J11    143  VSS63  SCONN288_ADR50001P013C01  I175
  J11    151  VSS64  SCONN288_ADR50001P013C01  I175
  J11    153  VSS65  SCONN288_ADR50001P013C01  I175
  J11    155  VSS66  SCONN288_ADR50001P013C01  I175
  J11    158  VSS67  SCONN288_ADR50001P013C01  I175
  J11    160  VSS68  SCONN288_ADR50001P013C01  I175
  J11    162  VSS69  SCONN288_ADR50001P013C01  I175
  J11    164  VSS70  SCONN288_ADR50001P013C01  I175
  J11    166  VSS71  SCONN288_ADR50001P013C01  I175
  J11    169  VSS72  SCONN288_ADR50001P013C01  I175
  J11    171  VSS73  SCONN288_ADR50001P013C01  I175
  J11    173  VSS74  SCONN288_ADR50001P013C01  I175
  J11    175  VSS75  SCONN288_ADR50001P013C01  I175
  J11    177  VSS76  SCONN288_ADR50001P013C01  I175
  J11    180  VSS77  SCONN288_ADR50001P013C01  I175
  J11    182  VSS78  SCONN288_ADR50001P013C01  I175
  J11    184  VSS79  SCONN288_ADR50001P013C01  I175
  J11    186  VSS80  SCONN288_ADR50001P013C01  I175
  J11    188  VSS81  SCONN288_ADR50001P013C01  I175
  J11    191  VSS82  SCONN288_ADR50001P013C01  I175
  J11    193  VSS83  SCONN288_ADR50001P013C01  I175
  J11    195  VSS84  SCONN288_ADR50001P013C01  I175
  J11    197  VSS85  SCONN288_ADR50001P013C01  I175
  J11    199  VSS86  SCONN288_ADR50001P013C01  I175
  J11    202  VSS87  SCONN288_ADR50001P013C01  I175
  J11    204  VSS88  SCONN288_ADR50001P013C01  I175
  J11    206  VSS89  SCONN288_ADR50001P013C01  I175
  J11    208  VSS90  SCONN288_ADR50001P013C01  I175
  J11    210  VSS91  SCONN288_ADR50001P013C01  I175
  J11    212  VSS92  SCONN288_ADR50001P013C01  I175
  J11    214  VSS93  SCONN288_ADR50001P013C01  I175
  J11    216  VSS94  SCONN288_ADR50001P013C01  I175
  J11    219  VSS95  SCONN288_ADR50001P013C01  I175
  J11    222  VSS96  SCONN288_ADR50001P013C01  I175
  J11    224  VSS97  SCONN288_ADR50001P013C01  I175
  J11    226  VSS98  SCONN288_ADR50001P013C01  I175
  J11    228  VSS99  SCONN288_ADR50001P013C01  I175
  J11    230  VSS100  SCONN288_ADR50001P013C01  I175
  J11    233  VSS101  SCONN288_ADR50001P013C01  I175
  J11    235  VSS102  SCONN288_ADR50001P013C01  I175
  J11    237  VSS103  SCONN288_ADR50001P013C01  I175
  J11    240  VSS104  SCONN288_ADR50001P013C01  I175
  J11    242  VSS105  SCONN288_ADR50001P013C01  I175
  J11    244  VSS106  SCONN288_ADR50001P013C01  I175
  J11    246  VSS107  SCONN288_ADR50001P013C01  I175
  J11    248  VSS108  SCONN288_ADR50001P013C01  I175
  J11    251  VSS109  SCONN288_ADR50001P013C01  I175
  J11    253  VSS110  SCONN288_ADR50001P013C01  I175
  J11    255  VSS111  SCONN288_ADR50001P013C01  I175
  J11    257  VSS112  SCONN288_ADR50001P013C01  I175
  J11    259  VSS113  SCONN288_ADR50001P013C01  I175
  J11    262  VSS114  SCONN288_ADR50001P013C01  I175
  J11    264  VSS115  SCONN288_ADR50001P013C01  I175
  J11    266  VSS116  SCONN288_ADR50001P013C01  I175
  J11    268  VSS117  SCONN288_ADR50001P013C01  I175
  J11    270  VSS118  SCONN288_ADR50001P013C01  I175
  J11    273  VSS119  SCONN288_ADR50001P013C01  I175
  J11    275  VSS120  SCONN288_ADR50001P013C01  I175
  J11    277  VSS121  SCONN288_ADR50001P013C01  I175
  J11    279  VSS122  SCONN288_ADR50001P013C01  I175
  J11    281  VSS123  SCONN288_ADR50001P013C01  I175
  J11    284  VSS124  SCONN288_ADR50001P013C01  I175
  J11    286  VSS125  SCONN288_ADR50001P013C01  I175
  J11    288  VSS126  SCONN288_ADR50001P013C01  I175
  J11     G1     G1  SCONN288_ADR50001P013C01  I175
  J11     G2     G2  SCONN288_ADR50001P013C01  I175
  J11     G3     G3  SCONN288_ADR50001P013C01  I175
  J12      6   VSS0  SCONN288_ADR50001P003C01  I175
  J12      8   VSS1  SCONN288_ADR50001P003C01  I175
  J12     10   VSS2  SCONN288_ADR50001P003C01  I175
  J12     13   VSS3  SCONN288_ADR50001P003C01  I175
  J12     15   VSS4  SCONN288_ADR50001P003C01  I175
  J12     17   VSS5  SCONN288_ADR50001P003C01  I175
  J12     19   VSS6  SCONN288_ADR50001P003C01  I175
  J12     21   VSS7  SCONN288_ADR50001P003C01  I175
  J12     24   VSS8  SCONN288_ADR50001P003C01  I175
  J12     26   VSS9  SCONN288_ADR50001P003C01  I175
  J12     28  VSS10  SCONN288_ADR50001P003C01  I175
  J12     30  VSS11  SCONN288_ADR50001P003C01  I175
  J12     32  VSS12  SCONN288_ADR50001P003C01  I175
  J12     35  VSS13  SCONN288_ADR50001P003C01  I175
  J12     37  VSS14  SCONN288_ADR50001P003C01  I175
  J12     39  VSS15  SCONN288_ADR50001P003C01  I175
  J12     41  VSS16  SCONN288_ADR50001P003C01  I175
  J12     43  VSS17  SCONN288_ADR50001P003C01  I175
  J12     46  VSS18  SCONN288_ADR50001P003C01  I175
  J12     48  VSS19  SCONN288_ADR50001P003C01  I175
  J12     50  VSS20  SCONN288_ADR50001P003C01  I175
  J12     52  VSS21  SCONN288_ADR50001P003C01  I175
  J12     54  VSS22  SCONN288_ADR50001P003C01  I175
  J12     57  VSS23  SCONN288_ADR50001P003C01  I175
  J12     59  VSS24  SCONN288_ADR50001P003C01  I175
  J12     61  VSS25  SCONN288_ADR50001P003C01  I175
  J12     63  VSS26  SCONN288_ADR50001P003C01  I175
  J12     65  VSS27  SCONN288_ADR50001P003C01  I175
  J12     67  VSS28  SCONN288_ADR50001P003C01  I175
  J12     69  VSS29  SCONN288_ADR50001P003C01  I175
  J12     71  VSS30  SCONN288_ADR50001P003C01  I175
  J12     73  VSS31  SCONN288_ADR50001P003C01  I175
  J12     75  VSS32  SCONN288_ADR50001P003C01  I175
  J12     77  VSS33  SCONN288_ADR50001P003C01  I175
  J12     79  VSS34  SCONN288_ADR50001P003C01  I175
  J12     81  VSS35  SCONN288_ADR50001P003C01  I175
  J12     83  VSS36  SCONN288_ADR50001P003C01  I175
  J12     85  VSS37  SCONN288_ADR50001P003C01  I175
  J12     88  VSS38  SCONN288_ADR50001P003C01  I175
  J12     90  VSS39  SCONN288_ADR50001P003C01  I175
  J12     92  VSS40  SCONN288_ADR50001P003C01  I175
  J12     95  VSS41  SCONN288_ADR50001P003C01  I175
  J12     97  VSS42  SCONN288_ADR50001P003C01  I175
  J12     99  VSS43  SCONN288_ADR50001P003C01  I175
  J12    101  VSS44  SCONN288_ADR50001P003C01  I175
  J12    103  VSS45  SCONN288_ADR50001P003C01  I175
  J12    106  VSS46  SCONN288_ADR50001P003C01  I175
  J12    108  VSS47  SCONN288_ADR50001P003C01  I175
  J12    110  VSS48  SCONN288_ADR50001P003C01  I175
  J12    112  VSS49  SCONN288_ADR50001P003C01  I175
  J12    114  VSS50  SCONN288_ADR50001P003C01  I175
  J12    117  VSS51  SCONN288_ADR50001P003C01  I175
  J12    119  VSS52  SCONN288_ADR50001P003C01  I175
  J12    121  VSS53  SCONN288_ADR50001P003C01  I175
  J12    123  VSS54  SCONN288_ADR50001P003C01  I175
  J12    125  VSS55  SCONN288_ADR50001P003C01  I175
  J12    128  VSS56  SCONN288_ADR50001P003C01  I175
  J12    130  VSS57  SCONN288_ADR50001P003C01  I175
  J12    132  VSS58  SCONN288_ADR50001P003C01  I175
  J12    134  VSS59  SCONN288_ADR50001P003C01  I175
  J12    136  VSS60  SCONN288_ADR50001P003C01  I175
  J12    139  VSS61  SCONN288_ADR50001P003C01  I175
  J12    141  VSS62  SCONN288_ADR50001P003C01  I175
  J12    143  VSS63  SCONN288_ADR50001P003C01  I175
  J12    151  VSS64  SCONN288_ADR50001P003C01  I175
  J12    153  VSS65  SCONN288_ADR50001P003C01  I175
  J12    155  VSS66  SCONN288_ADR50001P003C01  I175
  J12    158  VSS67  SCONN288_ADR50001P003C01  I175
  J12    160  VSS68  SCONN288_ADR50001P003C01  I175
  J12    162  VSS69  SCONN288_ADR50001P003C01  I175
  J12    164  VSS70  SCONN288_ADR50001P003C01  I175
  J12    166  VSS71  SCONN288_ADR50001P003C01  I175
  J12    169  VSS72  SCONN288_ADR50001P003C01  I175
  J12    171  VSS73  SCONN288_ADR50001P003C01  I175
  J12    173  VSS74  SCONN288_ADR50001P003C01  I175
  J12    175  VSS75  SCONN288_ADR50001P003C01  I175
  J12    177  VSS76  SCONN288_ADR50001P003C01  I175
  J12    180  VSS77  SCONN288_ADR50001P003C01  I175
  J12    182  VSS78  SCONN288_ADR50001P003C01  I175
  J12    184  VSS79  SCONN288_ADR50001P003C01  I175
  J12    186  VSS80  SCONN288_ADR50001P003C01  I175
  J12    188  VSS81  SCONN288_ADR50001P003C01  I175
  J12    191  VSS82  SCONN288_ADR50001P003C01  I175
  J12    193  VSS83  SCONN288_ADR50001P003C01  I175
  J12    195  VSS84  SCONN288_ADR50001P003C01  I175
  J12    197  VSS85  SCONN288_ADR50001P003C01  I175
  J12    199  VSS86  SCONN288_ADR50001P003C01  I175
  J12    202  VSS87  SCONN288_ADR50001P003C01  I175
  J12    204  VSS88  SCONN288_ADR50001P003C01  I175
  J12    206  VSS89  SCONN288_ADR50001P003C01  I175
  J12    208  VSS90  SCONN288_ADR50001P003C01  I175
  J12    210  VSS91  SCONN288_ADR50001P003C01  I175
  J12    212  VSS92  SCONN288_ADR50001P003C01  I175
  J12    214  VSS93  SCONN288_ADR50001P003C01  I175
  J12    216  VSS94  SCONN288_ADR50001P003C01  I175
  J12    219  VSS95  SCONN288_ADR50001P003C01  I175
  J12    222  VSS96  SCONN288_ADR50001P003C01  I175
  J12    224  VSS97  SCONN288_ADR50001P003C01  I175
  J12    226  VSS98  SCONN288_ADR50001P003C01  I175
  J12    228  VSS99  SCONN288_ADR50001P003C01  I175
  J12    230  VSS100  SCONN288_ADR50001P003C01  I175
  J12    233  VSS101  SCONN288_ADR50001P003C01  I175
  J12    235  VSS102  SCONN288_ADR50001P003C01  I175
  J12    237  VSS103  SCONN288_ADR50001P003C01  I175
  J12    240  VSS104  SCONN288_ADR50001P003C01  I175
  J12    242  VSS105  SCONN288_ADR50001P003C01  I175
  J12    244  VSS106  SCONN288_ADR50001P003C01  I175
  J12    246  VSS107  SCONN288_ADR50001P003C01  I175
  J12    248  VSS108  SCONN288_ADR50001P003C01  I175
  J12    251  VSS109  SCONN288_ADR50001P003C01  I175
  J12    253  VSS110  SCONN288_ADR50001P003C01  I175
  J12    255  VSS111  SCONN288_ADR50001P003C01  I175
  J12    257  VSS112  SCONN288_ADR50001P003C01  I175
  J12    259  VSS113  SCONN288_ADR50001P003C01  I175
  J12    262  VSS114  SCONN288_ADR50001P003C01  I175
  J12    264  VSS115  SCONN288_ADR50001P003C01  I175
  J12    266  VSS116  SCONN288_ADR50001P003C01  I175
  J12    268  VSS117  SCONN288_ADR50001P003C01  I175
  J12    270  VSS118  SCONN288_ADR50001P003C01  I175
  J12    273  VSS119  SCONN288_ADR50001P003C01  I175
  J12    275  VSS120  SCONN288_ADR50001P003C01  I175
  J12    277  VSS121  SCONN288_ADR50001P003C01  I175
  J12    279  VSS122  SCONN288_ADR50001P003C01  I175
  J12    281  VSS123  SCONN288_ADR50001P003C01  I175
  J12    284  VSS124  SCONN288_ADR50001P003C01  I175
  J12    286  VSS125  SCONN288_ADR50001P003C01  I175
  J12    288  VSS126  SCONN288_ADR50001P003C01  I175
  J12     G1     G1  SCONN288_ADR50001P003C01  I175
  J12     G2     G2  SCONN288_ADR50001P003C01  I175
  J12     G3     G3  SCONN288_ADR50001P003C01  I175
  J13      6   VSS0  SCONN288_ADR50001P013C01  I164
  J13      8   VSS1  SCONN288_ADR50001P013C01  I164
  J13     10   VSS2  SCONN288_ADR50001P013C01  I164
  J13     13   VSS3  SCONN288_ADR50001P013C01  I164
  J13     15   VSS4  SCONN288_ADR50001P013C01  I164
  J13     17   VSS5  SCONN288_ADR50001P013C01  I164
  J13     19   VSS6  SCONN288_ADR50001P013C01  I164
  J13     21   VSS7  SCONN288_ADR50001P013C01  I164
  J13     24   VSS8  SCONN288_ADR50001P013C01  I164
  J13     26   VSS9  SCONN288_ADR50001P013C01  I164
  J13     28  VSS10  SCONN288_ADR50001P013C01  I164
  J13     30  VSS11  SCONN288_ADR50001P013C01  I164
  J13     32  VSS12  SCONN288_ADR50001P013C01  I164
  J13     35  VSS13  SCONN288_ADR50001P013C01  I164
  J13     37  VSS14  SCONN288_ADR50001P013C01  I164
  J13     39  VSS15  SCONN288_ADR50001P013C01  I164
  J13     41  VSS16  SCONN288_ADR50001P013C01  I164
  J13     43  VSS17  SCONN288_ADR50001P013C01  I164
  J13     46  VSS18  SCONN288_ADR50001P013C01  I164
  J13     48  VSS19  SCONN288_ADR50001P013C01  I164
  J13     50  VSS20  SCONN288_ADR50001P013C01  I164
  J13     52  VSS21  SCONN288_ADR50001P013C01  I164
  J13     54  VSS22  SCONN288_ADR50001P013C01  I164
  J13     57  VSS23  SCONN288_ADR50001P013C01  I164
  J13     59  VSS24  SCONN288_ADR50001P013C01  I164
  J13     61  VSS25  SCONN288_ADR50001P013C01  I164
  J13     63  VSS26  SCONN288_ADR50001P013C01  I164
  J13     65  VSS27  SCONN288_ADR50001P013C01  I164
  J13     67  VSS28  SCONN288_ADR50001P013C01  I164
  J13     69  VSS29  SCONN288_ADR50001P013C01  I164
  J13     71  VSS30  SCONN288_ADR50001P013C01  I164
  J13     73  VSS31  SCONN288_ADR50001P013C01  I164
  J13     75  VSS32  SCONN288_ADR50001P013C01  I164
  J13     77  VSS33  SCONN288_ADR50001P013C01  I164
  J13     79  VSS34  SCONN288_ADR50001P013C01  I164
  J13     81  VSS35  SCONN288_ADR50001P013C01  I164
  J13     83  VSS36  SCONN288_ADR50001P013C01  I164
  J13     85  VSS37  SCONN288_ADR50001P013C01  I164
  J13     88  VSS38  SCONN288_ADR50001P013C01  I164
  J13     90  VSS39  SCONN288_ADR50001P013C01  I164
  J13     92  VSS40  SCONN288_ADR50001P013C01  I164
  J13     95  VSS41  SCONN288_ADR50001P013C01  I164
  J13     97  VSS42  SCONN288_ADR50001P013C01  I164
  J13     99  VSS43  SCONN288_ADR50001P013C01  I164
  J13    101  VSS44  SCONN288_ADR50001P013C01  I164
  J13    103  VSS45  SCONN288_ADR50001P013C01  I164
  J13    106  VSS46  SCONN288_ADR50001P013C01  I164
  J13    108  VSS47  SCONN288_ADR50001P013C01  I164
  J13    110  VSS48  SCONN288_ADR50001P013C01  I164
  J13    112  VSS49  SCONN288_ADR50001P013C01  I164
  J13    114  VSS50  SCONN288_ADR50001P013C01  I164
  J13    117  VSS51  SCONN288_ADR50001P013C01  I164
  J13    119  VSS52  SCONN288_ADR50001P013C01  I164
  J13    121  VSS53  SCONN288_ADR50001P013C01  I164
  J13    123  VSS54  SCONN288_ADR50001P013C01  I164
  J13    125  VSS55  SCONN288_ADR50001P013C01  I164
  J13    128  VSS56  SCONN288_ADR50001P013C01  I164
  J13    130  VSS57  SCONN288_ADR50001P013C01  I164
  J13    132  VSS58  SCONN288_ADR50001P013C01  I164
  J13    134  VSS59  SCONN288_ADR50001P013C01  I164
  J13    136  VSS60  SCONN288_ADR50001P013C01  I164
  J13    139  VSS61  SCONN288_ADR50001P013C01  I164
  J13    141  VSS62  SCONN288_ADR50001P013C01  I164
  J13    143  VSS63  SCONN288_ADR50001P013C01  I164
  J13    151  VSS64  SCONN288_ADR50001P013C01  I164
  J13    153  VSS65  SCONN288_ADR50001P013C01  I164
  J13    155  VSS66  SCONN288_ADR50001P013C01  I164
  J13    158  VSS67  SCONN288_ADR50001P013C01  I164
  J13    160  VSS68  SCONN288_ADR50001P013C01  I164
  J13    162  VSS69  SCONN288_ADR50001P013C01  I164
  J13    164  VSS70  SCONN288_ADR50001P013C01  I164
  J13    166  VSS71  SCONN288_ADR50001P013C01  I164
  J13    169  VSS72  SCONN288_ADR50001P013C01  I164
  J13    171  VSS73  SCONN288_ADR50001P013C01  I164
  J13    173  VSS74  SCONN288_ADR50001P013C01  I164
  J13    175  VSS75  SCONN288_ADR50001P013C01  I164
  J13    177  VSS76  SCONN288_ADR50001P013C01  I164
  J13    180  VSS77  SCONN288_ADR50001P013C01  I164
  J13    182  VSS78  SCONN288_ADR50001P013C01  I164
  J13    184  VSS79  SCONN288_ADR50001P013C01  I164
  J13    186  VSS80  SCONN288_ADR50001P013C01  I164
  J13    188  VSS81  SCONN288_ADR50001P013C01  I164
  J13    191  VSS82  SCONN288_ADR50001P013C01  I164
  J13    193  VSS83  SCONN288_ADR50001P013C01  I164
  J13    195  VSS84  SCONN288_ADR50001P013C01  I164
  J13    197  VSS85  SCONN288_ADR50001P013C01  I164
  J13    199  VSS86  SCONN288_ADR50001P013C01  I164
  J13    202  VSS87  SCONN288_ADR50001P013C01  I164
  J13    204  VSS88  SCONN288_ADR50001P013C01  I164
  J13    206  VSS89  SCONN288_ADR50001P013C01  I164
  J13    208  VSS90  SCONN288_ADR50001P013C01  I164
  J13    210  VSS91  SCONN288_ADR50001P013C01  I164
  J13    212  VSS92  SCONN288_ADR50001P013C01  I164
  J13    214  VSS93  SCONN288_ADR50001P013C01  I164
  J13    216  VSS94  SCONN288_ADR50001P013C01  I164
  J13    219  VSS95  SCONN288_ADR50001P013C01  I164
  J13    222  VSS96  SCONN288_ADR50001P013C01  I164
  J13    224  VSS97  SCONN288_ADR50001P013C01  I164
  J13    226  VSS98  SCONN288_ADR50001P013C01  I164
  J13    228  VSS99  SCONN288_ADR50001P013C01  I164
  J13    230  VSS100  SCONN288_ADR50001P013C01  I164
  J13    233  VSS101  SCONN288_ADR50001P013C01  I164
  J13    235  VSS102  SCONN288_ADR50001P013C01  I164
  J13    237  VSS103  SCONN288_ADR50001P013C01  I164
  J13    240  VSS104  SCONN288_ADR50001P013C01  I164
  J13    242  VSS105  SCONN288_ADR50001P013C01  I164
  J13    244  VSS106  SCONN288_ADR50001P013C01  I164
  J13    246  VSS107  SCONN288_ADR50001P013C01  I164
  J13    248  VSS108  SCONN288_ADR50001P013C01  I164
  J13    251  VSS109  SCONN288_ADR50001P013C01  I164
  J13    253  VSS110  SCONN288_ADR50001P013C01  I164
  J13    255  VSS111  SCONN288_ADR50001P013C01  I164
  J13    257  VSS112  SCONN288_ADR50001P013C01  I164
  J13    259  VSS113  SCONN288_ADR50001P013C01  I164
  J13    262  VSS114  SCONN288_ADR50001P013C01  I164
  J13    264  VSS115  SCONN288_ADR50001P013C01  I164
  J13    266  VSS116  SCONN288_ADR50001P013C01  I164
  J13    268  VSS117  SCONN288_ADR50001P013C01  I164
  J13    270  VSS118  SCONN288_ADR50001P013C01  I164
  J13    273  VSS119  SCONN288_ADR50001P013C01  I164
  J13    275  VSS120  SCONN288_ADR50001P013C01  I164
  J13    277  VSS121  SCONN288_ADR50001P013C01  I164
  J13    279  VSS122  SCONN288_ADR50001P013C01  I164
  J13    281  VSS123  SCONN288_ADR50001P013C01  I164
  J13    284  VSS124  SCONN288_ADR50001P013C01  I164
  J13    286  VSS125  SCONN288_ADR50001P013C01  I164
  J13    288  VSS126  SCONN288_ADR50001P013C01  I164
  J13     G1     G1  SCONN288_ADR50001P013C01  I164
  J13     G2     G2  SCONN288_ADR50001P013C01  I164
  J13     G3     G3  SCONN288_ADR50001P013C01  I164
  J14      6   VSS0  SCONN288_ADR50001P003C01  I176
  J14      8   VSS1  SCONN288_ADR50001P003C01  I176
  J14     10   VSS2  SCONN288_ADR50001P003C01  I176
  J14     13   VSS3  SCONN288_ADR50001P003C01  I176
  J14     15   VSS4  SCONN288_ADR50001P003C01  I176
  J14     17   VSS5  SCONN288_ADR50001P003C01  I176
  J14     19   VSS6  SCONN288_ADR50001P003C01  I176
  J14     21   VSS7  SCONN288_ADR50001P003C01  I176
  J14     24   VSS8  SCONN288_ADR50001P003C01  I176
  J14     26   VSS9  SCONN288_ADR50001P003C01  I176
  J14     28  VSS10  SCONN288_ADR50001P003C01  I176
  J14     30  VSS11  SCONN288_ADR50001P003C01  I176
  J14     32  VSS12  SCONN288_ADR50001P003C01  I176
  J14     35  VSS13  SCONN288_ADR50001P003C01  I176
  J14     37  VSS14  SCONN288_ADR50001P003C01  I176
  J14     39  VSS15  SCONN288_ADR50001P003C01  I176
  J14     41  VSS16  SCONN288_ADR50001P003C01  I176
  J14     43  VSS17  SCONN288_ADR50001P003C01  I176
  J14     46  VSS18  SCONN288_ADR50001P003C01  I176
  J14     48  VSS19  SCONN288_ADR50001P003C01  I176
  J14     50  VSS20  SCONN288_ADR50001P003C01  I176
  J14     52  VSS21  SCONN288_ADR50001P003C01  I176
  J14     54  VSS22  SCONN288_ADR50001P003C01  I176
  J14     57  VSS23  SCONN288_ADR50001P003C01  I176
  J14     59  VSS24  SCONN288_ADR50001P003C01  I176
  J14     61  VSS25  SCONN288_ADR50001P003C01  I176
  J14     63  VSS26  SCONN288_ADR50001P003C01  I176
  J14     65  VSS27  SCONN288_ADR50001P003C01  I176
  J14     67  VSS28  SCONN288_ADR50001P003C01  I176
  J14     69  VSS29  SCONN288_ADR50001P003C01  I176
  J14     71  VSS30  SCONN288_ADR50001P003C01  I176
  J14     73  VSS31  SCONN288_ADR50001P003C01  I176
  J14     75  VSS32  SCONN288_ADR50001P003C01  I176
  J14     77  VSS33  SCONN288_ADR50001P003C01  I176
  J14     79  VSS34  SCONN288_ADR50001P003C01  I176
  J14     81  VSS35  SCONN288_ADR50001P003C01  I176
  J14     83  VSS36  SCONN288_ADR50001P003C01  I176
  J14     85  VSS37  SCONN288_ADR50001P003C01  I176
  J14     88  VSS38  SCONN288_ADR50001P003C01  I176
  J14     90  VSS39  SCONN288_ADR50001P003C01  I176
  J14     92  VSS40  SCONN288_ADR50001P003C01  I176
  J14     95  VSS41  SCONN288_ADR50001P003C01  I176
  J14     97  VSS42  SCONN288_ADR50001P003C01  I176
  J14     99  VSS43  SCONN288_ADR50001P003C01  I176
  J14    101  VSS44  SCONN288_ADR50001P003C01  I176
  J14    103  VSS45  SCONN288_ADR50001P003C01  I176
  J14    106  VSS46  SCONN288_ADR50001P003C01  I176
  J14    108  VSS47  SCONN288_ADR50001P003C01  I176
  J14    110  VSS48  SCONN288_ADR50001P003C01  I176
  J14    112  VSS49  SCONN288_ADR50001P003C01  I176
  J14    114  VSS50  SCONN288_ADR50001P003C01  I176
  J14    117  VSS51  SCONN288_ADR50001P003C01  I176
  J14    119  VSS52  SCONN288_ADR50001P003C01  I176
  J14    121  VSS53  SCONN288_ADR50001P003C01  I176
  J14    123  VSS54  SCONN288_ADR50001P003C01  I176
  J14    125  VSS55  SCONN288_ADR50001P003C01  I176
  J14    128  VSS56  SCONN288_ADR50001P003C01  I176
  J14    130  VSS57  SCONN288_ADR50001P003C01  I176
  J14    132  VSS58  SCONN288_ADR50001P003C01  I176
  J14    134  VSS59  SCONN288_ADR50001P003C01  I176
  J14    136  VSS60  SCONN288_ADR50001P003C01  I176
  J14    139  VSS61  SCONN288_ADR50001P003C01  I176
  J14    141  VSS62  SCONN288_ADR50001P003C01  I176
  J14    143  VSS63  SCONN288_ADR50001P003C01  I176
  J14    151  VSS64  SCONN288_ADR50001P003C01  I176
  J14    153  VSS65  SCONN288_ADR50001P003C01  I176
  J14    155  VSS66  SCONN288_ADR50001P003C01  I176
  J14    158  VSS67  SCONN288_ADR50001P003C01  I176
  J14    160  VSS68  SCONN288_ADR50001P003C01  I176
  J14    162  VSS69  SCONN288_ADR50001P003C01  I176
  J14    164  VSS70  SCONN288_ADR50001P003C01  I176
  J14    166  VSS71  SCONN288_ADR50001P003C01  I176
  J14    169  VSS72  SCONN288_ADR50001P003C01  I176
  J14    171  VSS73  SCONN288_ADR50001P003C01  I176
  J14    173  VSS74  SCONN288_ADR50001P003C01  I176
  J14    175  VSS75  SCONN288_ADR50001P003C01  I176
  J14    177  VSS76  SCONN288_ADR50001P003C01  I176
  J14    180  VSS77  SCONN288_ADR50001P003C01  I176
  J14    182  VSS78  SCONN288_ADR50001P003C01  I176
  J14    184  VSS79  SCONN288_ADR50001P003C01  I176
  J14    186  VSS80  SCONN288_ADR50001P003C01  I176
  J14    188  VSS81  SCONN288_ADR50001P003C01  I176
  J14    191  VSS82  SCONN288_ADR50001P003C01  I176
  J14    193  VSS83  SCONN288_ADR50001P003C01  I176
  J14    195  VSS84  SCONN288_ADR50001P003C01  I176
  J14    197  VSS85  SCONN288_ADR50001P003C01  I176
  J14    199  VSS86  SCONN288_ADR50001P003C01  I176
  J14    202  VSS87  SCONN288_ADR50001P003C01  I176
  J14    204  VSS88  SCONN288_ADR50001P003C01  I176
  J14    206  VSS89  SCONN288_ADR50001P003C01  I176
  J14    208  VSS90  SCONN288_ADR50001P003C01  I176
  J14    210  VSS91  SCONN288_ADR50001P003C01  I176
  J14    212  VSS92  SCONN288_ADR50001P003C01  I176
  J14    214  VSS93  SCONN288_ADR50001P003C01  I176
  J14    216  VSS94  SCONN288_ADR50001P003C01  I176
  J14    219  VSS95  SCONN288_ADR50001P003C01  I176
  J14    222  VSS96  SCONN288_ADR50001P003C01  I176
  J14    224  VSS97  SCONN288_ADR50001P003C01  I176
  J14    226  VSS98  SCONN288_ADR50001P003C01  I176
  J14    228  VSS99  SCONN288_ADR50001P003C01  I176
  J14    230  VSS100  SCONN288_ADR50001P003C01  I176
  J14    233  VSS101  SCONN288_ADR50001P003C01  I176
  J14    235  VSS102  SCONN288_ADR50001P003C01  I176
  J14    237  VSS103  SCONN288_ADR50001P003C01  I176
  J14    240  VSS104  SCONN288_ADR50001P003C01  I176
  J14    242  VSS105  SCONN288_ADR50001P003C01  I176
  J14    244  VSS106  SCONN288_ADR50001P003C01  I176
  J14    246  VSS107  SCONN288_ADR50001P003C01  I176
  J14    248  VSS108  SCONN288_ADR50001P003C01  I176
  J14    251  VSS109  SCONN288_ADR50001P003C01  I176
  J14    253  VSS110  SCONN288_ADR50001P003C01  I176
  J14    255  VSS111  SCONN288_ADR50001P003C01  I176
  J14    257  VSS112  SCONN288_ADR50001P003C01  I176
  J14    259  VSS113  SCONN288_ADR50001P003C01  I176
  J14    262  VSS114  SCONN288_ADR50001P003C01  I176
  J14    264  VSS115  SCONN288_ADR50001P003C01  I176
  J14    266  VSS116  SCONN288_ADR50001P003C01  I176
  J14    268  VSS117  SCONN288_ADR50001P003C01  I176
  J14    270  VSS118  SCONN288_ADR50001P003C01  I176
  J14    273  VSS119  SCONN288_ADR50001P003C01  I176
  J14    275  VSS120  SCONN288_ADR50001P003C01  I176
  J14    277  VSS121  SCONN288_ADR50001P003C01  I176
  J14    279  VSS122  SCONN288_ADR50001P003C01  I176
  J14    281  VSS123  SCONN288_ADR50001P003C01  I176
  J14    284  VSS124  SCONN288_ADR50001P003C01  I176
  J14    286  VSS125  SCONN288_ADR50001P003C01  I176
  J14    288  VSS126  SCONN288_ADR50001P003C01  I176
  J14     G1     G1  SCONN288_ADR50001P003C01  I176
  J14     G2     G2  SCONN288_ADR50001P003C01  I176
  J14     G3     G3  SCONN288_ADR50001P003C01  I176
  J15      6   VSS0  SCONN288_ADR50001P013C01  I176
  J15      8   VSS1  SCONN288_ADR50001P013C01  I176
  J15     10   VSS2  SCONN288_ADR50001P013C01  I176
  J15     13   VSS3  SCONN288_ADR50001P013C01  I176
  J15     15   VSS4  SCONN288_ADR50001P013C01  I176
  J15     17   VSS5  SCONN288_ADR50001P013C01  I176
  J15     19   VSS6  SCONN288_ADR50001P013C01  I176
  J15     21   VSS7  SCONN288_ADR50001P013C01  I176
  J15     24   VSS8  SCONN288_ADR50001P013C01  I176
  J15     26   VSS9  SCONN288_ADR50001P013C01  I176
  J15     28  VSS10  SCONN288_ADR50001P013C01  I176
  J15     30  VSS11  SCONN288_ADR50001P013C01  I176
  J15     32  VSS12  SCONN288_ADR50001P013C01  I176
  J15     35  VSS13  SCONN288_ADR50001P013C01  I176
  J15     37  VSS14  SCONN288_ADR50001P013C01  I176
  J15     39  VSS15  SCONN288_ADR50001P013C01  I176
  J15     41  VSS16  SCONN288_ADR50001P013C01  I176
  J15     43  VSS17  SCONN288_ADR50001P013C01  I176
  J15     46  VSS18  SCONN288_ADR50001P013C01  I176
  J15     48  VSS19  SCONN288_ADR50001P013C01  I176
  J15     50  VSS20  SCONN288_ADR50001P013C01  I176
  J15     52  VSS21  SCONN288_ADR50001P013C01  I176
  J15     54  VSS22  SCONN288_ADR50001P013C01  I176
  J15     57  VSS23  SCONN288_ADR50001P013C01  I176
  J15     59  VSS24  SCONN288_ADR50001P013C01  I176
  J15     61  VSS25  SCONN288_ADR50001P013C01  I176
  J15     63  VSS26  SCONN288_ADR50001P013C01  I176
  J15     65  VSS27  SCONN288_ADR50001P013C01  I176
  J15     67  VSS28  SCONN288_ADR50001P013C01  I176
  J15     69  VSS29  SCONN288_ADR50001P013C01  I176
  J15     71  VSS30  SCONN288_ADR50001P013C01  I176
  J15     73  VSS31  SCONN288_ADR50001P013C01  I176
  J15     75  VSS32  SCONN288_ADR50001P013C01  I176
  J15     77  VSS33  SCONN288_ADR50001P013C01  I176
  J15     79  VSS34  SCONN288_ADR50001P013C01  I176
  J15     81  VSS35  SCONN288_ADR50001P013C01  I176
  J15     83  VSS36  SCONN288_ADR50001P013C01  I176
  J15     85  VSS37  SCONN288_ADR50001P013C01  I176
  J15     88  VSS38  SCONN288_ADR50001P013C01  I176
  J15     90  VSS39  SCONN288_ADR50001P013C01  I176
  J15     92  VSS40  SCONN288_ADR50001P013C01  I176
  J15     95  VSS41  SCONN288_ADR50001P013C01  I176
  J15     97  VSS42  SCONN288_ADR50001P013C01  I176
  J15     99  VSS43  SCONN288_ADR50001P013C01  I176
  J15    101  VSS44  SCONN288_ADR50001P013C01  I176
  J15    103  VSS45  SCONN288_ADR50001P013C01  I176
  J15    106  VSS46  SCONN288_ADR50001P013C01  I176
  J15    108  VSS47  SCONN288_ADR50001P013C01  I176
  J15    110  VSS48  SCONN288_ADR50001P013C01  I176
  J15    112  VSS49  SCONN288_ADR50001P013C01  I176
  J15    114  VSS50  SCONN288_ADR50001P013C01  I176
  J15    117  VSS51  SCONN288_ADR50001P013C01  I176
  J15    119  VSS52  SCONN288_ADR50001P013C01  I176
  J15    121  VSS53  SCONN288_ADR50001P013C01  I176
  J15    123  VSS54  SCONN288_ADR50001P013C01  I176
  J15    125  VSS55  SCONN288_ADR50001P013C01  I176
  J15    128  VSS56  SCONN288_ADR50001P013C01  I176
  J15    130  VSS57  SCONN288_ADR50001P013C01  I176
  J15    132  VSS58  SCONN288_ADR50001P013C01  I176
  J15    134  VSS59  SCONN288_ADR50001P013C01  I176
  J15    136  VSS60  SCONN288_ADR50001P013C01  I176
  J15    139  VSS61  SCONN288_ADR50001P013C01  I176
  J15    141  VSS62  SCONN288_ADR50001P013C01  I176
  J15    143  VSS63  SCONN288_ADR50001P013C01  I176
  J15    151  VSS64  SCONN288_ADR50001P013C01  I176
  J15    153  VSS65  SCONN288_ADR50001P013C01  I176
  J15    155  VSS66  SCONN288_ADR50001P013C01  I176
  J15    158  VSS67  SCONN288_ADR50001P013C01  I176
  J15    160  VSS68  SCONN288_ADR50001P013C01  I176
  J15    162  VSS69  SCONN288_ADR50001P013C01  I176
  J15    164  VSS70  SCONN288_ADR50001P013C01  I176
  J15    166  VSS71  SCONN288_ADR50001P013C01  I176
  J15    169  VSS72  SCONN288_ADR50001P013C01  I176
  J15    171  VSS73  SCONN288_ADR50001P013C01  I176
  J15    173  VSS74  SCONN288_ADR50001P013C01  I176
  J15    175  VSS75  SCONN288_ADR50001P013C01  I176
  J15    177  VSS76  SCONN288_ADR50001P013C01  I176
  J15    180  VSS77  SCONN288_ADR50001P013C01  I176
  J15    182  VSS78  SCONN288_ADR50001P013C01  I176
  J15    184  VSS79  SCONN288_ADR50001P013C01  I176
  J15    186  VSS80  SCONN288_ADR50001P013C01  I176
  J15    188  VSS81  SCONN288_ADR50001P013C01  I176
  J15    191  VSS82  SCONN288_ADR50001P013C01  I176
  J15    193  VSS83  SCONN288_ADR50001P013C01  I176
  J15    195  VSS84  SCONN288_ADR50001P013C01  I176
  J15    197  VSS85  SCONN288_ADR50001P013C01  I176
  J15    199  VSS86  SCONN288_ADR50001P013C01  I176
  J15    202  VSS87  SCONN288_ADR50001P013C01  I176
  J15    204  VSS88  SCONN288_ADR50001P013C01  I176
  J15    206  VSS89  SCONN288_ADR50001P013C01  I176
  J15    208  VSS90  SCONN288_ADR50001P013C01  I176
  J15    210  VSS91  SCONN288_ADR50001P013C01  I176
  J15    212  VSS92  SCONN288_ADR50001P013C01  I176
  J15    214  VSS93  SCONN288_ADR50001P013C01  I176
  J15    216  VSS94  SCONN288_ADR50001P013C01  I176
  J15    219  VSS95  SCONN288_ADR50001P013C01  I176
  J15    222  VSS96  SCONN288_ADR50001P013C01  I176
  J15    224  VSS97  SCONN288_ADR50001P013C01  I176
  J15    226  VSS98  SCONN288_ADR50001P013C01  I176
  J15    228  VSS99  SCONN288_ADR50001P013C01  I176
  J15    230  VSS100  SCONN288_ADR50001P013C01  I176
  J15    233  VSS101  SCONN288_ADR50001P013C01  I176
  J15    235  VSS102  SCONN288_ADR50001P013C01  I176
  J15    237  VSS103  SCONN288_ADR50001P013C01  I176
  J15    240  VSS104  SCONN288_ADR50001P013C01  I176
  J15    242  VSS105  SCONN288_ADR50001P013C01  I176
  J15    244  VSS106  SCONN288_ADR50001P013C01  I176
  J15    246  VSS107  SCONN288_ADR50001P013C01  I176
  J15    248  VSS108  SCONN288_ADR50001P013C01  I176
  J15    251  VSS109  SCONN288_ADR50001P013C01  I176
  J15    253  VSS110  SCONN288_ADR50001P013C01  I176
  J15    255  VSS111  SCONN288_ADR50001P013C01  I176
  J15    257  VSS112  SCONN288_ADR50001P013C01  I176
  J15    259  VSS113  SCONN288_ADR50001P013C01  I176
  J15    262  VSS114  SCONN288_ADR50001P013C01  I176
  J15    264  VSS115  SCONN288_ADR50001P013C01  I176
  J15    266  VSS116  SCONN288_ADR50001P013C01  I176
  J15    268  VSS117  SCONN288_ADR50001P013C01  I176
  J15    270  VSS118  SCONN288_ADR50001P013C01  I176
  J15    273  VSS119  SCONN288_ADR50001P013C01  I176
  J15    275  VSS120  SCONN288_ADR50001P013C01  I176
  J15    277  VSS121  SCONN288_ADR50001P013C01  I176
  J15    279  VSS122  SCONN288_ADR50001P013C01  I176
  J15    281  VSS123  SCONN288_ADR50001P013C01  I176
  J15    284  VSS124  SCONN288_ADR50001P013C01  I176
  J15    286  VSS125  SCONN288_ADR50001P013C01  I176
  J15    288  VSS126  SCONN288_ADR50001P013C01  I176
  J15     G1     G1  SCONN288_ADR50001P013C01  I176
  J15     G2     G2  SCONN288_ADR50001P013C01  I176
  J15     G3     G3  SCONN288_ADR50001P013C01  I176
  J16      6   VSS0  SCONN288_ADR50001P003C01  I64
  J16      8   VSS1  SCONN288_ADR50001P003C01  I64
  J16     10   VSS2  SCONN288_ADR50001P003C01  I64
  J16     13   VSS3  SCONN288_ADR50001P003C01  I64
  J16     15   VSS4  SCONN288_ADR50001P003C01  I64
  J16     17   VSS5  SCONN288_ADR50001P003C01  I64
  J16     19   VSS6  SCONN288_ADR50001P003C01  I64
  J16     21   VSS7  SCONN288_ADR50001P003C01  I64
  J16     24   VSS8  SCONN288_ADR50001P003C01  I64
  J16     26   VSS9  SCONN288_ADR50001P003C01  I64
  J16     28  VSS10  SCONN288_ADR50001P003C01  I64
  J16     30  VSS11  SCONN288_ADR50001P003C01  I64
  J16     32  VSS12  SCONN288_ADR50001P003C01  I64
  J16     35  VSS13  SCONN288_ADR50001P003C01  I64
  J16     37  VSS14  SCONN288_ADR50001P003C01  I64
  J16     39  VSS15  SCONN288_ADR50001P003C01  I64
  J16     41  VSS16  SCONN288_ADR50001P003C01  I64
  J16     43  VSS17  SCONN288_ADR50001P003C01  I64
  J16     46  VSS18  SCONN288_ADR50001P003C01  I64
  J16     48  VSS19  SCONN288_ADR50001P003C01  I64
  J16     50  VSS20  SCONN288_ADR50001P003C01  I64
  J16     52  VSS21  SCONN288_ADR50001P003C01  I64
  J16     54  VSS22  SCONN288_ADR50001P003C01  I64
  J16     57  VSS23  SCONN288_ADR50001P003C01  I64
  J16     59  VSS24  SCONN288_ADR50001P003C01  I64
  J16     61  VSS25  SCONN288_ADR50001P003C01  I64
  J16     63  VSS26  SCONN288_ADR50001P003C01  I64
  J16     65  VSS27  SCONN288_ADR50001P003C01  I64
  J16     67  VSS28  SCONN288_ADR50001P003C01  I64
  J16     69  VSS29  SCONN288_ADR50001P003C01  I64
  J16     71  VSS30  SCONN288_ADR50001P003C01  I64
  J16     73  VSS31  SCONN288_ADR50001P003C01  I64
  J16     75  VSS32  SCONN288_ADR50001P003C01  I64
  J16     77  VSS33  SCONN288_ADR50001P003C01  I64
  J16     79  VSS34  SCONN288_ADR50001P003C01  I64
  J16     81  VSS35  SCONN288_ADR50001P003C01  I64
  J16     83  VSS36  SCONN288_ADR50001P003C01  I64
  J16     85  VSS37  SCONN288_ADR50001P003C01  I64
  J16     88  VSS38  SCONN288_ADR50001P003C01  I64
  J16     90  VSS39  SCONN288_ADR50001P003C01  I64
  J16     92  VSS40  SCONN288_ADR50001P003C01  I64
  J16     95  VSS41  SCONN288_ADR50001P003C01  I64
  J16     97  VSS42  SCONN288_ADR50001P003C01  I64
  J16     99  VSS43  SCONN288_ADR50001P003C01  I64
  J16    101  VSS44  SCONN288_ADR50001P003C01  I64
  J16    103  VSS45  SCONN288_ADR50001P003C01  I64
  J16    106  VSS46  SCONN288_ADR50001P003C01  I64
  J16    108  VSS47  SCONN288_ADR50001P003C01  I64
  J16    110  VSS48  SCONN288_ADR50001P003C01  I64
  J16    112  VSS49  SCONN288_ADR50001P003C01  I64
  J16    114  VSS50  SCONN288_ADR50001P003C01  I64
  J16    117  VSS51  SCONN288_ADR50001P003C01  I64
  J16    119  VSS52  SCONN288_ADR50001P003C01  I64
  J16    121  VSS53  SCONN288_ADR50001P003C01  I64
  J16    123  VSS54  SCONN288_ADR50001P003C01  I64
  J16    125  VSS55  SCONN288_ADR50001P003C01  I64
  J16    128  VSS56  SCONN288_ADR50001P003C01  I64
  J16    130  VSS57  SCONN288_ADR50001P003C01  I64
  J16    132  VSS58  SCONN288_ADR50001P003C01  I64
  J16    134  VSS59  SCONN288_ADR50001P003C01  I64
  J16    136  VSS60  SCONN288_ADR50001P003C01  I64
  J16    139  VSS61  SCONN288_ADR50001P003C01  I64
  J16    141  VSS62  SCONN288_ADR50001P003C01  I64
  J16    143  VSS63  SCONN288_ADR50001P003C01  I64
  J16    151  VSS64  SCONN288_ADR50001P003C01  I64
  J16    153  VSS65  SCONN288_ADR50001P003C01  I64
  J16    155  VSS66  SCONN288_ADR50001P003C01  I64
  J16    158  VSS67  SCONN288_ADR50001P003C01  I64
  J16    160  VSS68  SCONN288_ADR50001P003C01  I64
  J16    162  VSS69  SCONN288_ADR50001P003C01  I64
  J16    164  VSS70  SCONN288_ADR50001P003C01  I64
  J16    166  VSS71  SCONN288_ADR50001P003C01  I64
  J16    169  VSS72  SCONN288_ADR50001P003C01  I64
  J16    171  VSS73  SCONN288_ADR50001P003C01  I64
  J16    173  VSS74  SCONN288_ADR50001P003C01  I64
  J16    175  VSS75  SCONN288_ADR50001P003C01  I64
  J16    177  VSS76  SCONN288_ADR50001P003C01  I64
  J16    180  VSS77  SCONN288_ADR50001P003C01  I64
  J16    182  VSS78  SCONN288_ADR50001P003C01  I64
  J16    184  VSS79  SCONN288_ADR50001P003C01  I64
  J16    186  VSS80  SCONN288_ADR50001P003C01  I64
  J16    188  VSS81  SCONN288_ADR50001P003C01  I64
  J16    191  VSS82  SCONN288_ADR50001P003C01  I64
  J16    193  VSS83  SCONN288_ADR50001P003C01  I64
  J16    195  VSS84  SCONN288_ADR50001P003C01  I64
  J16    197  VSS85  SCONN288_ADR50001P003C01  I64
  J16    199  VSS86  SCONN288_ADR50001P003C01  I64
  J16    202  VSS87  SCONN288_ADR50001P003C01  I64
  J16    204  VSS88  SCONN288_ADR50001P003C01  I64
  J16    206  VSS89  SCONN288_ADR50001P003C01  I64
  J16    208  VSS90  SCONN288_ADR50001P003C01  I64
  J16    210  VSS91  SCONN288_ADR50001P003C01  I64
  J16    212  VSS92  SCONN288_ADR50001P003C01  I64
  J16    214  VSS93  SCONN288_ADR50001P003C01  I64
  J16    216  VSS94  SCONN288_ADR50001P003C01  I64
  J16    219  VSS95  SCONN288_ADR50001P003C01  I64
  J16    222  VSS96  SCONN288_ADR50001P003C01  I64
  J16    224  VSS97  SCONN288_ADR50001P003C01  I64
  J16    226  VSS98  SCONN288_ADR50001P003C01  I64
  J16    228  VSS99  SCONN288_ADR50001P003C01  I64
  J16    230  VSS100  SCONN288_ADR50001P003C01  I64
  J16    233  VSS101  SCONN288_ADR50001P003C01  I64
  J16    235  VSS102  SCONN288_ADR50001P003C01  I64
  J16    237  VSS103  SCONN288_ADR50001P003C01  I64
  J16    240  VSS104  SCONN288_ADR50001P003C01  I64
  J16    242  VSS105  SCONN288_ADR50001P003C01  I64
  J16    244  VSS106  SCONN288_ADR50001P003C01  I64
  J16    246  VSS107  SCONN288_ADR50001P003C01  I64
  J16    248  VSS108  SCONN288_ADR50001P003C01  I64
  J16    251  VSS109  SCONN288_ADR50001P003C01  I64
  J16    253  VSS110  SCONN288_ADR50001P003C01  I64
  J16    255  VSS111  SCONN288_ADR50001P003C01  I64
  J16    257  VSS112  SCONN288_ADR50001P003C01  I64
  J16    259  VSS113  SCONN288_ADR50001P003C01  I64
  J16    262  VSS114  SCONN288_ADR50001P003C01  I64
  J16    264  VSS115  SCONN288_ADR50001P003C01  I64
  J16    266  VSS116  SCONN288_ADR50001P003C01  I64
  J16    268  VSS117  SCONN288_ADR50001P003C01  I64
  J16    270  VSS118  SCONN288_ADR50001P003C01  I64
  J16    273  VSS119  SCONN288_ADR50001P003C01  I64
  J16    275  VSS120  SCONN288_ADR50001P003C01  I64
  J16    277  VSS121  SCONN288_ADR50001P003C01  I64
  J16    279  VSS122  SCONN288_ADR50001P003C01  I64
  J16    281  VSS123  SCONN288_ADR50001P003C01  I64
  J16    284  VSS124  SCONN288_ADR50001P003C01  I64
  J16    286  VSS125  SCONN288_ADR50001P003C01  I64
  J16    288  VSS126  SCONN288_ADR50001P003C01  I64
  J16     G1     G1  SCONN288_ADR50001P003C01  I64
  J16     G2     G2  SCONN288_ADR50001P003C01  I64
  J16     G3     G3  SCONN288_ADR50001P003C01  I64
  J17      6   VSS0  SCONN288_ADR50001P013C01  I147
  J17      8   VSS1  SCONN288_ADR50001P013C01  I147
  J17     10   VSS2  SCONN288_ADR50001P013C01  I147
  J17     13   VSS3  SCONN288_ADR50001P013C01  I147
  J17     15   VSS4  SCONN288_ADR50001P013C01  I147
  J17     17   VSS5  SCONN288_ADR50001P013C01  I147
  J17     19   VSS6  SCONN288_ADR50001P013C01  I147
  J17     21   VSS7  SCONN288_ADR50001P013C01  I147
  J17     24   VSS8  SCONN288_ADR50001P013C01  I147
  J17     26   VSS9  SCONN288_ADR50001P013C01  I147
  J17     28  VSS10  SCONN288_ADR50001P013C01  I147
  J17     30  VSS11  SCONN288_ADR50001P013C01  I147
  J17     32  VSS12  SCONN288_ADR50001P013C01  I147
  J17     35  VSS13  SCONN288_ADR50001P013C01  I147
  J17     37  VSS14  SCONN288_ADR50001P013C01  I147
  J17     39  VSS15  SCONN288_ADR50001P013C01  I147
  J17     41  VSS16  SCONN288_ADR50001P013C01  I147
  J17     43  VSS17  SCONN288_ADR50001P013C01  I147
  J17     46  VSS18  SCONN288_ADR50001P013C01  I147
  J17     48  VSS19  SCONN288_ADR50001P013C01  I147
  J17     50  VSS20  SCONN288_ADR50001P013C01  I147
  J17     52  VSS21  SCONN288_ADR50001P013C01  I147
  J17     54  VSS22  SCONN288_ADR50001P013C01  I147
  J17     57  VSS23  SCONN288_ADR50001P013C01  I147
  J17     59  VSS24  SCONN288_ADR50001P013C01  I147
  J17     61  VSS25  SCONN288_ADR50001P013C01  I147
  J17     63  VSS26  SCONN288_ADR50001P013C01  I147
  J17     65  VSS27  SCONN288_ADR50001P013C01  I147
  J17     67  VSS28  SCONN288_ADR50001P013C01  I147
  J17     69  VSS29  SCONN288_ADR50001P013C01  I147
  J17     71  VSS30  SCONN288_ADR50001P013C01  I147
  J17     73  VSS31  SCONN288_ADR50001P013C01  I147
  J17     75  VSS32  SCONN288_ADR50001P013C01  I147
  J17     77  VSS33  SCONN288_ADR50001P013C01  I147
  J17     79  VSS34  SCONN288_ADR50001P013C01  I147
  J17     81  VSS35  SCONN288_ADR50001P013C01  I147
  J17     83  VSS36  SCONN288_ADR50001P013C01  I147
  J17     85  VSS37  SCONN288_ADR50001P013C01  I147
  J17     88  VSS38  SCONN288_ADR50001P013C01  I147
  J17     90  VSS39  SCONN288_ADR50001P013C01  I147
  J17     92  VSS40  SCONN288_ADR50001P013C01  I147
  J17     95  VSS41  SCONN288_ADR50001P013C01  I147
  J17     97  VSS42  SCONN288_ADR50001P013C01  I147
  J17     99  VSS43  SCONN288_ADR50001P013C01  I147
  J17    101  VSS44  SCONN288_ADR50001P013C01  I147
  J17    103  VSS45  SCONN288_ADR50001P013C01  I147
  J17    106  VSS46  SCONN288_ADR50001P013C01  I147
  J17    108  VSS47  SCONN288_ADR50001P013C01  I147
  J17    110  VSS48  SCONN288_ADR50001P013C01  I147
  J17    112  VSS49  SCONN288_ADR50001P013C01  I147
  J17    114  VSS50  SCONN288_ADR50001P013C01  I147
  J17    117  VSS51  SCONN288_ADR50001P013C01  I147
  J17    119  VSS52  SCONN288_ADR50001P013C01  I147
  J17    121  VSS53  SCONN288_ADR50001P013C01  I147
  J17    123  VSS54  SCONN288_ADR50001P013C01  I147
  J17    125  VSS55  SCONN288_ADR50001P013C01  I147
  J17    128  VSS56  SCONN288_ADR50001P013C01  I147
  J17    130  VSS57  SCONN288_ADR50001P013C01  I147
  J17    132  VSS58  SCONN288_ADR50001P013C01  I147
  J17    134  VSS59  SCONN288_ADR50001P013C01  I147
  J17    136  VSS60  SCONN288_ADR50001P013C01  I147
  J17    139  VSS61  SCONN288_ADR50001P013C01  I147
  J17    141  VSS62  SCONN288_ADR50001P013C01  I147
  J17    143  VSS63  SCONN288_ADR50001P013C01  I147
  J17    151  VSS64  SCONN288_ADR50001P013C01  I147
  J17    153  VSS65  SCONN288_ADR50001P013C01  I147
  J17    155  VSS66  SCONN288_ADR50001P013C01  I147
  J17    158  VSS67  SCONN288_ADR50001P013C01  I147
  J17    160  VSS68  SCONN288_ADR50001P013C01  I147
  J17    162  VSS69  SCONN288_ADR50001P013C01  I147
  J17    164  VSS70  SCONN288_ADR50001P013C01  I147
  J17    166  VSS71  SCONN288_ADR50001P013C01  I147
  J17    169  VSS72  SCONN288_ADR50001P013C01  I147
  J17    171  VSS73  SCONN288_ADR50001P013C01  I147
  J17    173  VSS74  SCONN288_ADR50001P013C01  I147
  J17    175  VSS75  SCONN288_ADR50001P013C01  I147
  J17    177  VSS76  SCONN288_ADR50001P013C01  I147
  J17    180  VSS77  SCONN288_ADR50001P013C01  I147
  J17    182  VSS78  SCONN288_ADR50001P013C01  I147
  J17    184  VSS79  SCONN288_ADR50001P013C01  I147
  J17    186  VSS80  SCONN288_ADR50001P013C01  I147
  J17    188  VSS81  SCONN288_ADR50001P013C01  I147
  J17    191  VSS82  SCONN288_ADR50001P013C01  I147
  J17    193  VSS83  SCONN288_ADR50001P013C01  I147
  J17    195  VSS84  SCONN288_ADR50001P013C01  I147
  J17    197  VSS85  SCONN288_ADR50001P013C01  I147
  J17    199  VSS86  SCONN288_ADR50001P013C01  I147
  J17    202  VSS87  SCONN288_ADR50001P013C01  I147
  J17    204  VSS88  SCONN288_ADR50001P013C01  I147
  J17    206  VSS89  SCONN288_ADR50001P013C01  I147
  J17    208  VSS90  SCONN288_ADR50001P013C01  I147
  J17    210  VSS91  SCONN288_ADR50001P013C01  I147
  J17    212  VSS92  SCONN288_ADR50001P013C01  I147
  J17    214  VSS93  SCONN288_ADR50001P013C01  I147
  J17    216  VSS94  SCONN288_ADR50001P013C01  I147
  J17    219  VSS95  SCONN288_ADR50001P013C01  I147
  J17    222  VSS96  SCONN288_ADR50001P013C01  I147
  J17    224  VSS97  SCONN288_ADR50001P013C01  I147
  J17    226  VSS98  SCONN288_ADR50001P013C01  I147
  J17    228  VSS99  SCONN288_ADR50001P013C01  I147
  J17    230  VSS100  SCONN288_ADR50001P013C01  I147
  J17    233  VSS101  SCONN288_ADR50001P013C01  I147
  J17    235  VSS102  SCONN288_ADR50001P013C01  I147
  J17    237  VSS103  SCONN288_ADR50001P013C01  I147
  J17    240  VSS104  SCONN288_ADR50001P013C01  I147
  J17    242  VSS105  SCONN288_ADR50001P013C01  I147
  J17    244  VSS106  SCONN288_ADR50001P013C01  I147
  J17    246  VSS107  SCONN288_ADR50001P013C01  I147
  J17    248  VSS108  SCONN288_ADR50001P013C01  I147
  J17    251  VSS109  SCONN288_ADR50001P013C01  I147
  J17    253  VSS110  SCONN288_ADR50001P013C01  I147
  J17    255  VSS111  SCONN288_ADR50001P013C01  I147
  J17    257  VSS112  SCONN288_ADR50001P013C01  I147
  J17    259  VSS113  SCONN288_ADR50001P013C01  I147
  J17    262  VSS114  SCONN288_ADR50001P013C01  I147
  J17    264  VSS115  SCONN288_ADR50001P013C01  I147
  J17    266  VSS116  SCONN288_ADR50001P013C01  I147
  J17    268  VSS117  SCONN288_ADR50001P013C01  I147
  J17    270  VSS118  SCONN288_ADR50001P013C01  I147
  J17    273  VSS119  SCONN288_ADR50001P013C01  I147
  J17    275  VSS120  SCONN288_ADR50001P013C01  I147
  J17    277  VSS121  SCONN288_ADR50001P013C01  I147
  J17    279  VSS122  SCONN288_ADR50001P013C01  I147
  J17    281  VSS123  SCONN288_ADR50001P013C01  I147
  J17    284  VSS124  SCONN288_ADR50001P013C01  I147
  J17    286  VSS125  SCONN288_ADR50001P013C01  I147
  J17    288  VSS126  SCONN288_ADR50001P013C01  I147
  J17     G1     G1  SCONN288_ADR50001P013C01  I147
  J17     G2     G2  SCONN288_ADR50001P013C01  I147
  J17     G3     G3  SCONN288_ADR50001P013C01  I147
  J18      6   VSS0  SCONN288_ADR50001P003C01  I175
  J18      8   VSS1  SCONN288_ADR50001P003C01  I175
  J18     10   VSS2  SCONN288_ADR50001P003C01  I175
  J18     13   VSS3  SCONN288_ADR50001P003C01  I175
  J18     15   VSS4  SCONN288_ADR50001P003C01  I175
  J18     17   VSS5  SCONN288_ADR50001P003C01  I175
  J18     19   VSS6  SCONN288_ADR50001P003C01  I175
  J18     21   VSS7  SCONN288_ADR50001P003C01  I175
  J18     24   VSS8  SCONN288_ADR50001P003C01  I175
  J18     26   VSS9  SCONN288_ADR50001P003C01  I175
  J18     28  VSS10  SCONN288_ADR50001P003C01  I175
  J18     30  VSS11  SCONN288_ADR50001P003C01  I175
  J18     32  VSS12  SCONN288_ADR50001P003C01  I175
  J18     35  VSS13  SCONN288_ADR50001P003C01  I175
  J18     37  VSS14  SCONN288_ADR50001P003C01  I175
  J18     39  VSS15  SCONN288_ADR50001P003C01  I175
  J18     41  VSS16  SCONN288_ADR50001P003C01  I175
  J18     43  VSS17  SCONN288_ADR50001P003C01  I175
  J18     46  VSS18  SCONN288_ADR50001P003C01  I175
  J18     48  VSS19  SCONN288_ADR50001P003C01  I175
  J18     50  VSS20  SCONN288_ADR50001P003C01  I175
  J18     52  VSS21  SCONN288_ADR50001P003C01  I175
  J18     54  VSS22  SCONN288_ADR50001P003C01  I175
  J18     57  VSS23  SCONN288_ADR50001P003C01  I175
  J18     59  VSS24  SCONN288_ADR50001P003C01  I175
  J18     61  VSS25  SCONN288_ADR50001P003C01  I175
  J18     63  VSS26  SCONN288_ADR50001P003C01  I175
  J18     65  VSS27  SCONN288_ADR50001P003C01  I175
  J18     67  VSS28  SCONN288_ADR50001P003C01  I175
  J18     69  VSS29  SCONN288_ADR50001P003C01  I175
  J18     71  VSS30  SCONN288_ADR50001P003C01  I175
  J18     73  VSS31  SCONN288_ADR50001P003C01  I175
  J18     75  VSS32  SCONN288_ADR50001P003C01  I175
  J18     77  VSS33  SCONN288_ADR50001P003C01  I175
  J18     79  VSS34  SCONN288_ADR50001P003C01  I175
  J18     81  VSS35  SCONN288_ADR50001P003C01  I175
  J18     83  VSS36  SCONN288_ADR50001P003C01  I175
  J18     85  VSS37  SCONN288_ADR50001P003C01  I175
  J18     88  VSS38  SCONN288_ADR50001P003C01  I175
  J18     90  VSS39  SCONN288_ADR50001P003C01  I175
  J18     92  VSS40  SCONN288_ADR50001P003C01  I175
  J18     95  VSS41  SCONN288_ADR50001P003C01  I175
  J18     97  VSS42  SCONN288_ADR50001P003C01  I175
  J18     99  VSS43  SCONN288_ADR50001P003C01  I175
  J18    101  VSS44  SCONN288_ADR50001P003C01  I175
  J18    103  VSS45  SCONN288_ADR50001P003C01  I175
  J18    106  VSS46  SCONN288_ADR50001P003C01  I175
  J18    108  VSS47  SCONN288_ADR50001P003C01  I175
  J18    110  VSS48  SCONN288_ADR50001P003C01  I175
  J18    112  VSS49  SCONN288_ADR50001P003C01  I175
  J18    114  VSS50  SCONN288_ADR50001P003C01  I175
  J18    117  VSS51  SCONN288_ADR50001P003C01  I175
  J18    119  VSS52  SCONN288_ADR50001P003C01  I175
  J18    121  VSS53  SCONN288_ADR50001P003C01  I175
  J18    123  VSS54  SCONN288_ADR50001P003C01  I175
  J18    125  VSS55  SCONN288_ADR50001P003C01  I175
  J18    128  VSS56  SCONN288_ADR50001P003C01  I175
  J18    130  VSS57  SCONN288_ADR50001P003C01  I175
  J18    132  VSS58  SCONN288_ADR50001P003C01  I175
  J18    134  VSS59  SCONN288_ADR50001P003C01  I175
  J18    136  VSS60  SCONN288_ADR50001P003C01  I175
  J18    139  VSS61  SCONN288_ADR50001P003C01  I175
  J18    141  VSS62  SCONN288_ADR50001P003C01  I175
  J18    143  VSS63  SCONN288_ADR50001P003C01  I175
  J18    151  VSS64  SCONN288_ADR50001P003C01  I175
  J18    153  VSS65  SCONN288_ADR50001P003C01  I175
  J18    155  VSS66  SCONN288_ADR50001P003C01  I175
  J18    158  VSS67  SCONN288_ADR50001P003C01  I175
  J18    160  VSS68  SCONN288_ADR50001P003C01  I175
  J18    162  VSS69  SCONN288_ADR50001P003C01  I175
  J18    164  VSS70  SCONN288_ADR50001P003C01  I175
  J18    166  VSS71  SCONN288_ADR50001P003C01  I175
  J18    169  VSS72  SCONN288_ADR50001P003C01  I175
  J18    171  VSS73  SCONN288_ADR50001P003C01  I175
  J18    173  VSS74  SCONN288_ADR50001P003C01  I175
  J18    175  VSS75  SCONN288_ADR50001P003C01  I175
  J18    177  VSS76  SCONN288_ADR50001P003C01  I175
  J18    180  VSS77  SCONN288_ADR50001P003C01  I175
  J18    182  VSS78  SCONN288_ADR50001P003C01  I175
  J18    184  VSS79  SCONN288_ADR50001P003C01  I175
  J18    186  VSS80  SCONN288_ADR50001P003C01  I175
  J18    188  VSS81  SCONN288_ADR50001P003C01  I175
  J18    191  VSS82  SCONN288_ADR50001P003C01  I175
  J18    193  VSS83  SCONN288_ADR50001P003C01  I175
  J18    195  VSS84  SCONN288_ADR50001P003C01  I175
  J18    197  VSS85  SCONN288_ADR50001P003C01  I175
  J18    199  VSS86  SCONN288_ADR50001P003C01  I175
  J18    202  VSS87  SCONN288_ADR50001P003C01  I175
  J18    204  VSS88  SCONN288_ADR50001P003C01  I175
  J18    206  VSS89  SCONN288_ADR50001P003C01  I175
  J18    208  VSS90  SCONN288_ADR50001P003C01  I175
  J18    210  VSS91  SCONN288_ADR50001P003C01  I175
  J18    212  VSS92  SCONN288_ADR50001P003C01  I175
  J18    214  VSS93  SCONN288_ADR50001P003C01  I175
  J18    216  VSS94  SCONN288_ADR50001P003C01  I175
  J18    219  VSS95  SCONN288_ADR50001P003C01  I175
  J18    222  VSS96  SCONN288_ADR50001P003C01  I175
  J18    224  VSS97  SCONN288_ADR50001P003C01  I175
  J18    226  VSS98  SCONN288_ADR50001P003C01  I175
  J18    228  VSS99  SCONN288_ADR50001P003C01  I175
  J18    230  VSS100  SCONN288_ADR50001P003C01  I175
  J18    233  VSS101  SCONN288_ADR50001P003C01  I175
  J18    235  VSS102  SCONN288_ADR50001P003C01  I175
  J18    237  VSS103  SCONN288_ADR50001P003C01  I175
  J18    240  VSS104  SCONN288_ADR50001P003C01  I175
  J18    242  VSS105  SCONN288_ADR50001P003C01  I175
  J18    244  VSS106  SCONN288_ADR50001P003C01  I175
  J18    246  VSS107  SCONN288_ADR50001P003C01  I175
  J18    248  VSS108  SCONN288_ADR50001P003C01  I175
  J18    251  VSS109  SCONN288_ADR50001P003C01  I175
  J18    253  VSS110  SCONN288_ADR50001P003C01  I175
  J18    255  VSS111  SCONN288_ADR50001P003C01  I175
  J18    257  VSS112  SCONN288_ADR50001P003C01  I175
  J18    259  VSS113  SCONN288_ADR50001P003C01  I175
  J18    262  VSS114  SCONN288_ADR50001P003C01  I175
  J18    264  VSS115  SCONN288_ADR50001P003C01  I175
  J18    266  VSS116  SCONN288_ADR50001P003C01  I175
  J18    268  VSS117  SCONN288_ADR50001P003C01  I175
  J18    270  VSS118  SCONN288_ADR50001P003C01  I175
  J18    273  VSS119  SCONN288_ADR50001P003C01  I175
  J18    275  VSS120  SCONN288_ADR50001P003C01  I175
  J18    277  VSS121  SCONN288_ADR50001P003C01  I175
  J18    279  VSS122  SCONN288_ADR50001P003C01  I175
  J18    281  VSS123  SCONN288_ADR50001P003C01  I175
  J18    284  VSS124  SCONN288_ADR50001P003C01  I175
  J18    286  VSS125  SCONN288_ADR50001P003C01  I175
  J18    288  VSS126  SCONN288_ADR50001P003C01  I175
  J18     G1     G1  SCONN288_ADR50001P003C01  I175
  J18     G2     G2  SCONN288_ADR50001P003C01  I175
  J18     G3     G3  SCONN288_ADR50001P003C01  I175
  J19      6   VSS0  SCONN288_ADR50001P013C01  I175
  J19      8   VSS1  SCONN288_ADR50001P013C01  I175
  J19     10   VSS2  SCONN288_ADR50001P013C01  I175
  J19     13   VSS3  SCONN288_ADR50001P013C01  I175
  J19     15   VSS4  SCONN288_ADR50001P013C01  I175
  J19     17   VSS5  SCONN288_ADR50001P013C01  I175
  J19     19   VSS6  SCONN288_ADR50001P013C01  I175
  J19     21   VSS7  SCONN288_ADR50001P013C01  I175
  J19     24   VSS8  SCONN288_ADR50001P013C01  I175
  J19     26   VSS9  SCONN288_ADR50001P013C01  I175
  J19     28  VSS10  SCONN288_ADR50001P013C01  I175
  J19     30  VSS11  SCONN288_ADR50001P013C01  I175
  J19     32  VSS12  SCONN288_ADR50001P013C01  I175
  J19     35  VSS13  SCONN288_ADR50001P013C01  I175
  J19     37  VSS14  SCONN288_ADR50001P013C01  I175
  J19     39  VSS15  SCONN288_ADR50001P013C01  I175
  J19     41  VSS16  SCONN288_ADR50001P013C01  I175
  J19     43  VSS17  SCONN288_ADR50001P013C01  I175
  J19     46  VSS18  SCONN288_ADR50001P013C01  I175
  J19     48  VSS19  SCONN288_ADR50001P013C01  I175
  J19     50  VSS20  SCONN288_ADR50001P013C01  I175
  J19     52  VSS21  SCONN288_ADR50001P013C01  I175
  J19     54  VSS22  SCONN288_ADR50001P013C01  I175
  J19     57  VSS23  SCONN288_ADR50001P013C01  I175
  J19     59  VSS24  SCONN288_ADR50001P013C01  I175
  J19     61  VSS25  SCONN288_ADR50001P013C01  I175
  J19     63  VSS26  SCONN288_ADR50001P013C01  I175
  J19     65  VSS27  SCONN288_ADR50001P013C01  I175
  J19     67  VSS28  SCONN288_ADR50001P013C01  I175
  J19     69  VSS29  SCONN288_ADR50001P013C01  I175
  J19     71  VSS30  SCONN288_ADR50001P013C01  I175
  J19     73  VSS31  SCONN288_ADR50001P013C01  I175
  J19     75  VSS32  SCONN288_ADR50001P013C01  I175
  J19     77  VSS33  SCONN288_ADR50001P013C01  I175
  J19     79  VSS34  SCONN288_ADR50001P013C01  I175
  J19     81  VSS35  SCONN288_ADR50001P013C01  I175
  J19     83  VSS36  SCONN288_ADR50001P013C01  I175
  J19     85  VSS37  SCONN288_ADR50001P013C01  I175
  J19     88  VSS38  SCONN288_ADR50001P013C01  I175
  J19     90  VSS39  SCONN288_ADR50001P013C01  I175
  J19     92  VSS40  SCONN288_ADR50001P013C01  I175
  J19     95  VSS41  SCONN288_ADR50001P013C01  I175
  J19     97  VSS42  SCONN288_ADR50001P013C01  I175
  J19     99  VSS43  SCONN288_ADR50001P013C01  I175
  J19    101  VSS44  SCONN288_ADR50001P013C01  I175
  J19    103  VSS45  SCONN288_ADR50001P013C01  I175
  J19    106  VSS46  SCONN288_ADR50001P013C01  I175
  J19    108  VSS47  SCONN288_ADR50001P013C01  I175
  J19    110  VSS48  SCONN288_ADR50001P013C01  I175
  J19    112  VSS49  SCONN288_ADR50001P013C01  I175
  J19    114  VSS50  SCONN288_ADR50001P013C01  I175
  J19    117  VSS51  SCONN288_ADR50001P013C01  I175
  J19    119  VSS52  SCONN288_ADR50001P013C01  I175
  J19    121  VSS53  SCONN288_ADR50001P013C01  I175
  J19    123  VSS54  SCONN288_ADR50001P013C01  I175
  J19    125  VSS55  SCONN288_ADR50001P013C01  I175
  J19    128  VSS56  SCONN288_ADR50001P013C01  I175
  J19    130  VSS57  SCONN288_ADR50001P013C01  I175
  J19    132  VSS58  SCONN288_ADR50001P013C01  I175
  J19    134  VSS59  SCONN288_ADR50001P013C01  I175
  J19    136  VSS60  SCONN288_ADR50001P013C01  I175
  J19    139  VSS61  SCONN288_ADR50001P013C01  I175
  J19    141  VSS62  SCONN288_ADR50001P013C01  I175
  J19    143  VSS63  SCONN288_ADR50001P013C01  I175
  J19    151  VSS64  SCONN288_ADR50001P013C01  I175
  J19    153  VSS65  SCONN288_ADR50001P013C01  I175
  J19    155  VSS66  SCONN288_ADR50001P013C01  I175
  J19    158  VSS67  SCONN288_ADR50001P013C01  I175
  J19    160  VSS68  SCONN288_ADR50001P013C01  I175
  J19    162  VSS69  SCONN288_ADR50001P013C01  I175
  J19    164  VSS70  SCONN288_ADR50001P013C01  I175
  J19    166  VSS71  SCONN288_ADR50001P013C01  I175
  J19    169  VSS72  SCONN288_ADR50001P013C01  I175
  J19    171  VSS73  SCONN288_ADR50001P013C01  I175
  J19    173  VSS74  SCONN288_ADR50001P013C01  I175
  J19    175  VSS75  SCONN288_ADR50001P013C01  I175
  J19    177  VSS76  SCONN288_ADR50001P013C01  I175
  J19    180  VSS77  SCONN288_ADR50001P013C01  I175
  J19    182  VSS78  SCONN288_ADR50001P013C01  I175
  J19    184  VSS79  SCONN288_ADR50001P013C01  I175
  J19    186  VSS80  SCONN288_ADR50001P013C01  I175
  J19    188  VSS81  SCONN288_ADR50001P013C01  I175
  J19    191  VSS82  SCONN288_ADR50001P013C01  I175
  J19    193  VSS83  SCONN288_ADR50001P013C01  I175
  J19    195  VSS84  SCONN288_ADR50001P013C01  I175
  J19    197  VSS85  SCONN288_ADR50001P013C01  I175
  J19    199  VSS86  SCONN288_ADR50001P013C01  I175
  J19    202  VSS87  SCONN288_ADR50001P013C01  I175
  J19    204  VSS88  SCONN288_ADR50001P013C01  I175
  J19    206  VSS89  SCONN288_ADR50001P013C01  I175
  J19    208  VSS90  SCONN288_ADR50001P013C01  I175
  J19    210  VSS91  SCONN288_ADR50001P013C01  I175
  J19    212  VSS92  SCONN288_ADR50001P013C01  I175
  J19    214  VSS93  SCONN288_ADR50001P013C01  I175
  J19    216  VSS94  SCONN288_ADR50001P013C01  I175
  J19    219  VSS95  SCONN288_ADR50001P013C01  I175
  J19    222  VSS96  SCONN288_ADR50001P013C01  I175
  J19    224  VSS97  SCONN288_ADR50001P013C01  I175
  J19    226  VSS98  SCONN288_ADR50001P013C01  I175
  J19    228  VSS99  SCONN288_ADR50001P013C01  I175
  J19    230  VSS100  SCONN288_ADR50001P013C01  I175
  J19    233  VSS101  SCONN288_ADR50001P013C01  I175
  J19    235  VSS102  SCONN288_ADR50001P013C01  I175
  J19    237  VSS103  SCONN288_ADR50001P013C01  I175
  J19    240  VSS104  SCONN288_ADR50001P013C01  I175
  J19    242  VSS105  SCONN288_ADR50001P013C01  I175
  J19    244  VSS106  SCONN288_ADR50001P013C01  I175
  J19    246  VSS107  SCONN288_ADR50001P013C01  I175
  J19    248  VSS108  SCONN288_ADR50001P013C01  I175
  J19    251  VSS109  SCONN288_ADR50001P013C01  I175
  J19    253  VSS110  SCONN288_ADR50001P013C01  I175
  J19    255  VSS111  SCONN288_ADR50001P013C01  I175
  J19    257  VSS112  SCONN288_ADR50001P013C01  I175
  J19    259  VSS113  SCONN288_ADR50001P013C01  I175
  J19    262  VSS114  SCONN288_ADR50001P013C01  I175
  J19    264  VSS115  SCONN288_ADR50001P013C01  I175
  J19    266  VSS116  SCONN288_ADR50001P013C01  I175
  J19    268  VSS117  SCONN288_ADR50001P013C01  I175
  J19    270  VSS118  SCONN288_ADR50001P013C01  I175
  J19    273  VSS119  SCONN288_ADR50001P013C01  I175
  J19    275  VSS120  SCONN288_ADR50001P013C01  I175
  J19    277  VSS121  SCONN288_ADR50001P013C01  I175
  J19    279  VSS122  SCONN288_ADR50001P013C01  I175
  J19    281  VSS123  SCONN288_ADR50001P013C01  I175
  J19    284  VSS124  SCONN288_ADR50001P013C01  I175
  J19    286  VSS125  SCONN288_ADR50001P013C01  I175
  J19    288  VSS126  SCONN288_ADR50001P013C01  I175
  J19     G1     G1  SCONN288_ADR50001P013C01  I175
  J19     G2     G2  SCONN288_ADR50001P013C01  I175
  J19     G3     G3  SCONN288_ADR50001P013C01  I175
  J20      6   VSS0  SCONN288_ADR50001P003C01  I176
  J20      8   VSS1  SCONN288_ADR50001P003C01  I176
  J20     10   VSS2  SCONN288_ADR50001P003C01  I176
  J20     13   VSS3  SCONN288_ADR50001P003C01  I176
  J20     15   VSS4  SCONN288_ADR50001P003C01  I176
  J20     17   VSS5  SCONN288_ADR50001P003C01  I176
  J20     19   VSS6  SCONN288_ADR50001P003C01  I176
  J20     21   VSS7  SCONN288_ADR50001P003C01  I176
  J20     24   VSS8  SCONN288_ADR50001P003C01  I176
  J20     26   VSS9  SCONN288_ADR50001P003C01  I176
  J20     28  VSS10  SCONN288_ADR50001P003C01  I176
  J20     30  VSS11  SCONN288_ADR50001P003C01  I176
  J20     32  VSS12  SCONN288_ADR50001P003C01  I176
  J20     35  VSS13  SCONN288_ADR50001P003C01  I176
  J20     37  VSS14  SCONN288_ADR50001P003C01  I176
  J20     39  VSS15  SCONN288_ADR50001P003C01  I176
  J20     41  VSS16  SCONN288_ADR50001P003C01  I176
  J20     43  VSS17  SCONN288_ADR50001P003C01  I176
  J20     46  VSS18  SCONN288_ADR50001P003C01  I176
  J20     48  VSS19  SCONN288_ADR50001P003C01  I176
  J20     50  VSS20  SCONN288_ADR50001P003C01  I176
  J20     52  VSS21  SCONN288_ADR50001P003C01  I176
  J20     54  VSS22  SCONN288_ADR50001P003C01  I176
  J20     57  VSS23  SCONN288_ADR50001P003C01  I176
  J20     59  VSS24  SCONN288_ADR50001P003C01  I176
  J20     61  VSS25  SCONN288_ADR50001P003C01  I176
  J20     63  VSS26  SCONN288_ADR50001P003C01  I176
  J20     65  VSS27  SCONN288_ADR50001P003C01  I176
  J20     67  VSS28  SCONN288_ADR50001P003C01  I176
  J20     69  VSS29  SCONN288_ADR50001P003C01  I176
  J20     71  VSS30  SCONN288_ADR50001P003C01  I176
  J20     73  VSS31  SCONN288_ADR50001P003C01  I176
  J20     75  VSS32  SCONN288_ADR50001P003C01  I176
  J20     77  VSS33  SCONN288_ADR50001P003C01  I176
  J20     79  VSS34  SCONN288_ADR50001P003C01  I176
  J20     81  VSS35  SCONN288_ADR50001P003C01  I176
  J20     83  VSS36  SCONN288_ADR50001P003C01  I176
  J20     85  VSS37  SCONN288_ADR50001P003C01  I176
  J20     88  VSS38  SCONN288_ADR50001P003C01  I176
  J20     90  VSS39  SCONN288_ADR50001P003C01  I176
  J20     92  VSS40  SCONN288_ADR50001P003C01  I176
  J20     95  VSS41  SCONN288_ADR50001P003C01  I176
  J20     97  VSS42  SCONN288_ADR50001P003C01  I176
  J20     99  VSS43  SCONN288_ADR50001P003C01  I176
  J20    101  VSS44  SCONN288_ADR50001P003C01  I176
  J20    103  VSS45  SCONN288_ADR50001P003C01  I176
  J20    106  VSS46  SCONN288_ADR50001P003C01  I176
  J20    108  VSS47  SCONN288_ADR50001P003C01  I176
  J20    110  VSS48  SCONN288_ADR50001P003C01  I176
  J20    112  VSS49  SCONN288_ADR50001P003C01  I176
  J20    114  VSS50  SCONN288_ADR50001P003C01  I176
  J20    117  VSS51  SCONN288_ADR50001P003C01  I176
  J20    119  VSS52  SCONN288_ADR50001P003C01  I176
  J20    121  VSS53  SCONN288_ADR50001P003C01  I176
  J20    123  VSS54  SCONN288_ADR50001P003C01  I176
  J20    125  VSS55  SCONN288_ADR50001P003C01  I176
  J20    128  VSS56  SCONN288_ADR50001P003C01  I176
  J20    130  VSS57  SCONN288_ADR50001P003C01  I176
  J20    132  VSS58  SCONN288_ADR50001P003C01  I176
  J20    134  VSS59  SCONN288_ADR50001P003C01  I176
  J20    136  VSS60  SCONN288_ADR50001P003C01  I176
  J20    139  VSS61  SCONN288_ADR50001P003C01  I176
  J20    141  VSS62  SCONN288_ADR50001P003C01  I176
  J20    143  VSS63  SCONN288_ADR50001P003C01  I176
  J20    151  VSS64  SCONN288_ADR50001P003C01  I176
  J20    153  VSS65  SCONN288_ADR50001P003C01  I176
  J20    155  VSS66  SCONN288_ADR50001P003C01  I176
  J20    158  VSS67  SCONN288_ADR50001P003C01  I176
  J20    160  VSS68  SCONN288_ADR50001P003C01  I176
  J20    162  VSS69  SCONN288_ADR50001P003C01  I176
  J20    164  VSS70  SCONN288_ADR50001P003C01  I176
  J20    166  VSS71  SCONN288_ADR50001P003C01  I176
  J20    169  VSS72  SCONN288_ADR50001P003C01  I176
  J20    171  VSS73  SCONN288_ADR50001P003C01  I176
  J20    173  VSS74  SCONN288_ADR50001P003C01  I176
  J20    175  VSS75  SCONN288_ADR50001P003C01  I176
  J20    177  VSS76  SCONN288_ADR50001P003C01  I176
  J20    180  VSS77  SCONN288_ADR50001P003C01  I176
  J20    182  VSS78  SCONN288_ADR50001P003C01  I176
  J20    184  VSS79  SCONN288_ADR50001P003C01  I176
  J20    186  VSS80  SCONN288_ADR50001P003C01  I176
  J20    188  VSS81  SCONN288_ADR50001P003C01  I176
  J20    191  VSS82  SCONN288_ADR50001P003C01  I176
  J20    193  VSS83  SCONN288_ADR50001P003C01  I176
  J20    195  VSS84  SCONN288_ADR50001P003C01  I176
  J20    197  VSS85  SCONN288_ADR50001P003C01  I176
  J20    199  VSS86  SCONN288_ADR50001P003C01  I176
  J20    202  VSS87  SCONN288_ADR50001P003C01  I176
  J20    204  VSS88  SCONN288_ADR50001P003C01  I176
  J20    206  VSS89  SCONN288_ADR50001P003C01  I176
  J20    208  VSS90  SCONN288_ADR50001P003C01  I176
  J20    210  VSS91  SCONN288_ADR50001P003C01  I176
  J20    212  VSS92  SCONN288_ADR50001P003C01  I176
  J20    214  VSS93  SCONN288_ADR50001P003C01  I176
  J20    216  VSS94  SCONN288_ADR50001P003C01  I176
  J20    219  VSS95  SCONN288_ADR50001P003C01  I176
  J20    222  VSS96  SCONN288_ADR50001P003C01  I176
  J20    224  VSS97  SCONN288_ADR50001P003C01  I176
  J20    226  VSS98  SCONN288_ADR50001P003C01  I176
  J20    228  VSS99  SCONN288_ADR50001P003C01  I176
  J20    230  VSS100  SCONN288_ADR50001P003C01  I176
  J20    233  VSS101  SCONN288_ADR50001P003C01  I176
  J20    235  VSS102  SCONN288_ADR50001P003C01  I176
  J20    237  VSS103  SCONN288_ADR50001P003C01  I176
  J20    240  VSS104  SCONN288_ADR50001P003C01  I176
  J20    242  VSS105  SCONN288_ADR50001P003C01  I176
  J20    244  VSS106  SCONN288_ADR50001P003C01  I176
  J20    246  VSS107  SCONN288_ADR50001P003C01  I176
  J20    248  VSS108  SCONN288_ADR50001P003C01  I176
  J20    251  VSS109  SCONN288_ADR50001P003C01  I176
  J20    253  VSS110  SCONN288_ADR50001P003C01  I176
  J20    255  VSS111  SCONN288_ADR50001P003C01  I176
  J20    257  VSS112  SCONN288_ADR50001P003C01  I176
  J20    259  VSS113  SCONN288_ADR50001P003C01  I176
  J20    262  VSS114  SCONN288_ADR50001P003C01  I176
  J20    264  VSS115  SCONN288_ADR50001P003C01  I176
  J20    266  VSS116  SCONN288_ADR50001P003C01  I176
  J20    268  VSS117  SCONN288_ADR50001P003C01  I176
  J20    270  VSS118  SCONN288_ADR50001P003C01  I176
  J20    273  VSS119  SCONN288_ADR50001P003C01  I176
  J20    275  VSS120  SCONN288_ADR50001P003C01  I176
  J20    277  VSS121  SCONN288_ADR50001P003C01  I176
  J20    279  VSS122  SCONN288_ADR50001P003C01  I176
  J20    281  VSS123  SCONN288_ADR50001P003C01  I176
  J20    284  VSS124  SCONN288_ADR50001P003C01  I176
  J20    286  VSS125  SCONN288_ADR50001P003C01  I176
  J20    288  VSS126  SCONN288_ADR50001P003C01  I176
  J20     G1     G1  SCONN288_ADR50001P003C01  I176
  J20     G2     G2  SCONN288_ADR50001P003C01  I176
  J20     G3     G3  SCONN288_ADR50001P003C01  I176
  J21      6   VSS0  SCONN288_ADR50001P013C01  I169
  J21      8   VSS1  SCONN288_ADR50001P013C01  I169
  J21     10   VSS2  SCONN288_ADR50001P013C01  I169
  J21     13   VSS3  SCONN288_ADR50001P013C01  I169
  J21     15   VSS4  SCONN288_ADR50001P013C01  I169
  J21     17   VSS5  SCONN288_ADR50001P013C01  I169
  J21     19   VSS6  SCONN288_ADR50001P013C01  I169
  J21     21   VSS7  SCONN288_ADR50001P013C01  I169
  J21     24   VSS8  SCONN288_ADR50001P013C01  I169
  J21     26   VSS9  SCONN288_ADR50001P013C01  I169
  J21     28  VSS10  SCONN288_ADR50001P013C01  I169
  J21     30  VSS11  SCONN288_ADR50001P013C01  I169
  J21     32  VSS12  SCONN288_ADR50001P013C01  I169
  J21     35  VSS13  SCONN288_ADR50001P013C01  I169
  J21     37  VSS14  SCONN288_ADR50001P013C01  I169
  J21     39  VSS15  SCONN288_ADR50001P013C01  I169
  J21     41  VSS16  SCONN288_ADR50001P013C01  I169
  J21     43  VSS17  SCONN288_ADR50001P013C01  I169
  J21     46  VSS18  SCONN288_ADR50001P013C01  I169
  J21     48  VSS19  SCONN288_ADR50001P013C01  I169
  J21     50  VSS20  SCONN288_ADR50001P013C01  I169
  J21     52  VSS21  SCONN288_ADR50001P013C01  I169
  J21     54  VSS22  SCONN288_ADR50001P013C01  I169
  J21     57  VSS23  SCONN288_ADR50001P013C01  I169
  J21     59  VSS24  SCONN288_ADR50001P013C01  I169
  J21     61  VSS25  SCONN288_ADR50001P013C01  I169
  J21     63  VSS26  SCONN288_ADR50001P013C01  I169
  J21     65  VSS27  SCONN288_ADR50001P013C01  I169
  J21     67  VSS28  SCONN288_ADR50001P013C01  I169
  J21     69  VSS29  SCONN288_ADR50001P013C01  I169
  J21     71  VSS30  SCONN288_ADR50001P013C01  I169
  J21     73  VSS31  SCONN288_ADR50001P013C01  I169
  J21     75  VSS32  SCONN288_ADR50001P013C01  I169
  J21     77  VSS33  SCONN288_ADR50001P013C01  I169
  J21     79  VSS34  SCONN288_ADR50001P013C01  I169
  J21     81  VSS35  SCONN288_ADR50001P013C01  I169
  J21     83  VSS36  SCONN288_ADR50001P013C01  I169
  J21     85  VSS37  SCONN288_ADR50001P013C01  I169
  J21     88  VSS38  SCONN288_ADR50001P013C01  I169
  J21     90  VSS39  SCONN288_ADR50001P013C01  I169
  J21     92  VSS40  SCONN288_ADR50001P013C01  I169
  J21     95  VSS41  SCONN288_ADR50001P013C01  I169
  J21     97  VSS42  SCONN288_ADR50001P013C01  I169
  J21     99  VSS43  SCONN288_ADR50001P013C01  I169
  J21    101  VSS44  SCONN288_ADR50001P013C01  I169
  J21    103  VSS45  SCONN288_ADR50001P013C01  I169
  J21    106  VSS46  SCONN288_ADR50001P013C01  I169
  J21    108  VSS47  SCONN288_ADR50001P013C01  I169
  J21    110  VSS48  SCONN288_ADR50001P013C01  I169
  J21    112  VSS49  SCONN288_ADR50001P013C01  I169
  J21    114  VSS50  SCONN288_ADR50001P013C01  I169
  J21    117  VSS51  SCONN288_ADR50001P013C01  I169
  J21    119  VSS52  SCONN288_ADR50001P013C01  I169
  J21    121  VSS53  SCONN288_ADR50001P013C01  I169
  J21    123  VSS54  SCONN288_ADR50001P013C01  I169
  J21    125  VSS55  SCONN288_ADR50001P013C01  I169
  J21    128  VSS56  SCONN288_ADR50001P013C01  I169
  J21    130  VSS57  SCONN288_ADR50001P013C01  I169
  J21    132  VSS58  SCONN288_ADR50001P013C01  I169
  J21    134  VSS59  SCONN288_ADR50001P013C01  I169
  J21    136  VSS60  SCONN288_ADR50001P013C01  I169
  J21    139  VSS61  SCONN288_ADR50001P013C01  I169
  J21    141  VSS62  SCONN288_ADR50001P013C01  I169
  J21    143  VSS63  SCONN288_ADR50001P013C01  I169
  J21    151  VSS64  SCONN288_ADR50001P013C01  I169
  J21    153  VSS65  SCONN288_ADR50001P013C01  I169
  J21    155  VSS66  SCONN288_ADR50001P013C01  I169
  J21    158  VSS67  SCONN288_ADR50001P013C01  I169
  J21    160  VSS68  SCONN288_ADR50001P013C01  I169
  J21    162  VSS69  SCONN288_ADR50001P013C01  I169
  J21    164  VSS70  SCONN288_ADR50001P013C01  I169
  J21    166  VSS71  SCONN288_ADR50001P013C01  I169
  J21    169  VSS72  SCONN288_ADR50001P013C01  I169
  J21    171  VSS73  SCONN288_ADR50001P013C01  I169
  J21    173  VSS74  SCONN288_ADR50001P013C01  I169
  J21    175  VSS75  SCONN288_ADR50001P013C01  I169
  J21    177  VSS76  SCONN288_ADR50001P013C01  I169
  J21    180  VSS77  SCONN288_ADR50001P013C01  I169
  J21    182  VSS78  SCONN288_ADR50001P013C01  I169
  J21    184  VSS79  SCONN288_ADR50001P013C01  I169
  J21    186  VSS80  SCONN288_ADR50001P013C01  I169
  J21    188  VSS81  SCONN288_ADR50001P013C01  I169
  J21    191  VSS82  SCONN288_ADR50001P013C01  I169
  J21    193  VSS83  SCONN288_ADR50001P013C01  I169
  J21    195  VSS84  SCONN288_ADR50001P013C01  I169
  J21    197  VSS85  SCONN288_ADR50001P013C01  I169
  J21    199  VSS86  SCONN288_ADR50001P013C01  I169
  J21    202  VSS87  SCONN288_ADR50001P013C01  I169
  J21    204  VSS88  SCONN288_ADR50001P013C01  I169
  J21    206  VSS89  SCONN288_ADR50001P013C01  I169
  J21    208  VSS90  SCONN288_ADR50001P013C01  I169
  J21    210  VSS91  SCONN288_ADR50001P013C01  I169
  J21    212  VSS92  SCONN288_ADR50001P013C01  I169
  J21    214  VSS93  SCONN288_ADR50001P013C01  I169
  J21    216  VSS94  SCONN288_ADR50001P013C01  I169
  J21    219  VSS95  SCONN288_ADR50001P013C01  I169
  J21    222  VSS96  SCONN288_ADR50001P013C01  I169
  J21    224  VSS97  SCONN288_ADR50001P013C01  I169
  J21    226  VSS98  SCONN288_ADR50001P013C01  I169
  J21    228  VSS99  SCONN288_ADR50001P013C01  I169
  J21    230  VSS100  SCONN288_ADR50001P013C01  I169
  J21    233  VSS101  SCONN288_ADR50001P013C01  I169
  J21    235  VSS102  SCONN288_ADR50001P013C01  I169
  J21    237  VSS103  SCONN288_ADR50001P013C01  I169
  J21    240  VSS104  SCONN288_ADR50001P013C01  I169
  J21    242  VSS105  SCONN288_ADR50001P013C01  I169
  J21    244  VSS106  SCONN288_ADR50001P013C01  I169
  J21    246  VSS107  SCONN288_ADR50001P013C01  I169
  J21    248  VSS108  SCONN288_ADR50001P013C01  I169
  J21    251  VSS109  SCONN288_ADR50001P013C01  I169
  J21    253  VSS110  SCONN288_ADR50001P013C01  I169
  J21    255  VSS111  SCONN288_ADR50001P013C01  I169
  J21    257  VSS112  SCONN288_ADR50001P013C01  I169
  J21    259  VSS113  SCONN288_ADR50001P013C01  I169
  J21    262  VSS114  SCONN288_ADR50001P013C01  I169
  J21    264  VSS115  SCONN288_ADR50001P013C01  I169
  J21    266  VSS116  SCONN288_ADR50001P013C01  I169
  J21    268  VSS117  SCONN288_ADR50001P013C01  I169
  J21    270  VSS118  SCONN288_ADR50001P013C01  I169
  J21    273  VSS119  SCONN288_ADR50001P013C01  I169
  J21    275  VSS120  SCONN288_ADR50001P013C01  I169
  J21    277  VSS121  SCONN288_ADR50001P013C01  I169
  J21    279  VSS122  SCONN288_ADR50001P013C01  I169
  J21    281  VSS123  SCONN288_ADR50001P013C01  I169
  J21    284  VSS124  SCONN288_ADR50001P013C01  I169
  J21    286  VSS125  SCONN288_ADR50001P013C01  I169
  J21    288  VSS126  SCONN288_ADR50001P013C01  I169
  J21     G1     G1  SCONN288_ADR50001P013C01  I169
  J21     G2     G2  SCONN288_ADR50001P013C01  I169
  J21     G3     G3  SCONN288_ADR50001P013C01  I169
  J22      6   VSS0  SCONN288_ADR50001P003C01  I176
  J22      8   VSS1  SCONN288_ADR50001P003C01  I176
  J22     10   VSS2  SCONN288_ADR50001P003C01  I176
  J22     13   VSS3  SCONN288_ADR50001P003C01  I176
  J22     15   VSS4  SCONN288_ADR50001P003C01  I176
  J22     17   VSS5  SCONN288_ADR50001P003C01  I176
  J22     19   VSS6  SCONN288_ADR50001P003C01  I176
  J22     21   VSS7  SCONN288_ADR50001P003C01  I176
  J22     24   VSS8  SCONN288_ADR50001P003C01  I176
  J22     26   VSS9  SCONN288_ADR50001P003C01  I176
  J22     28  VSS10  SCONN288_ADR50001P003C01  I176
  J22     30  VSS11  SCONN288_ADR50001P003C01  I176
  J22     32  VSS12  SCONN288_ADR50001P003C01  I176
  J22     35  VSS13  SCONN288_ADR50001P003C01  I176
  J22     37  VSS14  SCONN288_ADR50001P003C01  I176
  J22     39  VSS15  SCONN288_ADR50001P003C01  I176
  J22     41  VSS16  SCONN288_ADR50001P003C01  I176
  J22     43  VSS17  SCONN288_ADR50001P003C01  I176
  J22     46  VSS18  SCONN288_ADR50001P003C01  I176
  J22     48  VSS19  SCONN288_ADR50001P003C01  I176
  J22     50  VSS20  SCONN288_ADR50001P003C01  I176
  J22     52  VSS21  SCONN288_ADR50001P003C01  I176
  J22     54  VSS22  SCONN288_ADR50001P003C01  I176
  J22     57  VSS23  SCONN288_ADR50001P003C01  I176
  J22     59  VSS24  SCONN288_ADR50001P003C01  I176
  J22     61  VSS25  SCONN288_ADR50001P003C01  I176
  J22     63  VSS26  SCONN288_ADR50001P003C01  I176
  J22     65  VSS27  SCONN288_ADR50001P003C01  I176
  J22     67  VSS28  SCONN288_ADR50001P003C01  I176
  J22     69  VSS29  SCONN288_ADR50001P003C01  I176
  J22     71  VSS30  SCONN288_ADR50001P003C01  I176
  J22     73  VSS31  SCONN288_ADR50001P003C01  I176
  J22     75  VSS32  SCONN288_ADR50001P003C01  I176
  J22     77  VSS33  SCONN288_ADR50001P003C01  I176
  J22     79  VSS34  SCONN288_ADR50001P003C01  I176
  J22     81  VSS35  SCONN288_ADR50001P003C01  I176
  J22     83  VSS36  SCONN288_ADR50001P003C01  I176
  J22     85  VSS37  SCONN288_ADR50001P003C01  I176
  J22     88  VSS38  SCONN288_ADR50001P003C01  I176
  J22     90  VSS39  SCONN288_ADR50001P003C01  I176
  J22     92  VSS40  SCONN288_ADR50001P003C01  I176
  J22     95  VSS41  SCONN288_ADR50001P003C01  I176
  J22     97  VSS42  SCONN288_ADR50001P003C01  I176
  J22     99  VSS43  SCONN288_ADR50001P003C01  I176
  J22    101  VSS44  SCONN288_ADR50001P003C01  I176
  J22    103  VSS45  SCONN288_ADR50001P003C01  I176
  J22    106  VSS46  SCONN288_ADR50001P003C01  I176
  J22    108  VSS47  SCONN288_ADR50001P003C01  I176
  J22    110  VSS48  SCONN288_ADR50001P003C01  I176
  J22    112  VSS49  SCONN288_ADR50001P003C01  I176
  J22    114  VSS50  SCONN288_ADR50001P003C01  I176
  J22    117  VSS51  SCONN288_ADR50001P003C01  I176
  J22    119  VSS52  SCONN288_ADR50001P003C01  I176
  J22    121  VSS53  SCONN288_ADR50001P003C01  I176
  J22    123  VSS54  SCONN288_ADR50001P003C01  I176
  J22    125  VSS55  SCONN288_ADR50001P003C01  I176
  J22    128  VSS56  SCONN288_ADR50001P003C01  I176
  J22    130  VSS57  SCONN288_ADR50001P003C01  I176
  J22    132  VSS58  SCONN288_ADR50001P003C01  I176
  J22    134  VSS59  SCONN288_ADR50001P003C01  I176
  J22    136  VSS60  SCONN288_ADR50001P003C01  I176
  J22    139  VSS61  SCONN288_ADR50001P003C01  I176
  J22    141  VSS62  SCONN288_ADR50001P003C01  I176
  J22    143  VSS63  SCONN288_ADR50001P003C01  I176
  J22    151  VSS64  SCONN288_ADR50001P003C01  I176
  J22    153  VSS65  SCONN288_ADR50001P003C01  I176
  J22    155  VSS66  SCONN288_ADR50001P003C01  I176
  J22    158  VSS67  SCONN288_ADR50001P003C01  I176
  J22    160  VSS68  SCONN288_ADR50001P003C01  I176
  J22    162  VSS69  SCONN288_ADR50001P003C01  I176
  J22    164  VSS70  SCONN288_ADR50001P003C01  I176
  J22    166  VSS71  SCONN288_ADR50001P003C01  I176
  J22    169  VSS72  SCONN288_ADR50001P003C01  I176
  J22    171  VSS73  SCONN288_ADR50001P003C01  I176
  J22    173  VSS74  SCONN288_ADR50001P003C01  I176
  J22    175  VSS75  SCONN288_ADR50001P003C01  I176
  J22    177  VSS76  SCONN288_ADR50001P003C01  I176
  J22    180  VSS77  SCONN288_ADR50001P003C01  I176
  J22    182  VSS78  SCONN288_ADR50001P003C01  I176
  J22    184  VSS79  SCONN288_ADR50001P003C01  I176
  J22    186  VSS80  SCONN288_ADR50001P003C01  I176
  J22    188  VSS81  SCONN288_ADR50001P003C01  I176
  J22    191  VSS82  SCONN288_ADR50001P003C01  I176
  J22    193  VSS83  SCONN288_ADR50001P003C01  I176
  J22    195  VSS84  SCONN288_ADR50001P003C01  I176
  J22    197  VSS85  SCONN288_ADR50001P003C01  I176
  J22    199  VSS86  SCONN288_ADR50001P003C01  I176
  J22    202  VSS87  SCONN288_ADR50001P003C01  I176
  J22    204  VSS88  SCONN288_ADR50001P003C01  I176
  J22    206  VSS89  SCONN288_ADR50001P003C01  I176
  J22    208  VSS90  SCONN288_ADR50001P003C01  I176
  J22    210  VSS91  SCONN288_ADR50001P003C01  I176
  J22    212  VSS92  SCONN288_ADR50001P003C01  I176
  J22    214  VSS93  SCONN288_ADR50001P003C01  I176
  J22    216  VSS94  SCONN288_ADR50001P003C01  I176
  J22    219  VSS95  SCONN288_ADR50001P003C01  I176
  J22    222  VSS96  SCONN288_ADR50001P003C01  I176
  J22    224  VSS97  SCONN288_ADR50001P003C01  I176
  J22    226  VSS98  SCONN288_ADR50001P003C01  I176
  J22    228  VSS99  SCONN288_ADR50001P003C01  I176
  J22    230  VSS100  SCONN288_ADR50001P003C01  I176
  J22    233  VSS101  SCONN288_ADR50001P003C01  I176
  J22    235  VSS102  SCONN288_ADR50001P003C01  I176
  J22    237  VSS103  SCONN288_ADR50001P003C01  I176
  J22    240  VSS104  SCONN288_ADR50001P003C01  I176
  J22    242  VSS105  SCONN288_ADR50001P003C01  I176
  J22    244  VSS106  SCONN288_ADR50001P003C01  I176
  J22    246  VSS107  SCONN288_ADR50001P003C01  I176
  J22    248  VSS108  SCONN288_ADR50001P003C01  I176
  J22    251  VSS109  SCONN288_ADR50001P003C01  I176
  J22    253  VSS110  SCONN288_ADR50001P003C01  I176
  J22    255  VSS111  SCONN288_ADR50001P003C01  I176
  J22    257  VSS112  SCONN288_ADR50001P003C01  I176
  J22    259  VSS113  SCONN288_ADR50001P003C01  I176
  J22    262  VSS114  SCONN288_ADR50001P003C01  I176
  J22    264  VSS115  SCONN288_ADR50001P003C01  I176
  J22    266  VSS116  SCONN288_ADR50001P003C01  I176
  J22    268  VSS117  SCONN288_ADR50001P003C01  I176
  J22    270  VSS118  SCONN288_ADR50001P003C01  I176
  J22    273  VSS119  SCONN288_ADR50001P003C01  I176
  J22    275  VSS120  SCONN288_ADR50001P003C01  I176
  J22    277  VSS121  SCONN288_ADR50001P003C01  I176
  J22    279  VSS122  SCONN288_ADR50001P003C01  I176
  J22    281  VSS123  SCONN288_ADR50001P003C01  I176
  J22    284  VSS124  SCONN288_ADR50001P003C01  I176
  J22    286  VSS125  SCONN288_ADR50001P003C01  I176
  J22    288  VSS126  SCONN288_ADR50001P003C01  I176
  J22     G1     G1  SCONN288_ADR50001P003C01  I176
  J22     G2     G2  SCONN288_ADR50001P003C01  I176
  J22     G3     G3  SCONN288_ADR50001P003C01  I176
  J23      6   VSS0  SCONN288_ADR50001P013C01  I175
  J23      8   VSS1  SCONN288_ADR50001P013C01  I175
  J23     10   VSS2  SCONN288_ADR50001P013C01  I175
  J23     13   VSS3  SCONN288_ADR50001P013C01  I175
  J23     15   VSS4  SCONN288_ADR50001P013C01  I175
  J23     17   VSS5  SCONN288_ADR50001P013C01  I175
  J23     19   VSS6  SCONN288_ADR50001P013C01  I175
  J23     21   VSS7  SCONN288_ADR50001P013C01  I175
  J23     24   VSS8  SCONN288_ADR50001P013C01  I175
  J23     26   VSS9  SCONN288_ADR50001P013C01  I175
  J23     28  VSS10  SCONN288_ADR50001P013C01  I175
  J23     30  VSS11  SCONN288_ADR50001P013C01  I175
  J23     32  VSS12  SCONN288_ADR50001P013C01  I175
  J23     35  VSS13  SCONN288_ADR50001P013C01  I175
  J23     37  VSS14  SCONN288_ADR50001P013C01  I175
  J23     39  VSS15  SCONN288_ADR50001P013C01  I175
  J23     41  VSS16  SCONN288_ADR50001P013C01  I175
  J23     43  VSS17  SCONN288_ADR50001P013C01  I175
  J23     46  VSS18  SCONN288_ADR50001P013C01  I175
  J23     48  VSS19  SCONN288_ADR50001P013C01  I175
  J23     50  VSS20  SCONN288_ADR50001P013C01  I175
  J23     52  VSS21  SCONN288_ADR50001P013C01  I175
  J23     54  VSS22  SCONN288_ADR50001P013C01  I175
  J23     57  VSS23  SCONN288_ADR50001P013C01  I175
  J23     59  VSS24  SCONN288_ADR50001P013C01  I175
  J23     61  VSS25  SCONN288_ADR50001P013C01  I175
  J23     63  VSS26  SCONN288_ADR50001P013C01  I175
  J23     65  VSS27  SCONN288_ADR50001P013C01  I175
  J23     67  VSS28  SCONN288_ADR50001P013C01  I175
  J23     69  VSS29  SCONN288_ADR50001P013C01  I175
  J23     71  VSS30  SCONN288_ADR50001P013C01  I175
  J23     73  VSS31  SCONN288_ADR50001P013C01  I175
  J23     75  VSS32  SCONN288_ADR50001P013C01  I175
  J23     77  VSS33  SCONN288_ADR50001P013C01  I175
  J23     79  VSS34  SCONN288_ADR50001P013C01  I175
  J23     81  VSS35  SCONN288_ADR50001P013C01  I175
  J23     83  VSS36  SCONN288_ADR50001P013C01  I175
  J23     85  VSS37  SCONN288_ADR50001P013C01  I175
  J23     88  VSS38  SCONN288_ADR50001P013C01  I175
  J23     90  VSS39  SCONN288_ADR50001P013C01  I175
  J23     92  VSS40  SCONN288_ADR50001P013C01  I175
  J23     95  VSS41  SCONN288_ADR50001P013C01  I175
  J23     97  VSS42  SCONN288_ADR50001P013C01  I175
  J23     99  VSS43  SCONN288_ADR50001P013C01  I175
  J23    101  VSS44  SCONN288_ADR50001P013C01  I175
  J23    103  VSS45  SCONN288_ADR50001P013C01  I175
  J23    106  VSS46  SCONN288_ADR50001P013C01  I175
  J23    108  VSS47  SCONN288_ADR50001P013C01  I175
  J23    110  VSS48  SCONN288_ADR50001P013C01  I175
  J23    112  VSS49  SCONN288_ADR50001P013C01  I175
  J23    114  VSS50  SCONN288_ADR50001P013C01  I175
  J23    117  VSS51  SCONN288_ADR50001P013C01  I175
  J23    119  VSS52  SCONN288_ADR50001P013C01  I175
  J23    121  VSS53  SCONN288_ADR50001P013C01  I175
  J23    123  VSS54  SCONN288_ADR50001P013C01  I175
  J23    125  VSS55  SCONN288_ADR50001P013C01  I175
  J23    128  VSS56  SCONN288_ADR50001P013C01  I175
  J23    130  VSS57  SCONN288_ADR50001P013C01  I175
  J23    132  VSS58  SCONN288_ADR50001P013C01  I175
  J23    134  VSS59  SCONN288_ADR50001P013C01  I175
  J23    136  VSS60  SCONN288_ADR50001P013C01  I175
  J23    139  VSS61  SCONN288_ADR50001P013C01  I175
  J23    141  VSS62  SCONN288_ADR50001P013C01  I175
  J23    143  VSS63  SCONN288_ADR50001P013C01  I175
  J23    151  VSS64  SCONN288_ADR50001P013C01  I175
  J23    153  VSS65  SCONN288_ADR50001P013C01  I175
  J23    155  VSS66  SCONN288_ADR50001P013C01  I175
  J23    158  VSS67  SCONN288_ADR50001P013C01  I175
  J23    160  VSS68  SCONN288_ADR50001P013C01  I175
  J23    162  VSS69  SCONN288_ADR50001P013C01  I175
  J23    164  VSS70  SCONN288_ADR50001P013C01  I175
  J23    166  VSS71  SCONN288_ADR50001P013C01  I175
  J23    169  VSS72  SCONN288_ADR50001P013C01  I175
  J23    171  VSS73  SCONN288_ADR50001P013C01  I175
  J23    173  VSS74  SCONN288_ADR50001P013C01  I175
  J23    175  VSS75  SCONN288_ADR50001P013C01  I175
  J23    177  VSS76  SCONN288_ADR50001P013C01  I175
  J23    180  VSS77  SCONN288_ADR50001P013C01  I175
  J23    182  VSS78  SCONN288_ADR50001P013C01  I175
  J23    184  VSS79  SCONN288_ADR50001P013C01  I175
  J23    186  VSS80  SCONN288_ADR50001P013C01  I175
  J23    188  VSS81  SCONN288_ADR50001P013C01  I175
  J23    191  VSS82  SCONN288_ADR50001P013C01  I175
  J23    193  VSS83  SCONN288_ADR50001P013C01  I175
  J23    195  VSS84  SCONN288_ADR50001P013C01  I175
  J23    197  VSS85  SCONN288_ADR50001P013C01  I175
  J23    199  VSS86  SCONN288_ADR50001P013C01  I175
  J23    202  VSS87  SCONN288_ADR50001P013C01  I175
  J23    204  VSS88  SCONN288_ADR50001P013C01  I175
  J23    206  VSS89  SCONN288_ADR50001P013C01  I175
  J23    208  VSS90  SCONN288_ADR50001P013C01  I175
  J23    210  VSS91  SCONN288_ADR50001P013C01  I175
  J23    212  VSS92  SCONN288_ADR50001P013C01  I175
  J23    214  VSS93  SCONN288_ADR50001P013C01  I175
  J23    216  VSS94  SCONN288_ADR50001P013C01  I175
  J23    219  VSS95  SCONN288_ADR50001P013C01  I175
  J23    222  VSS96  SCONN288_ADR50001P013C01  I175
  J23    224  VSS97  SCONN288_ADR50001P013C01  I175
  J23    226  VSS98  SCONN288_ADR50001P013C01  I175
  J23    228  VSS99  SCONN288_ADR50001P013C01  I175
  J23    230  VSS100  SCONN288_ADR50001P013C01  I175
  J23    233  VSS101  SCONN288_ADR50001P013C01  I175
  J23    235  VSS102  SCONN288_ADR50001P013C01  I175
  J23    237  VSS103  SCONN288_ADR50001P013C01  I175
  J23    240  VSS104  SCONN288_ADR50001P013C01  I175
  J23    242  VSS105  SCONN288_ADR50001P013C01  I175
  J23    244  VSS106  SCONN288_ADR50001P013C01  I175
  J23    246  VSS107  SCONN288_ADR50001P013C01  I175
  J23    248  VSS108  SCONN288_ADR50001P013C01  I175
  J23    251  VSS109  SCONN288_ADR50001P013C01  I175
  J23    253  VSS110  SCONN288_ADR50001P013C01  I175
  J23    255  VSS111  SCONN288_ADR50001P013C01  I175
  J23    257  VSS112  SCONN288_ADR50001P013C01  I175
  J23    259  VSS113  SCONN288_ADR50001P013C01  I175
  J23    262  VSS114  SCONN288_ADR50001P013C01  I175
  J23    264  VSS115  SCONN288_ADR50001P013C01  I175
  J23    266  VSS116  SCONN288_ADR50001P013C01  I175
  J23    268  VSS117  SCONN288_ADR50001P013C01  I175
  J23    270  VSS118  SCONN288_ADR50001P013C01  I175
  J23    273  VSS119  SCONN288_ADR50001P013C01  I175
  J23    275  VSS120  SCONN288_ADR50001P013C01  I175
  J23    277  VSS121  SCONN288_ADR50001P013C01  I175
  J23    279  VSS122  SCONN288_ADR50001P013C01  I175
  J23    281  VSS123  SCONN288_ADR50001P013C01  I175
  J23    284  VSS124  SCONN288_ADR50001P013C01  I175
  J23    286  VSS125  SCONN288_ADR50001P013C01  I175
  J23    288  VSS126  SCONN288_ADR50001P013C01  I175
  J23     G1     G1  SCONN288_ADR50001P013C01  I175
  J23     G2     G2  SCONN288_ADR50001P013C01  I175
  J23     G3     G3  SCONN288_ADR50001P013C01  I175
  J24      6   VSS0  SCONN288_ADR50001P003C01  I180
  J24      8   VSS1  SCONN288_ADR50001P003C01  I180
  J24     10   VSS2  SCONN288_ADR50001P003C01  I180
  J24     13   VSS3  SCONN288_ADR50001P003C01  I180
  J24     15   VSS4  SCONN288_ADR50001P003C01  I180
  J24     17   VSS5  SCONN288_ADR50001P003C01  I180
  J24     19   VSS6  SCONN288_ADR50001P003C01  I180
  J24     21   VSS7  SCONN288_ADR50001P003C01  I180
  J24     24   VSS8  SCONN288_ADR50001P003C01  I180
  J24     26   VSS9  SCONN288_ADR50001P003C01  I180
  J24     28  VSS10  SCONN288_ADR50001P003C01  I180
  J24     30  VSS11  SCONN288_ADR50001P003C01  I180
  J24     32  VSS12  SCONN288_ADR50001P003C01  I180
  J24     35  VSS13  SCONN288_ADR50001P003C01  I180
  J24     37  VSS14  SCONN288_ADR50001P003C01  I180
  J24     39  VSS15  SCONN288_ADR50001P003C01  I180
  J24     41  VSS16  SCONN288_ADR50001P003C01  I180
  J24     43  VSS17  SCONN288_ADR50001P003C01  I180
  J24     46  VSS18  SCONN288_ADR50001P003C01  I180
  J24     48  VSS19  SCONN288_ADR50001P003C01  I180
  J24     50  VSS20  SCONN288_ADR50001P003C01  I180
  J24     52  VSS21  SCONN288_ADR50001P003C01  I180
  J24     54  VSS22  SCONN288_ADR50001P003C01  I180
  J24     57  VSS23  SCONN288_ADR50001P003C01  I180
  J24     59  VSS24  SCONN288_ADR50001P003C01  I180
  J24     61  VSS25  SCONN288_ADR50001P003C01  I180
  J24     63  VSS26  SCONN288_ADR50001P003C01  I180
  J24     65  VSS27  SCONN288_ADR50001P003C01  I180
  J24     67  VSS28  SCONN288_ADR50001P003C01  I180
  J24     69  VSS29  SCONN288_ADR50001P003C01  I180
  J24     71  VSS30  SCONN288_ADR50001P003C01  I180
  J24     73  VSS31  SCONN288_ADR50001P003C01  I180
  J24     75  VSS32  SCONN288_ADR50001P003C01  I180
  J24     77  VSS33  SCONN288_ADR50001P003C01  I180
  J24     79  VSS34  SCONN288_ADR50001P003C01  I180
  J24     81  VSS35  SCONN288_ADR50001P003C01  I180
  J24     83  VSS36  SCONN288_ADR50001P003C01  I180
  J24     85  VSS37  SCONN288_ADR50001P003C01  I180
  J24     88  VSS38  SCONN288_ADR50001P003C01  I180
  J24     90  VSS39  SCONN288_ADR50001P003C01  I180
  J24     92  VSS40  SCONN288_ADR50001P003C01  I180
  J24     95  VSS41  SCONN288_ADR50001P003C01  I180
  J24     97  VSS42  SCONN288_ADR50001P003C01  I180
  J24     99  VSS43  SCONN288_ADR50001P003C01  I180
  J24    101  VSS44  SCONN288_ADR50001P003C01  I180
  J24    103  VSS45  SCONN288_ADR50001P003C01  I180
  J24    106  VSS46  SCONN288_ADR50001P003C01  I180
  J24    108  VSS47  SCONN288_ADR50001P003C01  I180
  J24    110  VSS48  SCONN288_ADR50001P003C01  I180
  J24    112  VSS49  SCONN288_ADR50001P003C01  I180
  J24    114  VSS50  SCONN288_ADR50001P003C01  I180
  J24    117  VSS51  SCONN288_ADR50001P003C01  I180
  J24    119  VSS52  SCONN288_ADR50001P003C01  I180
  J24    121  VSS53  SCONN288_ADR50001P003C01  I180
  J24    123  VSS54  SCONN288_ADR50001P003C01  I180
  J24    125  VSS55  SCONN288_ADR50001P003C01  I180
  J24    128  VSS56  SCONN288_ADR50001P003C01  I180
  J24    130  VSS57  SCONN288_ADR50001P003C01  I180
  J24    132  VSS58  SCONN288_ADR50001P003C01  I180
  J24    134  VSS59  SCONN288_ADR50001P003C01  I180
  J24    136  VSS60  SCONN288_ADR50001P003C01  I180
  J24    139  VSS61  SCONN288_ADR50001P003C01  I180
  J24    141  VSS62  SCONN288_ADR50001P003C01  I180
  J24    143  VSS63  SCONN288_ADR50001P003C01  I180
  J24    151  VSS64  SCONN288_ADR50001P003C01  I180
  J24    153  VSS65  SCONN288_ADR50001P003C01  I180
  J24    155  VSS66  SCONN288_ADR50001P003C01  I180
  J24    158  VSS67  SCONN288_ADR50001P003C01  I180
  J24    160  VSS68  SCONN288_ADR50001P003C01  I180
  J24    162  VSS69  SCONN288_ADR50001P003C01  I180
  J24    164  VSS70  SCONN288_ADR50001P003C01  I180
  J24    166  VSS71  SCONN288_ADR50001P003C01  I180
  J24    169  VSS72  SCONN288_ADR50001P003C01  I180
  J24    171  VSS73  SCONN288_ADR50001P003C01  I180
  J24    173  VSS74  SCONN288_ADR50001P003C01  I180
  J24    175  VSS75  SCONN288_ADR50001P003C01  I180
  J24    177  VSS76  SCONN288_ADR50001P003C01  I180
  J24    180  VSS77  SCONN288_ADR50001P003C01  I180
  J24    182  VSS78  SCONN288_ADR50001P003C01  I180
  J24    184  VSS79  SCONN288_ADR50001P003C01  I180
  J24    186  VSS80  SCONN288_ADR50001P003C01  I180
  J24    188  VSS81  SCONN288_ADR50001P003C01  I180
  J24    191  VSS82  SCONN288_ADR50001P003C01  I180
  J24    193  VSS83  SCONN288_ADR50001P003C01  I180
  J24    195  VSS84  SCONN288_ADR50001P003C01  I180
  J24    197  VSS85  SCONN288_ADR50001P003C01  I180
  J24    199  VSS86  SCONN288_ADR50001P003C01  I180
  J24    202  VSS87  SCONN288_ADR50001P003C01  I180
  J24    204  VSS88  SCONN288_ADR50001P003C01  I180
  J24    206  VSS89  SCONN288_ADR50001P003C01  I180
  J24    208  VSS90  SCONN288_ADR50001P003C01  I180
  J24    210  VSS91  SCONN288_ADR50001P003C01  I180
  J24    212  VSS92  SCONN288_ADR50001P003C01  I180
  J24    214  VSS93  SCONN288_ADR50001P003C01  I180
  J24    216  VSS94  SCONN288_ADR50001P003C01  I180
  J24    219  VSS95  SCONN288_ADR50001P003C01  I180
  J24    222  VSS96  SCONN288_ADR50001P003C01  I180
  J24    224  VSS97  SCONN288_ADR50001P003C01  I180
  J24    226  VSS98  SCONN288_ADR50001P003C01  I180
  J24    228  VSS99  SCONN288_ADR50001P003C01  I180
  J24    230  VSS100  SCONN288_ADR50001P003C01  I180
  J24    233  VSS101  SCONN288_ADR50001P003C01  I180
  J24    235  VSS102  SCONN288_ADR50001P003C01  I180
  J24    237  VSS103  SCONN288_ADR50001P003C01  I180
  J24    240  VSS104  SCONN288_ADR50001P003C01  I180
  J24    242  VSS105  SCONN288_ADR50001P003C01  I180
  J24    244  VSS106  SCONN288_ADR50001P003C01  I180
  J24    246  VSS107  SCONN288_ADR50001P003C01  I180
  J24    248  VSS108  SCONN288_ADR50001P003C01  I180
  J24    251  VSS109  SCONN288_ADR50001P003C01  I180
  J24    253  VSS110  SCONN288_ADR50001P003C01  I180
  J24    255  VSS111  SCONN288_ADR50001P003C01  I180
  J24    257  VSS112  SCONN288_ADR50001P003C01  I180
  J24    259  VSS113  SCONN288_ADR50001P003C01  I180
  J24    262  VSS114  SCONN288_ADR50001P003C01  I180
  J24    264  VSS115  SCONN288_ADR50001P003C01  I180
  J24    266  VSS116  SCONN288_ADR50001P003C01  I180
  J24    268  VSS117  SCONN288_ADR50001P003C01  I180
  J24    270  VSS118  SCONN288_ADR50001P003C01  I180
  J24    273  VSS119  SCONN288_ADR50001P003C01  I180
  J24    275  VSS120  SCONN288_ADR50001P003C01  I180
  J24    277  VSS121  SCONN288_ADR50001P003C01  I180
  J24    279  VSS122  SCONN288_ADR50001P003C01  I180
  J24    281  VSS123  SCONN288_ADR50001P003C01  I180
  J24    284  VSS124  SCONN288_ADR50001P003C01  I180
  J24    286  VSS125  SCONN288_ADR50001P003C01  I180
  J24    288  VSS126  SCONN288_ADR50001P003C01  I180
  J24     G1     G1  SCONN288_ADR50001P003C01  I180
  J24     G2     G2  SCONN288_ADR50001P003C01  I180
  J24     G3     G3  SCONN288_ADR50001P003C01  I180
  J25      6   VSS0  SCONN288_ADR50001P013C01  I178
  J25      8   VSS1  SCONN288_ADR50001P013C01  I178
  J25     10   VSS2  SCONN288_ADR50001P013C01  I178
  J25     13   VSS3  SCONN288_ADR50001P013C01  I178
  J25     15   VSS4  SCONN288_ADR50001P013C01  I178
  J25     17   VSS5  SCONN288_ADR50001P013C01  I178
  J25     19   VSS6  SCONN288_ADR50001P013C01  I178
  J25     21   VSS7  SCONN288_ADR50001P013C01  I178
  J25     24   VSS8  SCONN288_ADR50001P013C01  I178
  J25     26   VSS9  SCONN288_ADR50001P013C01  I178
  J25     28  VSS10  SCONN288_ADR50001P013C01  I178
  J25     30  VSS11  SCONN288_ADR50001P013C01  I178
  J25     32  VSS12  SCONN288_ADR50001P013C01  I178
  J25     35  VSS13  SCONN288_ADR50001P013C01  I178
  J25     37  VSS14  SCONN288_ADR50001P013C01  I178
  J25     39  VSS15  SCONN288_ADR50001P013C01  I178
  J25     41  VSS16  SCONN288_ADR50001P013C01  I178
  J25     43  VSS17  SCONN288_ADR50001P013C01  I178
  J25     46  VSS18  SCONN288_ADR50001P013C01  I178
  J25     48  VSS19  SCONN288_ADR50001P013C01  I178
  J25     50  VSS20  SCONN288_ADR50001P013C01  I178
  J25     52  VSS21  SCONN288_ADR50001P013C01  I178
  J25     54  VSS22  SCONN288_ADR50001P013C01  I178
  J25     57  VSS23  SCONN288_ADR50001P013C01  I178
  J25     59  VSS24  SCONN288_ADR50001P013C01  I178
  J25     61  VSS25  SCONN288_ADR50001P013C01  I178
  J25     63  VSS26  SCONN288_ADR50001P013C01  I178
  J25     65  VSS27  SCONN288_ADR50001P013C01  I178
  J25     67  VSS28  SCONN288_ADR50001P013C01  I178
  J25     69  VSS29  SCONN288_ADR50001P013C01  I178
  J25     71  VSS30  SCONN288_ADR50001P013C01  I178
  J25     73  VSS31  SCONN288_ADR50001P013C01  I178
  J25     75  VSS32  SCONN288_ADR50001P013C01  I178
  J25     77  VSS33  SCONN288_ADR50001P013C01  I178
  J25     79  VSS34  SCONN288_ADR50001P013C01  I178
  J25     81  VSS35  SCONN288_ADR50001P013C01  I178
  J25     83  VSS36  SCONN288_ADR50001P013C01  I178
  J25     85  VSS37  SCONN288_ADR50001P013C01  I178
  J25     88  VSS38  SCONN288_ADR50001P013C01  I178
  J25     90  VSS39  SCONN288_ADR50001P013C01  I178
  J25     92  VSS40  SCONN288_ADR50001P013C01  I178
  J25     95  VSS41  SCONN288_ADR50001P013C01  I178
  J25     97  VSS42  SCONN288_ADR50001P013C01  I178
  J25     99  VSS43  SCONN288_ADR50001P013C01  I178
  J25    101  VSS44  SCONN288_ADR50001P013C01  I178
  J25    103  VSS45  SCONN288_ADR50001P013C01  I178
  J25    106  VSS46  SCONN288_ADR50001P013C01  I178
  J25    108  VSS47  SCONN288_ADR50001P013C01  I178
  J25    110  VSS48  SCONN288_ADR50001P013C01  I178
  J25    112  VSS49  SCONN288_ADR50001P013C01  I178
  J25    114  VSS50  SCONN288_ADR50001P013C01  I178
  J25    117  VSS51  SCONN288_ADR50001P013C01  I178
  J25    119  VSS52  SCONN288_ADR50001P013C01  I178
  J25    121  VSS53  SCONN288_ADR50001P013C01  I178
  J25    123  VSS54  SCONN288_ADR50001P013C01  I178
  J25    125  VSS55  SCONN288_ADR50001P013C01  I178
  J25    128  VSS56  SCONN288_ADR50001P013C01  I178
  J25    130  VSS57  SCONN288_ADR50001P013C01  I178
  J25    132  VSS58  SCONN288_ADR50001P013C01  I178
  J25    134  VSS59  SCONN288_ADR50001P013C01  I178
  J25    136  VSS60  SCONN288_ADR50001P013C01  I178
  J25    139  VSS61  SCONN288_ADR50001P013C01  I178
  J25    141  VSS62  SCONN288_ADR50001P013C01  I178
  J25    143  VSS63  SCONN288_ADR50001P013C01  I178
  J25    151  VSS64  SCONN288_ADR50001P013C01  I178
  J25    153  VSS65  SCONN288_ADR50001P013C01  I178
  J25    155  VSS66  SCONN288_ADR50001P013C01  I178
  J25    158  VSS67  SCONN288_ADR50001P013C01  I178
  J25    160  VSS68  SCONN288_ADR50001P013C01  I178
  J25    162  VSS69  SCONN288_ADR50001P013C01  I178
  J25    164  VSS70  SCONN288_ADR50001P013C01  I178
  J25    166  VSS71  SCONN288_ADR50001P013C01  I178
  J25    169  VSS72  SCONN288_ADR50001P013C01  I178
  J25    171  VSS73  SCONN288_ADR50001P013C01  I178
  J25    173  VSS74  SCONN288_ADR50001P013C01  I178
  J25    175  VSS75  SCONN288_ADR50001P013C01  I178
  J25    177  VSS76  SCONN288_ADR50001P013C01  I178
  J25    180  VSS77  SCONN288_ADR50001P013C01  I178
  J25    182  VSS78  SCONN288_ADR50001P013C01  I178
  J25    184  VSS79  SCONN288_ADR50001P013C01  I178
  J25    186  VSS80  SCONN288_ADR50001P013C01  I178
  J25    188  VSS81  SCONN288_ADR50001P013C01  I178
  J25    191  VSS82  SCONN288_ADR50001P013C01  I178
  J25    193  VSS83  SCONN288_ADR50001P013C01  I178
  J25    195  VSS84  SCONN288_ADR50001P013C01  I178
  J25    197  VSS85  SCONN288_ADR50001P013C01  I178
  J25    199  VSS86  SCONN288_ADR50001P013C01  I178
  J25    202  VSS87  SCONN288_ADR50001P013C01  I178
  J25    204  VSS88  SCONN288_ADR50001P013C01  I178
  J25    206  VSS89  SCONN288_ADR50001P013C01  I178
  J25    208  VSS90  SCONN288_ADR50001P013C01  I178
  J25    210  VSS91  SCONN288_ADR50001P013C01  I178
  J25    212  VSS92  SCONN288_ADR50001P013C01  I178
  J25    214  VSS93  SCONN288_ADR50001P013C01  I178
  J25    216  VSS94  SCONN288_ADR50001P013C01  I178
  J25    219  VSS95  SCONN288_ADR50001P013C01  I178
  J25    222  VSS96  SCONN288_ADR50001P013C01  I178
  J25    224  VSS97  SCONN288_ADR50001P013C01  I178
  J25    226  VSS98  SCONN288_ADR50001P013C01  I178
  J25    228  VSS99  SCONN288_ADR50001P013C01  I178
  J25    230  VSS100  SCONN288_ADR50001P013C01  I178
  J25    233  VSS101  SCONN288_ADR50001P013C01  I178
  J25    235  VSS102  SCONN288_ADR50001P013C01  I178
  J25    237  VSS103  SCONN288_ADR50001P013C01  I178
  J25    240  VSS104  SCONN288_ADR50001P013C01  I178
  J25    242  VSS105  SCONN288_ADR50001P013C01  I178
  J25    244  VSS106  SCONN288_ADR50001P013C01  I178
  J25    246  VSS107  SCONN288_ADR50001P013C01  I178
  J25    248  VSS108  SCONN288_ADR50001P013C01  I178
  J25    251  VSS109  SCONN288_ADR50001P013C01  I178
  J25    253  VSS110  SCONN288_ADR50001P013C01  I178
  J25    255  VSS111  SCONN288_ADR50001P013C01  I178
  J25    257  VSS112  SCONN288_ADR50001P013C01  I178
  J25    259  VSS113  SCONN288_ADR50001P013C01  I178
  J25    262  VSS114  SCONN288_ADR50001P013C01  I178
  J25    264  VSS115  SCONN288_ADR50001P013C01  I178
  J25    266  VSS116  SCONN288_ADR50001P013C01  I178
  J25    268  VSS117  SCONN288_ADR50001P013C01  I178
  J25    270  VSS118  SCONN288_ADR50001P013C01  I178
  J25    273  VSS119  SCONN288_ADR50001P013C01  I178
  J25    275  VSS120  SCONN288_ADR50001P013C01  I178
  J25    277  VSS121  SCONN288_ADR50001P013C01  I178
  J25    279  VSS122  SCONN288_ADR50001P013C01  I178
  J25    281  VSS123  SCONN288_ADR50001P013C01  I178
  J25    284  VSS124  SCONN288_ADR50001P013C01  I178
  J25    286  VSS125  SCONN288_ADR50001P013C01  I178
  J25    288  VSS126  SCONN288_ADR50001P013C01  I178
  J25     G1     G1  SCONN288_ADR50001P013C01  I178
  J25     G2     G2  SCONN288_ADR50001P013C01  I178
  J25     G3     G3  SCONN288_ADR50001P013C01  I178
  J26      6   VSS0  SCONN288_ADR50001P003C01  I179
  J26      8   VSS1  SCONN288_ADR50001P003C01  I179
  J26     10   VSS2  SCONN288_ADR50001P003C01  I179
  J26     13   VSS3  SCONN288_ADR50001P003C01  I179
  J26     15   VSS4  SCONN288_ADR50001P003C01  I179
  J26     17   VSS5  SCONN288_ADR50001P003C01  I179
  J26     19   VSS6  SCONN288_ADR50001P003C01  I179
  J26     21   VSS7  SCONN288_ADR50001P003C01  I179
  J26     24   VSS8  SCONN288_ADR50001P003C01  I179
  J26     26   VSS9  SCONN288_ADR50001P003C01  I179
  J26     28  VSS10  SCONN288_ADR50001P003C01  I179
  J26     30  VSS11  SCONN288_ADR50001P003C01  I179
  J26     32  VSS12  SCONN288_ADR50001P003C01  I179
  J26     35  VSS13  SCONN288_ADR50001P003C01  I179
  J26     37  VSS14  SCONN288_ADR50001P003C01  I179
  J26     39  VSS15  SCONN288_ADR50001P003C01  I179
  J26     41  VSS16  SCONN288_ADR50001P003C01  I179
  J26     43  VSS17  SCONN288_ADR50001P003C01  I179
  J26     46  VSS18  SCONN288_ADR50001P003C01  I179
  J26     48  VSS19  SCONN288_ADR50001P003C01  I179
  J26     50  VSS20  SCONN288_ADR50001P003C01  I179
  J26     52  VSS21  SCONN288_ADR50001P003C01  I179
  J26     54  VSS22  SCONN288_ADR50001P003C01  I179
  J26     57  VSS23  SCONN288_ADR50001P003C01  I179
  J26     59  VSS24  SCONN288_ADR50001P003C01  I179
  J26     61  VSS25  SCONN288_ADR50001P003C01  I179
  J26     63  VSS26  SCONN288_ADR50001P003C01  I179
  J26     65  VSS27  SCONN288_ADR50001P003C01  I179
  J26     67  VSS28  SCONN288_ADR50001P003C01  I179
  J26     69  VSS29  SCONN288_ADR50001P003C01  I179
  J26     71  VSS30  SCONN288_ADR50001P003C01  I179
  J26     73  VSS31  SCONN288_ADR50001P003C01  I179
  J26     75  VSS32  SCONN288_ADR50001P003C01  I179
  J26     77  VSS33  SCONN288_ADR50001P003C01  I179
  J26     79  VSS34  SCONN288_ADR50001P003C01  I179
  J26     81  VSS35  SCONN288_ADR50001P003C01  I179
  J26     83  VSS36  SCONN288_ADR50001P003C01  I179
  J26     85  VSS37  SCONN288_ADR50001P003C01  I179
  J26     88  VSS38  SCONN288_ADR50001P003C01  I179
  J26     90  VSS39  SCONN288_ADR50001P003C01  I179
  J26     92  VSS40  SCONN288_ADR50001P003C01  I179
  J26     95  VSS41  SCONN288_ADR50001P003C01  I179
  J26     97  VSS42  SCONN288_ADR50001P003C01  I179
  J26     99  VSS43  SCONN288_ADR50001P003C01  I179
  J26    101  VSS44  SCONN288_ADR50001P003C01  I179
  J26    103  VSS45  SCONN288_ADR50001P003C01  I179
  J26    106  VSS46  SCONN288_ADR50001P003C01  I179
  J26    108  VSS47  SCONN288_ADR50001P003C01  I179
  J26    110  VSS48  SCONN288_ADR50001P003C01  I179
  J26    112  VSS49  SCONN288_ADR50001P003C01  I179
  J26    114  VSS50  SCONN288_ADR50001P003C01  I179
  J26    117  VSS51  SCONN288_ADR50001P003C01  I179
  J26    119  VSS52  SCONN288_ADR50001P003C01  I179
  J26    121  VSS53  SCONN288_ADR50001P003C01  I179
  J26    123  VSS54  SCONN288_ADR50001P003C01  I179
  J26    125  VSS55  SCONN288_ADR50001P003C01  I179
  J26    128  VSS56  SCONN288_ADR50001P003C01  I179
  J26    130  VSS57  SCONN288_ADR50001P003C01  I179
  J26    132  VSS58  SCONN288_ADR50001P003C01  I179
  J26    134  VSS59  SCONN288_ADR50001P003C01  I179
  J26    136  VSS60  SCONN288_ADR50001P003C01  I179
  J26    139  VSS61  SCONN288_ADR50001P003C01  I179
  J26    141  VSS62  SCONN288_ADR50001P003C01  I179
  J26    143  VSS63  SCONN288_ADR50001P003C01  I179
  J26    151  VSS64  SCONN288_ADR50001P003C01  I179
  J26    153  VSS65  SCONN288_ADR50001P003C01  I179
  J26    155  VSS66  SCONN288_ADR50001P003C01  I179
  J26    158  VSS67  SCONN288_ADR50001P003C01  I179
  J26    160  VSS68  SCONN288_ADR50001P003C01  I179
  J26    162  VSS69  SCONN288_ADR50001P003C01  I179
  J26    164  VSS70  SCONN288_ADR50001P003C01  I179
  J26    166  VSS71  SCONN288_ADR50001P003C01  I179
  J26    169  VSS72  SCONN288_ADR50001P003C01  I179
  J26    171  VSS73  SCONN288_ADR50001P003C01  I179
  J26    173  VSS74  SCONN288_ADR50001P003C01  I179
  J26    175  VSS75  SCONN288_ADR50001P003C01  I179
  J26    177  VSS76  SCONN288_ADR50001P003C01  I179
  J26    180  VSS77  SCONN288_ADR50001P003C01  I179
  J26    182  VSS78  SCONN288_ADR50001P003C01  I179
  J26    184  VSS79  SCONN288_ADR50001P003C01  I179
  J26    186  VSS80  SCONN288_ADR50001P003C01  I179
  J26    188  VSS81  SCONN288_ADR50001P003C01  I179
  J26    191  VSS82  SCONN288_ADR50001P003C01  I179
  J26    193  VSS83  SCONN288_ADR50001P003C01  I179
  J26    195  VSS84  SCONN288_ADR50001P003C01  I179
  J26    197  VSS85  SCONN288_ADR50001P003C01  I179
  J26    199  VSS86  SCONN288_ADR50001P003C01  I179
  J26    202  VSS87  SCONN288_ADR50001P003C01  I179
  J26    204  VSS88  SCONN288_ADR50001P003C01  I179
  J26    206  VSS89  SCONN288_ADR50001P003C01  I179
  J26    208  VSS90  SCONN288_ADR50001P003C01  I179
  J26    210  VSS91  SCONN288_ADR50001P003C01  I179
  J26    212  VSS92  SCONN288_ADR50001P003C01  I179
  J26    214  VSS93  SCONN288_ADR50001P003C01  I179
  J26    216  VSS94  SCONN288_ADR50001P003C01  I179
  J26    219  VSS95  SCONN288_ADR50001P003C01  I179
  J26    222  VSS96  SCONN288_ADR50001P003C01  I179
  J26    224  VSS97  SCONN288_ADR50001P003C01  I179
  J26    226  VSS98  SCONN288_ADR50001P003C01  I179
  J26    228  VSS99  SCONN288_ADR50001P003C01  I179
  J26    230  VSS100  SCONN288_ADR50001P003C01  I179
  J26    233  VSS101  SCONN288_ADR50001P003C01  I179
  J26    235  VSS102  SCONN288_ADR50001P003C01  I179
  J26    237  VSS103  SCONN288_ADR50001P003C01  I179
  J26    240  VSS104  SCONN288_ADR50001P003C01  I179
  J26    242  VSS105  SCONN288_ADR50001P003C01  I179
  J26    244  VSS106  SCONN288_ADR50001P003C01  I179
  J26    246  VSS107  SCONN288_ADR50001P003C01  I179
  J26    248  VSS108  SCONN288_ADR50001P003C01  I179
  J26    251  VSS109  SCONN288_ADR50001P003C01  I179
  J26    253  VSS110  SCONN288_ADR50001P003C01  I179
  J26    255  VSS111  SCONN288_ADR50001P003C01  I179
  J26    257  VSS112  SCONN288_ADR50001P003C01  I179
  J26    259  VSS113  SCONN288_ADR50001P003C01  I179
  J26    262  VSS114  SCONN288_ADR50001P003C01  I179
  J26    264  VSS115  SCONN288_ADR50001P003C01  I179
  J26    266  VSS116  SCONN288_ADR50001P003C01  I179
  J26    268  VSS117  SCONN288_ADR50001P003C01  I179
  J26    270  VSS118  SCONN288_ADR50001P003C01  I179
  J26    273  VSS119  SCONN288_ADR50001P003C01  I179
  J26    275  VSS120  SCONN288_ADR50001P003C01  I179
  J26    277  VSS121  SCONN288_ADR50001P003C01  I179
  J26    279  VSS122  SCONN288_ADR50001P003C01  I179
  J26    281  VSS123  SCONN288_ADR50001P003C01  I179
  J26    284  VSS124  SCONN288_ADR50001P003C01  I179
  J26    286  VSS125  SCONN288_ADR50001P003C01  I179
  J26    288  VSS126  SCONN288_ADR50001P003C01  I179
  J26     G1     G1  SCONN288_ADR50001P003C01  I179
  J26     G2     G2  SCONN288_ADR50001P003C01  I179
  J26     G3     G3  SCONN288_ADR50001P003C01  I179
  J27      6   VSS0  SCONN288_ADR50001P013C01  I178
  J27      8   VSS1  SCONN288_ADR50001P013C01  I178
  J27     10   VSS2  SCONN288_ADR50001P013C01  I178
  J27     13   VSS3  SCONN288_ADR50001P013C01  I178
  J27     15   VSS4  SCONN288_ADR50001P013C01  I178
  J27     17   VSS5  SCONN288_ADR50001P013C01  I178
  J27     19   VSS6  SCONN288_ADR50001P013C01  I178
  J27     21   VSS7  SCONN288_ADR50001P013C01  I178
  J27     24   VSS8  SCONN288_ADR50001P013C01  I178
  J27     26   VSS9  SCONN288_ADR50001P013C01  I178
  J27     28  VSS10  SCONN288_ADR50001P013C01  I178
  J27     30  VSS11  SCONN288_ADR50001P013C01  I178
  J27     32  VSS12  SCONN288_ADR50001P013C01  I178
  J27     35  VSS13  SCONN288_ADR50001P013C01  I178
  J27     37  VSS14  SCONN288_ADR50001P013C01  I178
  J27     39  VSS15  SCONN288_ADR50001P013C01  I178
  J27     41  VSS16  SCONN288_ADR50001P013C01  I178
  J27     43  VSS17  SCONN288_ADR50001P013C01  I178
  J27     46  VSS18  SCONN288_ADR50001P013C01  I178
  J27     48  VSS19  SCONN288_ADR50001P013C01  I178
  J27     50  VSS20  SCONN288_ADR50001P013C01  I178
  J27     52  VSS21  SCONN288_ADR50001P013C01  I178
  J27     54  VSS22  SCONN288_ADR50001P013C01  I178
  J27     57  VSS23  SCONN288_ADR50001P013C01  I178
  J27     59  VSS24  SCONN288_ADR50001P013C01  I178
  J27     61  VSS25  SCONN288_ADR50001P013C01  I178
  J27     63  VSS26  SCONN288_ADR50001P013C01  I178
  J27     65  VSS27  SCONN288_ADR50001P013C01  I178
  J27     67  VSS28  SCONN288_ADR50001P013C01  I178
  J27     69  VSS29  SCONN288_ADR50001P013C01  I178
  J27     71  VSS30  SCONN288_ADR50001P013C01  I178
  J27     73  VSS31  SCONN288_ADR50001P013C01  I178
  J27     75  VSS32  SCONN288_ADR50001P013C01  I178
  J27     77  VSS33  SCONN288_ADR50001P013C01  I178
  J27     79  VSS34  SCONN288_ADR50001P013C01  I178
  J27     81  VSS35  SCONN288_ADR50001P013C01  I178
  J27     83  VSS36  SCONN288_ADR50001P013C01  I178
  J27     85  VSS37  SCONN288_ADR50001P013C01  I178
  J27     88  VSS38  SCONN288_ADR50001P013C01  I178
  J27     90  VSS39  SCONN288_ADR50001P013C01  I178
  J27     92  VSS40  SCONN288_ADR50001P013C01  I178
  J27     95  VSS41  SCONN288_ADR50001P013C01  I178
  J27     97  VSS42  SCONN288_ADR50001P013C01  I178
  J27     99  VSS43  SCONN288_ADR50001P013C01  I178
  J27    101  VSS44  SCONN288_ADR50001P013C01  I178
  J27    103  VSS45  SCONN288_ADR50001P013C01  I178
  J27    106  VSS46  SCONN288_ADR50001P013C01  I178
  J27    108  VSS47  SCONN288_ADR50001P013C01  I178
  J27    110  VSS48  SCONN288_ADR50001P013C01  I178
  J27    112  VSS49  SCONN288_ADR50001P013C01  I178
  J27    114  VSS50  SCONN288_ADR50001P013C01  I178
  J27    117  VSS51  SCONN288_ADR50001P013C01  I178
  J27    119  VSS52  SCONN288_ADR50001P013C01  I178
  J27    121  VSS53  SCONN288_ADR50001P013C01  I178
  J27    123  VSS54  SCONN288_ADR50001P013C01  I178
  J27    125  VSS55  SCONN288_ADR50001P013C01  I178
  J27    128  VSS56  SCONN288_ADR50001P013C01  I178
  J27    130  VSS57  SCONN288_ADR50001P013C01  I178
  J27    132  VSS58  SCONN288_ADR50001P013C01  I178
  J27    134  VSS59  SCONN288_ADR50001P013C01  I178
  J27    136  VSS60  SCONN288_ADR50001P013C01  I178
  J27    139  VSS61  SCONN288_ADR50001P013C01  I178
  J27    141  VSS62  SCONN288_ADR50001P013C01  I178
  J27    143  VSS63  SCONN288_ADR50001P013C01  I178
  J27    151  VSS64  SCONN288_ADR50001P013C01  I178
  J27    153  VSS65  SCONN288_ADR50001P013C01  I178
  J27    155  VSS66  SCONN288_ADR50001P013C01  I178
  J27    158  VSS67  SCONN288_ADR50001P013C01  I178
  J27    160  VSS68  SCONN288_ADR50001P013C01  I178
  J27    162  VSS69  SCONN288_ADR50001P013C01  I178
  J27    164  VSS70  SCONN288_ADR50001P013C01  I178
  J27    166  VSS71  SCONN288_ADR50001P013C01  I178
  J27    169  VSS72  SCONN288_ADR50001P013C01  I178
  J27    171  VSS73  SCONN288_ADR50001P013C01  I178
  J27    173  VSS74  SCONN288_ADR50001P013C01  I178
  J27    175  VSS75  SCONN288_ADR50001P013C01  I178
  J27    177  VSS76  SCONN288_ADR50001P013C01  I178
  J27    180  VSS77  SCONN288_ADR50001P013C01  I178
  J27    182  VSS78  SCONN288_ADR50001P013C01  I178
  J27    184  VSS79  SCONN288_ADR50001P013C01  I178
  J27    186  VSS80  SCONN288_ADR50001P013C01  I178
  J27    188  VSS81  SCONN288_ADR50001P013C01  I178
  J27    191  VSS82  SCONN288_ADR50001P013C01  I178
  J27    193  VSS83  SCONN288_ADR50001P013C01  I178
  J27    195  VSS84  SCONN288_ADR50001P013C01  I178
  J27    197  VSS85  SCONN288_ADR50001P013C01  I178
  J27    199  VSS86  SCONN288_ADR50001P013C01  I178
  J27    202  VSS87  SCONN288_ADR50001P013C01  I178
  J27    204  VSS88  SCONN288_ADR50001P013C01  I178
  J27    206  VSS89  SCONN288_ADR50001P013C01  I178
  J27    208  VSS90  SCONN288_ADR50001P013C01  I178
  J27    210  VSS91  SCONN288_ADR50001P013C01  I178
  J27    212  VSS92  SCONN288_ADR50001P013C01  I178
  J27    214  VSS93  SCONN288_ADR50001P013C01  I178
  J27    216  VSS94  SCONN288_ADR50001P013C01  I178
  J27    219  VSS95  SCONN288_ADR50001P013C01  I178
  J27    222  VSS96  SCONN288_ADR50001P013C01  I178
  J27    224  VSS97  SCONN288_ADR50001P013C01  I178
  J27    226  VSS98  SCONN288_ADR50001P013C01  I178
  J27    228  VSS99  SCONN288_ADR50001P013C01  I178
  J27    230  VSS100  SCONN288_ADR50001P013C01  I178
  J27    233  VSS101  SCONN288_ADR50001P013C01  I178
  J27    235  VSS102  SCONN288_ADR50001P013C01  I178
  J27    237  VSS103  SCONN288_ADR50001P013C01  I178
  J27    240  VSS104  SCONN288_ADR50001P013C01  I178
  J27    242  VSS105  SCONN288_ADR50001P013C01  I178
  J27    244  VSS106  SCONN288_ADR50001P013C01  I178
  J27    246  VSS107  SCONN288_ADR50001P013C01  I178
  J27    248  VSS108  SCONN288_ADR50001P013C01  I178
  J27    251  VSS109  SCONN288_ADR50001P013C01  I178
  J27    253  VSS110  SCONN288_ADR50001P013C01  I178
  J27    255  VSS111  SCONN288_ADR50001P013C01  I178
  J27    257  VSS112  SCONN288_ADR50001P013C01  I178
  J27    259  VSS113  SCONN288_ADR50001P013C01  I178
  J27    262  VSS114  SCONN288_ADR50001P013C01  I178
  J27    264  VSS115  SCONN288_ADR50001P013C01  I178
  J27    266  VSS116  SCONN288_ADR50001P013C01  I178
  J27    268  VSS117  SCONN288_ADR50001P013C01  I178
  J27    270  VSS118  SCONN288_ADR50001P013C01  I178
  J27    273  VSS119  SCONN288_ADR50001P013C01  I178
  J27    275  VSS120  SCONN288_ADR50001P013C01  I178
  J27    277  VSS121  SCONN288_ADR50001P013C01  I178
  J27    279  VSS122  SCONN288_ADR50001P013C01  I178
  J27    281  VSS123  SCONN288_ADR50001P013C01  I178
  J27    284  VSS124  SCONN288_ADR50001P013C01  I178
  J27    286  VSS125  SCONN288_ADR50001P013C01  I178
  J27    288  VSS126  SCONN288_ADR50001P013C01  I178
  J27     G1     G1  SCONN288_ADR50001P013C01  I178
  J27     G2     G2  SCONN288_ADR50001P013C01  I178
  J27     G3     G3  SCONN288_ADR50001P013C01  I178
  J28      6   VSS0  SCONN288_ADR50001P003C01  I176
  J28      8   VSS1  SCONN288_ADR50001P003C01  I176
  J28     10   VSS2  SCONN288_ADR50001P003C01  I176
  J28     13   VSS3  SCONN288_ADR50001P003C01  I176
  J28     15   VSS4  SCONN288_ADR50001P003C01  I176
  J28     17   VSS5  SCONN288_ADR50001P003C01  I176
  J28     19   VSS6  SCONN288_ADR50001P003C01  I176
  J28     21   VSS7  SCONN288_ADR50001P003C01  I176
  J28     24   VSS8  SCONN288_ADR50001P003C01  I176
  J28     26   VSS9  SCONN288_ADR50001P003C01  I176
  J28     28  VSS10  SCONN288_ADR50001P003C01  I176
  J28     30  VSS11  SCONN288_ADR50001P003C01  I176
  J28     32  VSS12  SCONN288_ADR50001P003C01  I176
  J28     35  VSS13  SCONN288_ADR50001P003C01  I176
  J28     37  VSS14  SCONN288_ADR50001P003C01  I176
  J28     39  VSS15  SCONN288_ADR50001P003C01  I176
  J28     41  VSS16  SCONN288_ADR50001P003C01  I176
  J28     43  VSS17  SCONN288_ADR50001P003C01  I176
  J28     46  VSS18  SCONN288_ADR50001P003C01  I176
  J28     48  VSS19  SCONN288_ADR50001P003C01  I176
  J28     50  VSS20  SCONN288_ADR50001P003C01  I176
  J28     52  VSS21  SCONN288_ADR50001P003C01  I176
  J28     54  VSS22  SCONN288_ADR50001P003C01  I176
  J28     57  VSS23  SCONN288_ADR50001P003C01  I176
  J28     59  VSS24  SCONN288_ADR50001P003C01  I176
  J28     61  VSS25  SCONN288_ADR50001P003C01  I176
  J28     63  VSS26  SCONN288_ADR50001P003C01  I176
  J28     65  VSS27  SCONN288_ADR50001P003C01  I176
  J28     67  VSS28  SCONN288_ADR50001P003C01  I176
  J28     69  VSS29  SCONN288_ADR50001P003C01  I176
  J28     71  VSS30  SCONN288_ADR50001P003C01  I176
  J28     73  VSS31  SCONN288_ADR50001P003C01  I176
  J28     75  VSS32  SCONN288_ADR50001P003C01  I176
  J28     77  VSS33  SCONN288_ADR50001P003C01  I176
  J28     79  VSS34  SCONN288_ADR50001P003C01  I176
  J28     81  VSS35  SCONN288_ADR50001P003C01  I176
  J28     83  VSS36  SCONN288_ADR50001P003C01  I176
  J28     85  VSS37  SCONN288_ADR50001P003C01  I176
  J28     88  VSS38  SCONN288_ADR50001P003C01  I176
  J28     90  VSS39  SCONN288_ADR50001P003C01  I176
  J28     92  VSS40  SCONN288_ADR50001P003C01  I176
  J28     95  VSS41  SCONN288_ADR50001P003C01  I176
  J28     97  VSS42  SCONN288_ADR50001P003C01  I176
  J28     99  VSS43  SCONN288_ADR50001P003C01  I176
  J28    101  VSS44  SCONN288_ADR50001P003C01  I176
  J28    103  VSS45  SCONN288_ADR50001P003C01  I176
  J28    106  VSS46  SCONN288_ADR50001P003C01  I176
  J28    108  VSS47  SCONN288_ADR50001P003C01  I176
  J28    110  VSS48  SCONN288_ADR50001P003C01  I176
  J28    112  VSS49  SCONN288_ADR50001P003C01  I176
  J28    114  VSS50  SCONN288_ADR50001P003C01  I176
  J28    117  VSS51  SCONN288_ADR50001P003C01  I176
  J28    119  VSS52  SCONN288_ADR50001P003C01  I176
  J28    121  VSS53  SCONN288_ADR50001P003C01  I176
  J28    123  VSS54  SCONN288_ADR50001P003C01  I176
  J28    125  VSS55  SCONN288_ADR50001P003C01  I176
  J28    128  VSS56  SCONN288_ADR50001P003C01  I176
  J28    130  VSS57  SCONN288_ADR50001P003C01  I176
  J28    132  VSS58  SCONN288_ADR50001P003C01  I176
  J28    134  VSS59  SCONN288_ADR50001P003C01  I176
  J28    136  VSS60  SCONN288_ADR50001P003C01  I176
  J28    139  VSS61  SCONN288_ADR50001P003C01  I176
  J28    141  VSS62  SCONN288_ADR50001P003C01  I176
  J28    143  VSS63  SCONN288_ADR50001P003C01  I176
  J28    151  VSS64  SCONN288_ADR50001P003C01  I176
  J28    153  VSS65  SCONN288_ADR50001P003C01  I176
  J28    155  VSS66  SCONN288_ADR50001P003C01  I176
  J28    158  VSS67  SCONN288_ADR50001P003C01  I176
  J28    160  VSS68  SCONN288_ADR50001P003C01  I176
  J28    162  VSS69  SCONN288_ADR50001P003C01  I176
  J28    164  VSS70  SCONN288_ADR50001P003C01  I176
  J28    166  VSS71  SCONN288_ADR50001P003C01  I176
  J28    169  VSS72  SCONN288_ADR50001P003C01  I176
  J28    171  VSS73  SCONN288_ADR50001P003C01  I176
  J28    173  VSS74  SCONN288_ADR50001P003C01  I176
  J28    175  VSS75  SCONN288_ADR50001P003C01  I176
  J28    177  VSS76  SCONN288_ADR50001P003C01  I176
  J28    180  VSS77  SCONN288_ADR50001P003C01  I176
  J28    182  VSS78  SCONN288_ADR50001P003C01  I176
  J28    184  VSS79  SCONN288_ADR50001P003C01  I176
  J28    186  VSS80  SCONN288_ADR50001P003C01  I176
  J28    188  VSS81  SCONN288_ADR50001P003C01  I176
  J28    191  VSS82  SCONN288_ADR50001P003C01  I176
  J28    193  VSS83  SCONN288_ADR50001P003C01  I176
  J28    195  VSS84  SCONN288_ADR50001P003C01  I176
  J28    197  VSS85  SCONN288_ADR50001P003C01  I176
  J28    199  VSS86  SCONN288_ADR50001P003C01  I176
  J28    202  VSS87  SCONN288_ADR50001P003C01  I176
  J28    204  VSS88  SCONN288_ADR50001P003C01  I176
  J28    206  VSS89  SCONN288_ADR50001P003C01  I176
  J28    208  VSS90  SCONN288_ADR50001P003C01  I176
  J28    210  VSS91  SCONN288_ADR50001P003C01  I176
  J28    212  VSS92  SCONN288_ADR50001P003C01  I176
  J28    214  VSS93  SCONN288_ADR50001P003C01  I176
  J28    216  VSS94  SCONN288_ADR50001P003C01  I176
  J28    219  VSS95  SCONN288_ADR50001P003C01  I176
  J28    222  VSS96  SCONN288_ADR50001P003C01  I176
  J28    224  VSS97  SCONN288_ADR50001P003C01  I176
  J28    226  VSS98  SCONN288_ADR50001P003C01  I176
  J28    228  VSS99  SCONN288_ADR50001P003C01  I176
  J28    230  VSS100  SCONN288_ADR50001P003C01  I176
  J28    233  VSS101  SCONN288_ADR50001P003C01  I176
  J28    235  VSS102  SCONN288_ADR50001P003C01  I176
  J28    237  VSS103  SCONN288_ADR50001P003C01  I176
  J28    240  VSS104  SCONN288_ADR50001P003C01  I176
  J28    242  VSS105  SCONN288_ADR50001P003C01  I176
  J28    244  VSS106  SCONN288_ADR50001P003C01  I176
  J28    246  VSS107  SCONN288_ADR50001P003C01  I176
  J28    248  VSS108  SCONN288_ADR50001P003C01  I176
  J28    251  VSS109  SCONN288_ADR50001P003C01  I176
  J28    253  VSS110  SCONN288_ADR50001P003C01  I176
  J28    255  VSS111  SCONN288_ADR50001P003C01  I176
  J28    257  VSS112  SCONN288_ADR50001P003C01  I176
  J28    259  VSS113  SCONN288_ADR50001P003C01  I176
  J28    262  VSS114  SCONN288_ADR50001P003C01  I176
  J28    264  VSS115  SCONN288_ADR50001P003C01  I176
  J28    266  VSS116  SCONN288_ADR50001P003C01  I176
  J28    268  VSS117  SCONN288_ADR50001P003C01  I176
  J28    270  VSS118  SCONN288_ADR50001P003C01  I176
  J28    273  VSS119  SCONN288_ADR50001P003C01  I176
  J28    275  VSS120  SCONN288_ADR50001P003C01  I176
  J28    277  VSS121  SCONN288_ADR50001P003C01  I176
  J28    279  VSS122  SCONN288_ADR50001P003C01  I176
  J28    281  VSS123  SCONN288_ADR50001P003C01  I176
  J28    284  VSS124  SCONN288_ADR50001P003C01  I176
  J28    286  VSS125  SCONN288_ADR50001P003C01  I176
  J28    288  VSS126  SCONN288_ADR50001P003C01  I176
  J28     G1     G1  SCONN288_ADR50001P003C01  I176
  J28     G2     G2  SCONN288_ADR50001P003C01  I176
  J28     G3     G3  SCONN288_ADR50001P003C01  I176
  J29      6   VSS0  SCONN288_ADR50001P013C01  I178
  J29      8   VSS1  SCONN288_ADR50001P013C01  I178
  J29     10   VSS2  SCONN288_ADR50001P013C01  I178
  J29     13   VSS3  SCONN288_ADR50001P013C01  I178
  J29     15   VSS4  SCONN288_ADR50001P013C01  I178
  J29     17   VSS5  SCONN288_ADR50001P013C01  I178
  J29     19   VSS6  SCONN288_ADR50001P013C01  I178
  J29     21   VSS7  SCONN288_ADR50001P013C01  I178
  J29     24   VSS8  SCONN288_ADR50001P013C01  I178
  J29     26   VSS9  SCONN288_ADR50001P013C01  I178
  J29     28  VSS10  SCONN288_ADR50001P013C01  I178
  J29     30  VSS11  SCONN288_ADR50001P013C01  I178
  J29     32  VSS12  SCONN288_ADR50001P013C01  I178
  J29     35  VSS13  SCONN288_ADR50001P013C01  I178
  J29     37  VSS14  SCONN288_ADR50001P013C01  I178
  J29     39  VSS15  SCONN288_ADR50001P013C01  I178
  J29     41  VSS16  SCONN288_ADR50001P013C01  I178
  J29     43  VSS17  SCONN288_ADR50001P013C01  I178
  J29     46  VSS18  SCONN288_ADR50001P013C01  I178
  J29     48  VSS19  SCONN288_ADR50001P013C01  I178
  J29     50  VSS20  SCONN288_ADR50001P013C01  I178
  J29     52  VSS21  SCONN288_ADR50001P013C01  I178
  J29     54  VSS22  SCONN288_ADR50001P013C01  I178
  J29     57  VSS23  SCONN288_ADR50001P013C01  I178
  J29     59  VSS24  SCONN288_ADR50001P013C01  I178
  J29     61  VSS25  SCONN288_ADR50001P013C01  I178
  J29     63  VSS26  SCONN288_ADR50001P013C01  I178
  J29     65  VSS27  SCONN288_ADR50001P013C01  I178
  J29     67  VSS28  SCONN288_ADR50001P013C01  I178
  J29     69  VSS29  SCONN288_ADR50001P013C01  I178
  J29     71  VSS30  SCONN288_ADR50001P013C01  I178
  J29     73  VSS31  SCONN288_ADR50001P013C01  I178
  J29     75  VSS32  SCONN288_ADR50001P013C01  I178
  J29     77  VSS33  SCONN288_ADR50001P013C01  I178
  J29     79  VSS34  SCONN288_ADR50001P013C01  I178
  J29     81  VSS35  SCONN288_ADR50001P013C01  I178
  J29     83  VSS36  SCONN288_ADR50001P013C01  I178
  J29     85  VSS37  SCONN288_ADR50001P013C01  I178
  J29     88  VSS38  SCONN288_ADR50001P013C01  I178
  J29     90  VSS39  SCONN288_ADR50001P013C01  I178
  J29     92  VSS40  SCONN288_ADR50001P013C01  I178
  J29     95  VSS41  SCONN288_ADR50001P013C01  I178
  J29     97  VSS42  SCONN288_ADR50001P013C01  I178
  J29     99  VSS43  SCONN288_ADR50001P013C01  I178
  J29    101  VSS44  SCONN288_ADR50001P013C01  I178
  J29    103  VSS45  SCONN288_ADR50001P013C01  I178
  J29    106  VSS46  SCONN288_ADR50001P013C01  I178
  J29    108  VSS47  SCONN288_ADR50001P013C01  I178
  J29    110  VSS48  SCONN288_ADR50001P013C01  I178
  J29    112  VSS49  SCONN288_ADR50001P013C01  I178
  J29    114  VSS50  SCONN288_ADR50001P013C01  I178
  J29    117  VSS51  SCONN288_ADR50001P013C01  I178
  J29    119  VSS52  SCONN288_ADR50001P013C01  I178
  J29    121  VSS53  SCONN288_ADR50001P013C01  I178
  J29    123  VSS54  SCONN288_ADR50001P013C01  I178
  J29    125  VSS55  SCONN288_ADR50001P013C01  I178
  J29    128  VSS56  SCONN288_ADR50001P013C01  I178
  J29    130  VSS57  SCONN288_ADR50001P013C01  I178
  J29    132  VSS58  SCONN288_ADR50001P013C01  I178
  J29    134  VSS59  SCONN288_ADR50001P013C01  I178
  J29    136  VSS60  SCONN288_ADR50001P013C01  I178
  J29    139  VSS61  SCONN288_ADR50001P013C01  I178
  J29    141  VSS62  SCONN288_ADR50001P013C01  I178
  J29    143  VSS63  SCONN288_ADR50001P013C01  I178
  J29    151  VSS64  SCONN288_ADR50001P013C01  I178
  J29    153  VSS65  SCONN288_ADR50001P013C01  I178
  J29    155  VSS66  SCONN288_ADR50001P013C01  I178
  J29    158  VSS67  SCONN288_ADR50001P013C01  I178
  J29    160  VSS68  SCONN288_ADR50001P013C01  I178
  J29    162  VSS69  SCONN288_ADR50001P013C01  I178
  J29    164  VSS70  SCONN288_ADR50001P013C01  I178
  J29    166  VSS71  SCONN288_ADR50001P013C01  I178
  J29    169  VSS72  SCONN288_ADR50001P013C01  I178
  J29    171  VSS73  SCONN288_ADR50001P013C01  I178
  J29    173  VSS74  SCONN288_ADR50001P013C01  I178
  J29    175  VSS75  SCONN288_ADR50001P013C01  I178
  J29    177  VSS76  SCONN288_ADR50001P013C01  I178
  J29    180  VSS77  SCONN288_ADR50001P013C01  I178
  J29    182  VSS78  SCONN288_ADR50001P013C01  I178
  J29    184  VSS79  SCONN288_ADR50001P013C01  I178
  J29    186  VSS80  SCONN288_ADR50001P013C01  I178
  J29    188  VSS81  SCONN288_ADR50001P013C01  I178
  J29    191  VSS82  SCONN288_ADR50001P013C01  I178
  J29    193  VSS83  SCONN288_ADR50001P013C01  I178
  J29    195  VSS84  SCONN288_ADR50001P013C01  I178
  J29    197  VSS85  SCONN288_ADR50001P013C01  I178
  J29    199  VSS86  SCONN288_ADR50001P013C01  I178
  J29    202  VSS87  SCONN288_ADR50001P013C01  I178
  J29    204  VSS88  SCONN288_ADR50001P013C01  I178
  J29    206  VSS89  SCONN288_ADR50001P013C01  I178
  J29    208  VSS90  SCONN288_ADR50001P013C01  I178
  J29    210  VSS91  SCONN288_ADR50001P013C01  I178
  J29    212  VSS92  SCONN288_ADR50001P013C01  I178
  J29    214  VSS93  SCONN288_ADR50001P013C01  I178
  J29    216  VSS94  SCONN288_ADR50001P013C01  I178
  J29    219  VSS95  SCONN288_ADR50001P013C01  I178
  J29    222  VSS96  SCONN288_ADR50001P013C01  I178
  J29    224  VSS97  SCONN288_ADR50001P013C01  I178
  J29    226  VSS98  SCONN288_ADR50001P013C01  I178
  J29    228  VSS99  SCONN288_ADR50001P013C01  I178
  J29    230  VSS100  SCONN288_ADR50001P013C01  I178
  J29    233  VSS101  SCONN288_ADR50001P013C01  I178
  J29    235  VSS102  SCONN288_ADR50001P013C01  I178
  J29    237  VSS103  SCONN288_ADR50001P013C01  I178
  J29    240  VSS104  SCONN288_ADR50001P013C01  I178
  J29    242  VSS105  SCONN288_ADR50001P013C01  I178
  J29    244  VSS106  SCONN288_ADR50001P013C01  I178
  J29    246  VSS107  SCONN288_ADR50001P013C01  I178
  J29    248  VSS108  SCONN288_ADR50001P013C01  I178
  J29    251  VSS109  SCONN288_ADR50001P013C01  I178
  J29    253  VSS110  SCONN288_ADR50001P013C01  I178
  J29    255  VSS111  SCONN288_ADR50001P013C01  I178
  J29    257  VSS112  SCONN288_ADR50001P013C01  I178
  J29    259  VSS113  SCONN288_ADR50001P013C01  I178
  J29    262  VSS114  SCONN288_ADR50001P013C01  I178
  J29    264  VSS115  SCONN288_ADR50001P013C01  I178
  J29    266  VSS116  SCONN288_ADR50001P013C01  I178
  J29    268  VSS117  SCONN288_ADR50001P013C01  I178
  J29    270  VSS118  SCONN288_ADR50001P013C01  I178
  J29    273  VSS119  SCONN288_ADR50001P013C01  I178
  J29    275  VSS120  SCONN288_ADR50001P013C01  I178
  J29    277  VSS121  SCONN288_ADR50001P013C01  I178
  J29    279  VSS122  SCONN288_ADR50001P013C01  I178
  J29    281  VSS123  SCONN288_ADR50001P013C01  I178
  J29    284  VSS124  SCONN288_ADR50001P013C01  I178
  J29    286  VSS125  SCONN288_ADR50001P013C01  I178
  J29    288  VSS126  SCONN288_ADR50001P013C01  I178
  J29     G1     G1  SCONN288_ADR50001P013C01  I178
  J29     G2     G2  SCONN288_ADR50001P013C01  I178
  J29     G3     G3  SCONN288_ADR50001P013C01  I178
  J30      6   VSS0  SCONN288_ADR50001P003C01  I178
  J30      8   VSS1  SCONN288_ADR50001P003C01  I178
  J30     10   VSS2  SCONN288_ADR50001P003C01  I178
  J30     13   VSS3  SCONN288_ADR50001P003C01  I178
  J30     15   VSS4  SCONN288_ADR50001P003C01  I178
  J30     17   VSS5  SCONN288_ADR50001P003C01  I178
  J30     19   VSS6  SCONN288_ADR50001P003C01  I178
  J30     21   VSS7  SCONN288_ADR50001P003C01  I178
  J30     24   VSS8  SCONN288_ADR50001P003C01  I178
  J30     26   VSS9  SCONN288_ADR50001P003C01  I178
  J30     28  VSS10  SCONN288_ADR50001P003C01  I178
  J30     30  VSS11  SCONN288_ADR50001P003C01  I178
  J30     32  VSS12  SCONN288_ADR50001P003C01  I178
  J30     35  VSS13  SCONN288_ADR50001P003C01  I178
  J30     37  VSS14  SCONN288_ADR50001P003C01  I178
  J30     39  VSS15  SCONN288_ADR50001P003C01  I178
  J30     41  VSS16  SCONN288_ADR50001P003C01  I178
  J30     43  VSS17  SCONN288_ADR50001P003C01  I178
  J30     46  VSS18  SCONN288_ADR50001P003C01  I178
  J30     48  VSS19  SCONN288_ADR50001P003C01  I178
  J30     50  VSS20  SCONN288_ADR50001P003C01  I178
  J30     52  VSS21  SCONN288_ADR50001P003C01  I178
  J30     54  VSS22  SCONN288_ADR50001P003C01  I178
  J30     57  VSS23  SCONN288_ADR50001P003C01  I178
  J30     59  VSS24  SCONN288_ADR50001P003C01  I178
  J30     61  VSS25  SCONN288_ADR50001P003C01  I178
  J30     63  VSS26  SCONN288_ADR50001P003C01  I178
  J30     65  VSS27  SCONN288_ADR50001P003C01  I178
  J30     67  VSS28  SCONN288_ADR50001P003C01  I178
  J30     69  VSS29  SCONN288_ADR50001P003C01  I178
  J30     71  VSS30  SCONN288_ADR50001P003C01  I178
  J30     73  VSS31  SCONN288_ADR50001P003C01  I178
  J30     75  VSS32  SCONN288_ADR50001P003C01  I178
  J30     77  VSS33  SCONN288_ADR50001P003C01  I178
  J30     79  VSS34  SCONN288_ADR50001P003C01  I178
  J30     81  VSS35  SCONN288_ADR50001P003C01  I178
  J30     83  VSS36  SCONN288_ADR50001P003C01  I178
  J30     85  VSS37  SCONN288_ADR50001P003C01  I178
  J30     88  VSS38  SCONN288_ADR50001P003C01  I178
  J30     90  VSS39  SCONN288_ADR50001P003C01  I178
  J30     92  VSS40  SCONN288_ADR50001P003C01  I178
  J30     95  VSS41  SCONN288_ADR50001P003C01  I178
  J30     97  VSS42  SCONN288_ADR50001P003C01  I178
  J30     99  VSS43  SCONN288_ADR50001P003C01  I178
  J30    101  VSS44  SCONN288_ADR50001P003C01  I178
  J30    103  VSS45  SCONN288_ADR50001P003C01  I178
  J30    106  VSS46  SCONN288_ADR50001P003C01  I178
  J30    108  VSS47  SCONN288_ADR50001P003C01  I178
  J30    110  VSS48  SCONN288_ADR50001P003C01  I178
  J30    112  VSS49  SCONN288_ADR50001P003C01  I178
  J30    114  VSS50  SCONN288_ADR50001P003C01  I178
  J30    117  VSS51  SCONN288_ADR50001P003C01  I178
  J30    119  VSS52  SCONN288_ADR50001P003C01  I178
  J30    121  VSS53  SCONN288_ADR50001P003C01  I178
  J30    123  VSS54  SCONN288_ADR50001P003C01  I178
  J30    125  VSS55  SCONN288_ADR50001P003C01  I178
  J30    128  VSS56  SCONN288_ADR50001P003C01  I178
  J30    130  VSS57  SCONN288_ADR50001P003C01  I178
  J30    132  VSS58  SCONN288_ADR50001P003C01  I178
  J30    134  VSS59  SCONN288_ADR50001P003C01  I178
  J30    136  VSS60  SCONN288_ADR50001P003C01  I178
  J30    139  VSS61  SCONN288_ADR50001P003C01  I178
  J30    141  VSS62  SCONN288_ADR50001P003C01  I178
  J30    143  VSS63  SCONN288_ADR50001P003C01  I178
  J30    151  VSS64  SCONN288_ADR50001P003C01  I178
  J30    153  VSS65  SCONN288_ADR50001P003C01  I178
  J30    155  VSS66  SCONN288_ADR50001P003C01  I178
  J30    158  VSS67  SCONN288_ADR50001P003C01  I178
  J30    160  VSS68  SCONN288_ADR50001P003C01  I178
  J30    162  VSS69  SCONN288_ADR50001P003C01  I178
  J30    164  VSS70  SCONN288_ADR50001P003C01  I178
  J30    166  VSS71  SCONN288_ADR50001P003C01  I178
  J30    169  VSS72  SCONN288_ADR50001P003C01  I178
  J30    171  VSS73  SCONN288_ADR50001P003C01  I178
  J30    173  VSS74  SCONN288_ADR50001P003C01  I178
  J30    175  VSS75  SCONN288_ADR50001P003C01  I178
  J30    177  VSS76  SCONN288_ADR50001P003C01  I178
  J30    180  VSS77  SCONN288_ADR50001P003C01  I178
  J30    182  VSS78  SCONN288_ADR50001P003C01  I178
  J30    184  VSS79  SCONN288_ADR50001P003C01  I178
  J30    186  VSS80  SCONN288_ADR50001P003C01  I178
  J30    188  VSS81  SCONN288_ADR50001P003C01  I178
  J30    191  VSS82  SCONN288_ADR50001P003C01  I178
  J30    193  VSS83  SCONN288_ADR50001P003C01  I178
  J30    195  VSS84  SCONN288_ADR50001P003C01  I178
  J30    197  VSS85  SCONN288_ADR50001P003C01  I178
  J30    199  VSS86  SCONN288_ADR50001P003C01  I178
  J30    202  VSS87  SCONN288_ADR50001P003C01  I178
  J30    204  VSS88  SCONN288_ADR50001P003C01  I178
  J30    206  VSS89  SCONN288_ADR50001P003C01  I178
  J30    208  VSS90  SCONN288_ADR50001P003C01  I178
  J30    210  VSS91  SCONN288_ADR50001P003C01  I178
  J30    212  VSS92  SCONN288_ADR50001P003C01  I178
  J30    214  VSS93  SCONN288_ADR50001P003C01  I178
  J30    216  VSS94  SCONN288_ADR50001P003C01  I178
  J30    219  VSS95  SCONN288_ADR50001P003C01  I178
  J30    222  VSS96  SCONN288_ADR50001P003C01  I178
  J30    224  VSS97  SCONN288_ADR50001P003C01  I178
  J30    226  VSS98  SCONN288_ADR50001P003C01  I178
  J30    228  VSS99  SCONN288_ADR50001P003C01  I178
  J30    230  VSS100  SCONN288_ADR50001P003C01  I178
  J30    233  VSS101  SCONN288_ADR50001P003C01  I178
  J30    235  VSS102  SCONN288_ADR50001P003C01  I178
  J30    237  VSS103  SCONN288_ADR50001P003C01  I178
  J30    240  VSS104  SCONN288_ADR50001P003C01  I178
  J30    242  VSS105  SCONN288_ADR50001P003C01  I178
  J30    244  VSS106  SCONN288_ADR50001P003C01  I178
  J30    246  VSS107  SCONN288_ADR50001P003C01  I178
  J30    248  VSS108  SCONN288_ADR50001P003C01  I178
  J30    251  VSS109  SCONN288_ADR50001P003C01  I178
  J30    253  VSS110  SCONN288_ADR50001P003C01  I178
  J30    255  VSS111  SCONN288_ADR50001P003C01  I178
  J30    257  VSS112  SCONN288_ADR50001P003C01  I178
  J30    259  VSS113  SCONN288_ADR50001P003C01  I178
  J30    262  VSS114  SCONN288_ADR50001P003C01  I178
  J30    264  VSS115  SCONN288_ADR50001P003C01  I178
  J30    266  VSS116  SCONN288_ADR50001P003C01  I178
  J30    268  VSS117  SCONN288_ADR50001P003C01  I178
  J30    270  VSS118  SCONN288_ADR50001P003C01  I178
  J30    273  VSS119  SCONN288_ADR50001P003C01  I178
  J30    275  VSS120  SCONN288_ADR50001P003C01  I178
  J30    277  VSS121  SCONN288_ADR50001P003C01  I178
  J30    279  VSS122  SCONN288_ADR50001P003C01  I178
  J30    281  VSS123  SCONN288_ADR50001P003C01  I178
  J30    284  VSS124  SCONN288_ADR50001P003C01  I178
  J30    286  VSS125  SCONN288_ADR50001P003C01  I178
  J30    288  VSS126  SCONN288_ADR50001P003C01  I178
  J30     G1     G1  SCONN288_ADR50001P003C01  I178
  J30     G2     G2  SCONN288_ADR50001P003C01  I178
  J30     G3     G3  SCONN288_ADR50001P003C01  I178
  J31      6   VSS0  SCONN288_ADR50001P013C01  I178
  J31      8   VSS1  SCONN288_ADR50001P013C01  I178
  J31     10   VSS2  SCONN288_ADR50001P013C01  I178
  J31     13   VSS3  SCONN288_ADR50001P013C01  I178
  J31     15   VSS4  SCONN288_ADR50001P013C01  I178
  J31     17   VSS5  SCONN288_ADR50001P013C01  I178
  J31     19   VSS6  SCONN288_ADR50001P013C01  I178
  J31     21   VSS7  SCONN288_ADR50001P013C01  I178
  J31     24   VSS8  SCONN288_ADR50001P013C01  I178
  J31     26   VSS9  SCONN288_ADR50001P013C01  I178
  J31     28  VSS10  SCONN288_ADR50001P013C01  I178
  J31     30  VSS11  SCONN288_ADR50001P013C01  I178
  J31     32  VSS12  SCONN288_ADR50001P013C01  I178
  J31     35  VSS13  SCONN288_ADR50001P013C01  I178
  J31     37  VSS14  SCONN288_ADR50001P013C01  I178
  J31     39  VSS15  SCONN288_ADR50001P013C01  I178
  J31     41  VSS16  SCONN288_ADR50001P013C01  I178
  J31     43  VSS17  SCONN288_ADR50001P013C01  I178
  J31     46  VSS18  SCONN288_ADR50001P013C01  I178
  J31     48  VSS19  SCONN288_ADR50001P013C01  I178
  J31     50  VSS20  SCONN288_ADR50001P013C01  I178
  J31     52  VSS21  SCONN288_ADR50001P013C01  I178
  J31     54  VSS22  SCONN288_ADR50001P013C01  I178
  J31     57  VSS23  SCONN288_ADR50001P013C01  I178
  J31     59  VSS24  SCONN288_ADR50001P013C01  I178
  J31     61  VSS25  SCONN288_ADR50001P013C01  I178
  J31     63  VSS26  SCONN288_ADR50001P013C01  I178
  J31     65  VSS27  SCONN288_ADR50001P013C01  I178
  J31     67  VSS28  SCONN288_ADR50001P013C01  I178
  J31     69  VSS29  SCONN288_ADR50001P013C01  I178
  J31     71  VSS30  SCONN288_ADR50001P013C01  I178
  J31     73  VSS31  SCONN288_ADR50001P013C01  I178
  J31     75  VSS32  SCONN288_ADR50001P013C01  I178
  J31     77  VSS33  SCONN288_ADR50001P013C01  I178
  J31     79  VSS34  SCONN288_ADR50001P013C01  I178
  J31     81  VSS35  SCONN288_ADR50001P013C01  I178
  J31     83  VSS36  SCONN288_ADR50001P013C01  I178
  J31     85  VSS37  SCONN288_ADR50001P013C01  I178
  J31     88  VSS38  SCONN288_ADR50001P013C01  I178
  J31     90  VSS39  SCONN288_ADR50001P013C01  I178
  J31     92  VSS40  SCONN288_ADR50001P013C01  I178
  J31     95  VSS41  SCONN288_ADR50001P013C01  I178
  J31     97  VSS42  SCONN288_ADR50001P013C01  I178
  J31     99  VSS43  SCONN288_ADR50001P013C01  I178
  J31    101  VSS44  SCONN288_ADR50001P013C01  I178
  J31    103  VSS45  SCONN288_ADR50001P013C01  I178
  J31    106  VSS46  SCONN288_ADR50001P013C01  I178
  J31    108  VSS47  SCONN288_ADR50001P013C01  I178
  J31    110  VSS48  SCONN288_ADR50001P013C01  I178
  J31    112  VSS49  SCONN288_ADR50001P013C01  I178
  J31    114  VSS50  SCONN288_ADR50001P013C01  I178
  J31    117  VSS51  SCONN288_ADR50001P013C01  I178
  J31    119  VSS52  SCONN288_ADR50001P013C01  I178
  J31    121  VSS53  SCONN288_ADR50001P013C01  I178
  J31    123  VSS54  SCONN288_ADR50001P013C01  I178
  J31    125  VSS55  SCONN288_ADR50001P013C01  I178
  J31    128  VSS56  SCONN288_ADR50001P013C01  I178
  J31    130  VSS57  SCONN288_ADR50001P013C01  I178
  J31    132  VSS58  SCONN288_ADR50001P013C01  I178
  J31    134  VSS59  SCONN288_ADR50001P013C01  I178
  J31    136  VSS60  SCONN288_ADR50001P013C01  I178
  J31    139  VSS61  SCONN288_ADR50001P013C01  I178
  J31    141  VSS62  SCONN288_ADR50001P013C01  I178
  J31    143  VSS63  SCONN288_ADR50001P013C01  I178
  J31    151  VSS64  SCONN288_ADR50001P013C01  I178
  J31    153  VSS65  SCONN288_ADR50001P013C01  I178
  J31    155  VSS66  SCONN288_ADR50001P013C01  I178
  J31    158  VSS67  SCONN288_ADR50001P013C01  I178
  J31    160  VSS68  SCONN288_ADR50001P013C01  I178
  J31    162  VSS69  SCONN288_ADR50001P013C01  I178
  J31    164  VSS70  SCONN288_ADR50001P013C01  I178
  J31    166  VSS71  SCONN288_ADR50001P013C01  I178
  J31    169  VSS72  SCONN288_ADR50001P013C01  I178
  J31    171  VSS73  SCONN288_ADR50001P013C01  I178
  J31    173  VSS74  SCONN288_ADR50001P013C01  I178
  J31    175  VSS75  SCONN288_ADR50001P013C01  I178
  J31    177  VSS76  SCONN288_ADR50001P013C01  I178
  J31    180  VSS77  SCONN288_ADR50001P013C01  I178
  J31    182  VSS78  SCONN288_ADR50001P013C01  I178
  J31    184  VSS79  SCONN288_ADR50001P013C01  I178
  J31    186  VSS80  SCONN288_ADR50001P013C01  I178
  J31    188  VSS81  SCONN288_ADR50001P013C01  I178
  J31    191  VSS82  SCONN288_ADR50001P013C01  I178
  J31    193  VSS83  SCONN288_ADR50001P013C01  I178
  J31    195  VSS84  SCONN288_ADR50001P013C01  I178
  J31    197  VSS85  SCONN288_ADR50001P013C01  I178
  J31    199  VSS86  SCONN288_ADR50001P013C01  I178
  J31    202  VSS87  SCONN288_ADR50001P013C01  I178
  J31    204  VSS88  SCONN288_ADR50001P013C01  I178
  J31    206  VSS89  SCONN288_ADR50001P013C01  I178
  J31    208  VSS90  SCONN288_ADR50001P013C01  I178
  J31    210  VSS91  SCONN288_ADR50001P013C01  I178
  J31    212  VSS92  SCONN288_ADR50001P013C01  I178
  J31    214  VSS93  SCONN288_ADR50001P013C01  I178
  J31    216  VSS94  SCONN288_ADR50001P013C01  I178
  J31    219  VSS95  SCONN288_ADR50001P013C01  I178
  J31    222  VSS96  SCONN288_ADR50001P013C01  I178
  J31    224  VSS97  SCONN288_ADR50001P013C01  I178
  J31    226  VSS98  SCONN288_ADR50001P013C01  I178
  J31    228  VSS99  SCONN288_ADR50001P013C01  I178
  J31    230  VSS100  SCONN288_ADR50001P013C01  I178
  J31    233  VSS101  SCONN288_ADR50001P013C01  I178
  J31    235  VSS102  SCONN288_ADR50001P013C01  I178
  J31    237  VSS103  SCONN288_ADR50001P013C01  I178
  J31    240  VSS104  SCONN288_ADR50001P013C01  I178
  J31    242  VSS105  SCONN288_ADR50001P013C01  I178
  J31    244  VSS106  SCONN288_ADR50001P013C01  I178
  J31    246  VSS107  SCONN288_ADR50001P013C01  I178
  J31    248  VSS108  SCONN288_ADR50001P013C01  I178
  J31    251  VSS109  SCONN288_ADR50001P013C01  I178
  J31    253  VSS110  SCONN288_ADR50001P013C01  I178
  J31    255  VSS111  SCONN288_ADR50001P013C01  I178
  J31    257  VSS112  SCONN288_ADR50001P013C01  I178
  J31    259  VSS113  SCONN288_ADR50001P013C01  I178
  J31    262  VSS114  SCONN288_ADR50001P013C01  I178
  J31    264  VSS115  SCONN288_ADR50001P013C01  I178
  J31    266  VSS116  SCONN288_ADR50001P013C01  I178
  J31    268  VSS117  SCONN288_ADR50001P013C01  I178
  J31    270  VSS118  SCONN288_ADR50001P013C01  I178
  J31    273  VSS119  SCONN288_ADR50001P013C01  I178
  J31    275  VSS120  SCONN288_ADR50001P013C01  I178
  J31    277  VSS121  SCONN288_ADR50001P013C01  I178
  J31    279  VSS122  SCONN288_ADR50001P013C01  I178
  J31    281  VSS123  SCONN288_ADR50001P013C01  I178
  J31    284  VSS124  SCONN288_ADR50001P013C01  I178
  J31    286  VSS125  SCONN288_ADR50001P013C01  I178
  J31    288  VSS126  SCONN288_ADR50001P013C01  I178
  J31     G1     G1  SCONN288_ADR50001P013C01  I178
  J31     G2     G2  SCONN288_ADR50001P013C01  I178
  J31     G3     G3  SCONN288_ADR50001P013C01  I178
  J32      6   VSS0  SCONN288_ADR50001P003C01  I177
  J32      8   VSS1  SCONN288_ADR50001P003C01  I177
  J32     10   VSS2  SCONN288_ADR50001P003C01  I177
  J32     13   VSS3  SCONN288_ADR50001P003C01  I177
  J32     15   VSS4  SCONN288_ADR50001P003C01  I177
  J32     17   VSS5  SCONN288_ADR50001P003C01  I177
  J32     19   VSS6  SCONN288_ADR50001P003C01  I177
  J32     21   VSS7  SCONN288_ADR50001P003C01  I177
  J32     24   VSS8  SCONN288_ADR50001P003C01  I177
  J32     26   VSS9  SCONN288_ADR50001P003C01  I177
  J32     28  VSS10  SCONN288_ADR50001P003C01  I177
  J32     30  VSS11  SCONN288_ADR50001P003C01  I177
  J32     32  VSS12  SCONN288_ADR50001P003C01  I177
  J32     35  VSS13  SCONN288_ADR50001P003C01  I177
  J32     37  VSS14  SCONN288_ADR50001P003C01  I177
  J32     39  VSS15  SCONN288_ADR50001P003C01  I177
  J32     41  VSS16  SCONN288_ADR50001P003C01  I177
  J32     43  VSS17  SCONN288_ADR50001P003C01  I177
  J32     46  VSS18  SCONN288_ADR50001P003C01  I177
  J32     48  VSS19  SCONN288_ADR50001P003C01  I177
  J32     50  VSS20  SCONN288_ADR50001P003C01  I177
  J32     52  VSS21  SCONN288_ADR50001P003C01  I177
  J32     54  VSS22  SCONN288_ADR50001P003C01  I177
  J32     57  VSS23  SCONN288_ADR50001P003C01  I177
  J32     59  VSS24  SCONN288_ADR50001P003C01  I177
  J32     61  VSS25  SCONN288_ADR50001P003C01  I177
  J32     63  VSS26  SCONN288_ADR50001P003C01  I177
  J32     65  VSS27  SCONN288_ADR50001P003C01  I177
  J32     67  VSS28  SCONN288_ADR50001P003C01  I177
  J32     69  VSS29  SCONN288_ADR50001P003C01  I177
  J32     71  VSS30  SCONN288_ADR50001P003C01  I177
  J32     73  VSS31  SCONN288_ADR50001P003C01  I177
  J32     75  VSS32  SCONN288_ADR50001P003C01  I177
  J32     77  VSS33  SCONN288_ADR50001P003C01  I177
  J32     79  VSS34  SCONN288_ADR50001P003C01  I177
  J32     81  VSS35  SCONN288_ADR50001P003C01  I177
  J32     83  VSS36  SCONN288_ADR50001P003C01  I177
  J32     85  VSS37  SCONN288_ADR50001P003C01  I177
  J32     88  VSS38  SCONN288_ADR50001P003C01  I177
  J32     90  VSS39  SCONN288_ADR50001P003C01  I177
  J32     92  VSS40  SCONN288_ADR50001P003C01  I177
  J32     95  VSS41  SCONN288_ADR50001P003C01  I177
  J32     97  VSS42  SCONN288_ADR50001P003C01  I177
  J32     99  VSS43  SCONN288_ADR50001P003C01  I177
  J32    101  VSS44  SCONN288_ADR50001P003C01  I177
  J32    103  VSS45  SCONN288_ADR50001P003C01  I177
  J32    106  VSS46  SCONN288_ADR50001P003C01  I177
  J32    108  VSS47  SCONN288_ADR50001P003C01  I177
  J32    110  VSS48  SCONN288_ADR50001P003C01  I177
  J32    112  VSS49  SCONN288_ADR50001P003C01  I177
  J32    114  VSS50  SCONN288_ADR50001P003C01  I177
  J32    117  VSS51  SCONN288_ADR50001P003C01  I177
  J32    119  VSS52  SCONN288_ADR50001P003C01  I177
  J32    121  VSS53  SCONN288_ADR50001P003C01  I177
  J32    123  VSS54  SCONN288_ADR50001P003C01  I177
  J32    125  VSS55  SCONN288_ADR50001P003C01  I177
  J32    128  VSS56  SCONN288_ADR50001P003C01  I177
  J32    130  VSS57  SCONN288_ADR50001P003C01  I177
  J32    132  VSS58  SCONN288_ADR50001P003C01  I177
  J32    134  VSS59  SCONN288_ADR50001P003C01  I177
  J32    136  VSS60  SCONN288_ADR50001P003C01  I177
  J32    139  VSS61  SCONN288_ADR50001P003C01  I177
  J32    141  VSS62  SCONN288_ADR50001P003C01  I177
  J32    143  VSS63  SCONN288_ADR50001P003C01  I177
  J32    151  VSS64  SCONN288_ADR50001P003C01  I177
  J32    153  VSS65  SCONN288_ADR50001P003C01  I177
  J32    155  VSS66  SCONN288_ADR50001P003C01  I177
  J32    158  VSS67  SCONN288_ADR50001P003C01  I177
  J32    160  VSS68  SCONN288_ADR50001P003C01  I177
  J32    162  VSS69  SCONN288_ADR50001P003C01  I177
  J32    164  VSS70  SCONN288_ADR50001P003C01  I177
  J32    166  VSS71  SCONN288_ADR50001P003C01  I177
  J32    169  VSS72  SCONN288_ADR50001P003C01  I177
  J32    171  VSS73  SCONN288_ADR50001P003C01  I177
  J32    173  VSS74  SCONN288_ADR50001P003C01  I177
  J32    175  VSS75  SCONN288_ADR50001P003C01  I177
  J32    177  VSS76  SCONN288_ADR50001P003C01  I177
  J32    180  VSS77  SCONN288_ADR50001P003C01  I177
  J32    182  VSS78  SCONN288_ADR50001P003C01  I177
  J32    184  VSS79  SCONN288_ADR50001P003C01  I177
  J32    186  VSS80  SCONN288_ADR50001P003C01  I177
  J32    188  VSS81  SCONN288_ADR50001P003C01  I177
  J32    191  VSS82  SCONN288_ADR50001P003C01  I177
  J32    193  VSS83  SCONN288_ADR50001P003C01  I177
  J32    195  VSS84  SCONN288_ADR50001P003C01  I177
  J32    197  VSS85  SCONN288_ADR50001P003C01  I177
  J32    199  VSS86  SCONN288_ADR50001P003C01  I177
  J32    202  VSS87  SCONN288_ADR50001P003C01  I177
  J32    204  VSS88  SCONN288_ADR50001P003C01  I177
  J32    206  VSS89  SCONN288_ADR50001P003C01  I177
  J32    208  VSS90  SCONN288_ADR50001P003C01  I177
  J32    210  VSS91  SCONN288_ADR50001P003C01  I177
  J32    212  VSS92  SCONN288_ADR50001P003C01  I177
  J32    214  VSS93  SCONN288_ADR50001P003C01  I177
  J32    216  VSS94  SCONN288_ADR50001P003C01  I177
  J32    219  VSS95  SCONN288_ADR50001P003C01  I177
  J32    222  VSS96  SCONN288_ADR50001P003C01  I177
  J32    224  VSS97  SCONN288_ADR50001P003C01  I177
  J32    226  VSS98  SCONN288_ADR50001P003C01  I177
  J32    228  VSS99  SCONN288_ADR50001P003C01  I177
  J32    230  VSS100  SCONN288_ADR50001P003C01  I177
  J32    233  VSS101  SCONN288_ADR50001P003C01  I177
  J32    235  VSS102  SCONN288_ADR50001P003C01  I177
  J32    237  VSS103  SCONN288_ADR50001P003C01  I177
  J32    240  VSS104  SCONN288_ADR50001P003C01  I177
  J32    242  VSS105  SCONN288_ADR50001P003C01  I177
  J32    244  VSS106  SCONN288_ADR50001P003C01  I177
  J32    246  VSS107  SCONN288_ADR50001P003C01  I177
  J32    248  VSS108  SCONN288_ADR50001P003C01  I177
  J32    251  VSS109  SCONN288_ADR50001P003C01  I177
  J32    253  VSS110  SCONN288_ADR50001P003C01  I177
  J32    255  VSS111  SCONN288_ADR50001P003C01  I177
  J32    257  VSS112  SCONN288_ADR50001P003C01  I177
  J32    259  VSS113  SCONN288_ADR50001P003C01  I177
  J32    262  VSS114  SCONN288_ADR50001P003C01  I177
  J32    264  VSS115  SCONN288_ADR50001P003C01  I177
  J32    266  VSS116  SCONN288_ADR50001P003C01  I177
  J32    268  VSS117  SCONN288_ADR50001P003C01  I177
  J32    270  VSS118  SCONN288_ADR50001P003C01  I177
  J32    273  VSS119  SCONN288_ADR50001P003C01  I177
  J32    275  VSS120  SCONN288_ADR50001P003C01  I177
  J32    277  VSS121  SCONN288_ADR50001P003C01  I177
  J32    279  VSS122  SCONN288_ADR50001P003C01  I177
  J32    281  VSS123  SCONN288_ADR50001P003C01  I177
  J32    284  VSS124  SCONN288_ADR50001P003C01  I177
  J32    286  VSS125  SCONN288_ADR50001P003C01  I177
  J32    288  VSS126  SCONN288_ADR50001P003C01  I177
  J32     G1     G1  SCONN288_ADR50001P003C01  I177
  J32     G2     G2  SCONN288_ADR50001P003C01  I177
  J32     G3     G3  SCONN288_ADR50001P003C01  I177
  J33     A1  GNDA1  SCONN84_123318136  I53
  J33     A2  GNDA2  SCONN84_123318136  I53
  J33     A3  GNDA3  SCONN84_123318136  I53
  J33     A4  GNDA4  SCONN84_123318136  I53
  J33     A5  GNDA5  SCONN84_123318136  I53
  J33     A6  GNDA6  SCONN84_123318136  I53
  J33    A13  GNDA13  SCONN84_123318136  I53
  J33    A16  GNDA16  SCONN84_123318136  I53
  J33    A19  GNDA19  SCONN84_123318136  I53
  J33    A22  GNDA22  SCONN84_123318136  I53
  J33    A25  GNDA25  SCONN84_123318136  I53
  J33    A28  GNDA28  SCONN84_123318136  I53
  J33    A29  GNDA29  SCONN84_123318136  I53
  J33    A32  GNDA32  SCONN84_123318136  I53
  J33    A35  GNDA35  SCONN84_123318136  I53
  J33    A38  GNDA38  SCONN84_123318136  I53
  J33    A41  GNDA41  SCONN84_123318136  I53
  J33    B13  GNDB13  SCONN84_123318136  I53
  J33    B16  GNDB16  SCONN84_123318136  I53
  J33    B19  GNDB19  SCONN84_123318136  I53
  J33    B22  GNDB22  SCONN84_123318136  I53
  J33    B25  GNDB25  SCONN84_123318136  I53
  J33    B28  GNDB28  SCONN84_123318136  I53
  J33    B29  GNDB29  SCONN84_123318136  I53
  J33    B32  GNDB32  SCONN84_123318136  I53
  J33    B35  GNDB35  SCONN84_123318136  I53
  J33    B38  GNDB38  SCONN84_123318136  I53
  J33    B41  GNDB41  SCONN84_123318136  I53
  J33     G1     G1  SCONN84_123318136  I53
  J33     G2     G2  SCONN84_123318136  I53
  J33     G3     G3  SCONN84_123318136  I53
  J33     G4     G4  SCONN84_123318136  I53
  J33     G5     G5  SCONN84_123318136  I53
  J34     A1  GNDA1  SCONN84_123318136  I43
  J34     A2  GNDA2  SCONN84_123318136  I43
  J34     A3  GNDA3  SCONN84_123318136  I43
  J34     A4  GNDA4  SCONN84_123318136  I43
  J34     A5  GNDA5  SCONN84_123318136  I43
  J34     A6  GNDA6  SCONN84_123318136  I43
  J34    A13  GNDA13  SCONN84_123318136  I43
  J34    A16  GNDA16  SCONN84_123318136  I43
  J34    A19  GNDA19  SCONN84_123318136  I43
  J34    A22  GNDA22  SCONN84_123318136  I43
  J34    A25  GNDA25  SCONN84_123318136  I43
  J34    A28  GNDA28  SCONN84_123318136  I43
  J34    A29  GNDA29  SCONN84_123318136  I43
  J34    A32  GNDA32  SCONN84_123318136  I43
  J34    A35  GNDA35  SCONN84_123318136  I43
  J34    A38  GNDA38  SCONN84_123318136  I43
  J34    A41  GNDA41  SCONN84_123318136  I43
  J34    B13  GNDB13  SCONN84_123318136  I43
  J34    B16  GNDB16  SCONN84_123318136  I43
  J34    B19  GNDB19  SCONN84_123318136  I43
  J34    B22  GNDB22  SCONN84_123318136  I43
  J34    B25  GNDB25  SCONN84_123318136  I43
  J34    B28  GNDB28  SCONN84_123318136  I43
  J34    B29  GNDB29  SCONN84_123318136  I43
  J34    B32  GNDB32  SCONN84_123318136  I43
  J34    B35  GNDB35  SCONN84_123318136  I43
  J34    B38  GNDB38  SCONN84_123318136  I43
  J34    B41  GNDB41  SCONN84_123318136  I43
  J34     G1     G1  SCONN84_123318136  I43
  J34     G2     G2  SCONN84_123318136  I43
  J34     G3     G3  SCONN84_123318136  I43
  J34     G4     G4  SCONN84_123318136  I43
  J34     G5     G5  SCONN84_123318136  I43
  J35     A2  SIGNAL_A2  SCONN140_G64V3431BHR  I64
  J35     A5  SIGNAL_A5  SCONN140_G64V3431BHR  I64
  J35     A6  SIGNAL_A6  SCONN140_G64V3431BHR  I64
  J35     A7  GND_A7  SCONN140_G64V3431BHR  I64
  J35     A8  SIGNAL_A8  SCONN140_G64V3431BHR  I64
  J35    A10  GND_A10  SCONN140_G64V3431BHR  I64
  J35    A13  GND_A13  SCONN140_G64V3431BHR  I64
  J35    A16  GND_A16  SCONN140_G64V3431BHR  I64
  J35    A19  GND_A19  SCONN140_G64V3431BHR  I64
  J35    A22  GND_A22  SCONN140_G64V3431BHR  I64
  J35    A25  GND_A25  SCONN140_G64V3431BHR  I64
  J35    A28  GND_A28  SCONN140_G64V3431BHR  I64
  J35    A29  GND_A29  SCONN140_G64V3431BHR  I64
  J35    A32  GND_A32  SCONN140_G64V3431BHR  I64
  J35    A35  GND_A35  SCONN140_G64V3431BHR  I64
  J35    A38  GND_A38  SCONN140_G64V3431BHR  I64
  J35    A41  GND_A41  SCONN140_G64V3431BHR  I64
  J35    A43  GND_A43  SCONN140_G64V3431BHR  I64
  J35    A46  GND_A46  SCONN140_G64V3431BHR  I64
  J35    A49  GND_A49  SCONN140_G64V3431BHR  I64
  J35    A52  GND_A52  SCONN140_G64V3431BHR  I64
  J35    A55  GND_A55  SCONN140_G64V3431BHR  I64
  J35    A58  GND_A58  SCONN140_G64V3431BHR  I64
  J35    A61  GND_A61  SCONN140_G64V3431BHR  I64
  J35    A64  GND_A64  SCONN140_G64V3431BHR  I64
  J35    A67  GND_A67  SCONN140_G64V3431BHR  I64
  J35    A70  GND_A70  SCONN140_G64V3431BHR  I64
  J35     B6  SIGNAL_B6  SCONN140_G64V3431BHR  I64
  J35     B7  GND_B7  SCONN140_G64V3431BHR  I64
  J35    B13  GND_B13  SCONN140_G64V3431BHR  I64
  J35    B16  GND_B16  SCONN140_G64V3431BHR  I64
  J35    B19  GND_B19  SCONN140_G64V3431BHR  I64
  J35    B22  GND_B22  SCONN140_G64V3431BHR  I64
  J35    B25  GND_B25  SCONN140_G64V3431BHR  I64
  J35    B28  GND_B28  SCONN140_G64V3431BHR  I64
  J35    B29  GND_B29  SCONN140_G64V3431BHR  I64
  J35    B32  GND_B32  SCONN140_G64V3431BHR  I64
  J35    B35  GND_B35  SCONN140_G64V3431BHR  I64
  J35    B38  GND_B38  SCONN140_G64V3431BHR  I64
  J35    B41  GND_B41  SCONN140_G64V3431BHR  I64
  J35    B43  GND_B43  SCONN140_G64V3431BHR  I64
  J35    B46  GND_B46  SCONN140_G64V3431BHR  I64
  J35    B49  GND_B49  SCONN140_G64V3431BHR  I64
  J35    B52  GND_B52  SCONN140_G64V3431BHR  I64
  J35    B55  GND_B55  SCONN140_G64V3431BHR  I64
  J35    B58  GND_B58  SCONN140_G64V3431BHR  I64
  J35    B61  GND_B61  SCONN140_G64V3431BHR  I64
  J35    B64  GND_B64  SCONN140_G64V3431BHR  I64
  J35    B67  GND_B67  SCONN140_G64V3431BHR  I64
  J35    B70  GND_B70  SCONN140_G64V3431BHR  I64
  J35     G1     G1  SCONN140_G64V3431BHR  I64
  J35     G2     G2  SCONN140_G64V3431BHR  I64
  J35     G3     G3  SCONN140_G64V3431BHR  I64
  J35     G4     G4  SCONN140_G64V3431BHR  I64
  J35     G5     G5  SCONN140_G64V3431BHR  I64
  J35     G6     G6  SCONN140_G64V3431BHR  I64
  J35     G7     G7  SCONN140_G64V3431BHR  I64
  J35     G8     G8  SCONN140_G64V3431BHR  I64
  J37     A1  GND_A1  SCONN168_623403212  I86
  J37     A2  GND_A2  SCONN168_623403212  I86
  J37     A3  GND_A3  SCONN168_623403212  I86
  J37     A4  GND_A4  SCONN168_623403212  I86
  J37     A5  GND_A5  SCONN168_623403212  I86
  J37     A6  GND_A6  SCONN168_623403212  I86
  J37    A13  GND_A13  SCONN168_623403212  I86
  J37    A16  GND_A16  SCONN168_623403212  I86
  J37    A19  GND_A19  SCONN168_623403212  I86
  J37    A22  GND_A22  SCONN168_623403212  I86
  J37    A25  GND_A25  SCONN168_623403212  I86
  J37    A28  GND_A28  SCONN168_623403212  I86
  J37    A29  GND_A29  SCONN168_623403212  I86
  J37    A32  GND_A32  SCONN168_623403212  I86
  J37    A35  GND_A35  SCONN168_623403212  I86
  J37    A38  GND_A38  SCONN168_623403212  I86
  J37    A41  GND_A41  SCONN168_623403212  I86
  J37    A43  GND_A43  SCONN168_623403212  I86
  J37    A46  GND_A46  SCONN168_623403212  I86
  J37    A49  GND_A49  SCONN168_623403212  I86
  J37    A52  GND_A52  SCONN168_623403212  I86
  J37    A55  GND_A55  SCONN168_623403212  I86
  J37    A58  GND_A58  SCONN168_623403212  I86
  J37    A61  GND_A61  SCONN168_623403212  I86
  J37    A64  GND_A64  SCONN168_623403212  I86
  J37    A67  GND_A67  SCONN168_623403212  I86
  J37    B13  GND_B13  SCONN168_623403212  I86
  J37    B16  GND_B16  SCONN168_623403212  I86
  J37    B19  GND_B19  SCONN168_623403212  I86
  J37    B22  GND_B22  SCONN168_623403212  I86
  J37    B25  GND_B25  SCONN168_623403212  I86
  J37    B28  GND_B28  SCONN168_623403212  I86
  J37    B29  GND_B29  SCONN168_623403212  I86
  J37    B32  GND_B32  SCONN168_623403212  I86
  J37    B35  GND_B35  SCONN168_623403212  I86
  J37    B38  GND_B38  SCONN168_623403212  I86
  J37    B41  GND_B41  SCONN168_623403212  I86
  J37    B43  GND_B43  SCONN168_623403212  I86
  J37    B46  GND_B46  SCONN168_623403212  I86
  J37    B49  GND_B49  SCONN168_623403212  I86
  J37    B52  GND_B52  SCONN168_623403212  I86
  J37    B55  GND_B55  SCONN168_623403212  I86
  J37    B58  GND_B58  SCONN168_623403212  I86
  J37    B61  GND_B61  SCONN168_623403212  I86
  J37    B64  GND_B64  SCONN168_623403212  I86
  J37    B67  GND_B67  SCONN168_623403212  I86
  J37    OCP_A10  GND_OCP_A10  SCONN168_623403212  I86
  J37    OCP_A13  GND_OCP_A13  SCONN168_623403212  I86
  J37    OCP_B10  GND_OCP_B10  SCONN168_623403212  I86
  J37    OCP_B13  GND_OCP_B13  SCONN168_623403212  I86
  J41    A11  PERST1#  SCONN168_623403212  I115
  J41    A14  REFCLKN1  SCONN168_623403212  I115
  J41    A17  PERN0  SCONN168_623403212  I115
  J41    A20  PERN1  SCONN168_623403212  I115
  J41    A33  PERN5  SCONN168_623403212  I115
  J41    A42  PRSNTB1#  SCONN168_623403212  I115
  J41    A43  GND_A43  SCONN168_623403212  I115
  J41    A52  GND_A52  SCONN168_623403212  I115
  J41    A55  GND_A55  SCONN168_623403212  I115
  J41    A58  GND_A58  SCONN168_623403212  I115
  J41    A61  GND_A61  SCONN168_623403212  I115
  J41    A64  GND_A64  SCONN168_623403212  I115
  J41    A67  GND_A67  SCONN168_623403212  I115
  J41    A70  PWRBRK#  SCONN168_623403212  I115
  J41    B10  PERST0#  SCONN168_623403212  I115
  J41    B17  PETN0  SCONN168_623403212  I115
  J41    B26  PETN3  SCONN168_623403212  I115
  J41    B33  PETN5  SCONN168_623403212  I115
  J41    B38  GND_B38  SCONN168_623403212  I115
  J41    B49  GND_B49  SCONN168_623403212  I115
  J41    B52  GND_B52  SCONN168_623403212  I115
  J41    B55  GND_B55  SCONN168_623403212  I115
  J41    B58  GND_B58  SCONN168_623403212  I115
  J41    B61  GND_B61  SCONN168_623403212  I115
  J41    B64  GND_B64  SCONN168_623403212  I115
  J41    B67  GND_B67  SCONN168_623403212  I115
  J41    B70  PRSNTB3#  SCONN168_623403212  I115
  J41    OCP_A3  WAKE#  SCONN168_623403212  I115
  J41    OCP_A4  RBT_ARB_IN  SCONN168_623403212  I115
  J41    OCP_A13  GND_OCP_A13  SCONN168_623403212  I115
  J41    OCP_B4  DATA_IN  SCONN168_623403212  I115
  J41    OCP_B7  SLOT_ID0  SCONN168_623403212  I115
  J41    OCP_B10  GND_OCP_B10  SCONN168_623403212  I115
  J42     14     14  SCONN60_QSH03001LDAKTR  I44
  J42     16     16  SCONN60_QSH03001LDAKTR  I44
  J42     57     57  SCONN60_QSH03001LDAKTR  I44
  J42     58     58  SCONN60_QSH03001LDAKTR  I44
  J42     60     60  SCONN60_QSH03001LDAKTR  I44
  J42     G1     G1  SCONN60_QSH03001LDAKTR  I44
  J42     G2     G2  SCONN60_QSH03001LDAKTR  I44
  J42     G3     G3  SCONN60_QSH03001LDAKTR  I44
  J42     G4     G4  SCONN60_QSH03001LDAKTR  I44
  J43      2      2  CONN10_G2100HT0038071  I42
  J43     10     10  CONN10_G2100HT0038071  I42
  J44      4      4  CONN24_52SH90245BRD  I125
  J44      5      5  CONN24_52SH90245BRD  I125
  J44      8      8  CONN24_52SH90245BRD  I125
  J44     12     12  CONN24_52SH90245BRD  I125
  J44     16     16  CONN24_52SH90245BRD  I125
  J44     20     20  CONN24_52SH90245BRD  I125
  J48      4    GND  CONN9_2UB3903013101F  I39
  J48      7  GND_D  CONN9_2UB3903013101F  I39
  J48     G1     G1  CONN9_2UB3903013101F  I39
  J48     G2     G2  CONN9_2UB3903013101F  I39
  J48     G3     G3  CONN9_2UB3903013101F  I39
  J48     G4     G4  CONN9_2UB3903013101F  I39
  J49      1      1  CONN10_10142708102011LF   I2
  J49      2      2  CONN10_10142708102011LF   I2
  J49      3      3  CONN10_10142708102011LF   I2
  J49      4      4  CONN10_10142708102011LF   I2
  J49      5      5  CONN10_10142708102011LF   I2
  J50      1      1  CONN10_10142708102011LF   I4
  J50      2      2  CONN10_10142708102011LF   I4
  J50      3      3  CONN10_10142708102011LF   I4
  J50      4      4  CONN10_10142708102011LF   I4
  J50      5      5  CONN10_10142708102011LF   I4
  J54      1      1  CONN7_ABASAT054KA1   I8
  J54      4      4  CONN7_ABASAT054KA1   I8
  J54      7      7  CONN7_ABASAT054KA1   I8
  J54     G1     G1  CONN7_ABASAT054KA1   I8
  J54     G2     G2  CONN7_ABASAT054KA1   I8
  J55    A13  GND_A13  SCONN140_G64V3431BHR  I150
  J55    A16  GND_A16  SCONN140_G64V3431BHR  I150
  J55    A19  GND_A19  SCONN140_G64V3431BHR  I150
  J55    A22  GND_A22  SCONN140_G64V3431BHR  I150
  J55    A25  GND_A25  SCONN140_G64V3431BHR  I150
  J55    A28  GND_A28  SCONN140_G64V3431BHR  I150
  J55    A29  GND_A29  SCONN140_G64V3431BHR  I150
  J55    A32  GND_A32  SCONN140_G64V3431BHR  I150
  J55    A35  GND_A35  SCONN140_G64V3431BHR  I150
  J55    A38  GND_A38  SCONN140_G64V3431BHR  I150
  J55    A41  GND_A41  SCONN140_G64V3431BHR  I150
  J55    A42  GND_A42  SCONN140_G64V3431BHR  I150
  J55    A43  GND_A43  SCONN140_G64V3431BHR  I150
  J55    A46  GND_A46  SCONN140_G64V3431BHR  I150
  J55    A49  GND_A49  SCONN140_G64V3431BHR  I150
  J55    A52  GND_A52  SCONN140_G64V3431BHR  I150
  J55    A55  GND_A55  SCONN140_G64V3431BHR  I150
  J55    A58  GND_A58  SCONN140_G64V3431BHR  I150
  J55    A61  GND_A61  SCONN140_G64V3431BHR  I150
  J55    A64  GND_A64  SCONN140_G64V3431BHR  I150
  J55    A67  GND_A67  SCONN140_G64V3431BHR  I150
  J55     B5  SIGNAL_B5  SCONN140_G64V3431BHR  I150
  J55     B6  SIGNAL_B6  SCONN140_G64V3431BHR  I150
  J55    B13  GND_B13  SCONN140_G64V3431BHR  I150
  J55    B16  GND_B16  SCONN140_G64V3431BHR  I150
  J55    B19  GND_B19  SCONN140_G64V3431BHR  I150
  J55    B22  GND_B22  SCONN140_G64V3431BHR  I150
  J55    B25  GND_B25  SCONN140_G64V3431BHR  I150
  J55    B28  GND_B28  SCONN140_G64V3431BHR  I150
  J55    B29  GND_B29  SCONN140_G64V3431BHR  I150
  J55    B32  GND_B32  SCONN140_G64V3431BHR  I150
  J55    B35  GND_B35  SCONN140_G64V3431BHR  I150
  J55    B38  GND_B38  SCONN140_G64V3431BHR  I150
  J55    B41  GND_B41  SCONN140_G64V3431BHR  I150
  J55    B43  GND_B43  SCONN140_G64V3431BHR  I150
  J55    B46  GND_B46  SCONN140_G64V3431BHR  I150
  J55    B49  GND_B49  SCONN140_G64V3431BHR  I150
  J55    B52  GND_B52  SCONN140_G64V3431BHR  I150
  J55    B55  GND_B55  SCONN140_G64V3431BHR  I150
  J55    B58  GND_B58  SCONN140_G64V3431BHR  I150
  J55    B61  GND_B61  SCONN140_G64V3431BHR  I150
  J55    B64  GND_B64  SCONN140_G64V3431BHR  I150
  J55    B67  GND_B67  SCONN140_G64V3431BHR  I150
  J55     G1     G1  SCONN140_G64V3431BHR  I150
  J55     G2     G2  SCONN140_G64V3431BHR  I150
  J55     G3     G3  SCONN140_G64V3431BHR  I150
  J55     G4     G4  SCONN140_G64V3431BHR  I150
  J55     G5     G5  SCONN140_G64V3431BHR  I150
  J55     G6     G6  SCONN140_G64V3431BHR  I150
  J55     G7     G7  SCONN140_G64V3431BHR  I150
  J55     G8     G8  SCONN140_G64V3431BHR  I150
  J57    A13  GND_A13  SCONN140_G64V3431BHR  I242
  J57    A16  GND_A16  SCONN140_G64V3431BHR  I242
  J57    A19  GND_A19  SCONN140_G64V3431BHR  I242
  J57    A22  GND_A22  SCONN140_G64V3431BHR  I242
  J57    A25  GND_A25  SCONN140_G64V3431BHR  I242
  J57    A28  GND_A28  SCONN140_G64V3431BHR  I242
  J57    A29  GND_A29  SCONN140_G64V3431BHR  I242
  J57    A32  GND_A32  SCONN140_G64V3431BHR  I242
  J57    A35  GND_A35  SCONN140_G64V3431BHR  I242
  J57    A38  GND_A38  SCONN140_G64V3431BHR  I242
  J57    A41  GND_A41  SCONN140_G64V3431BHR  I242
  J57    A42  GND_A42  SCONN140_G64V3431BHR  I242
  J57    A43  GND_A43  SCONN140_G64V3431BHR  I242
  J57    A46  GND_A46  SCONN140_G64V3431BHR  I242
  J57    A49  GND_A49  SCONN140_G64V3431BHR  I242
  J57    A52  GND_A52  SCONN140_G64V3431BHR  I242
  J57    A55  GND_A55  SCONN140_G64V3431BHR  I242
  J57    A58  GND_A58  SCONN140_G64V3431BHR  I242
  J57    A61  GND_A61  SCONN140_G64V3431BHR  I242
  J57    A64  GND_A64  SCONN140_G64V3431BHR  I242
  J57    A67  GND_A67  SCONN140_G64V3431BHR  I242
  J57     B5  SIGNAL_B5  SCONN140_G64V3431BHR  I242
  J57     B6  SIGNAL_B6  SCONN140_G64V3431BHR  I242
  J57    B13  GND_B13  SCONN140_G64V3431BHR  I242
  J57    B16  GND_B16  SCONN140_G64V3431BHR  I242
  J57    B19  GND_B19  SCONN140_G64V3431BHR  I242
  J57    B22  GND_B22  SCONN140_G64V3431BHR  I242
  J57    B25  GND_B25  SCONN140_G64V3431BHR  I242
  J57    B28  GND_B28  SCONN140_G64V3431BHR  I242
  J57    B29  GND_B29  SCONN140_G64V3431BHR  I242
  J57    B32  GND_B32  SCONN140_G64V3431BHR  I242
  J57    B35  GND_B35  SCONN140_G64V3431BHR  I242
  J57    B38  GND_B38  SCONN140_G64V3431BHR  I242
  J57    B41  GND_B41  SCONN140_G64V3431BHR  I242
  J57    B43  GND_B43  SCONN140_G64V3431BHR  I242
  J57    B46  GND_B46  SCONN140_G64V3431BHR  I242
  J57    B49  GND_B49  SCONN140_G64V3431BHR  I242
  J57    B52  GND_B52  SCONN140_G64V3431BHR  I242
  J57    B55  GND_B55  SCONN140_G64V3431BHR  I242
  J57    B58  GND_B58  SCONN140_G64V3431BHR  I242
  J57    B61  GND_B61  SCONN140_G64V3431BHR  I242
  J57    B64  GND_B64  SCONN140_G64V3431BHR  I242
  J57    B67  GND_B67  SCONN140_G64V3431BHR  I242
  J57     G1     G1  SCONN140_G64V3431BHR  I242
  J57     G2     G2  SCONN140_G64V3431BHR  I242
  J57     G3     G3  SCONN140_G64V3431BHR  I242
  J57     G4     G4  SCONN140_G64V3431BHR  I242
  J57     G5     G5  SCONN140_G64V3431BHR  I242
  J57     G6     G6  SCONN140_G64V3431BHR  I242
  J57     G7     G7  SCONN140_G64V3431BHR  I242
  J57     G8     G8  SCONN140_G64V3431BHR  I242
  J59      3   GND2  SCONN75K_APCI0155P004A  I178
  J59      9   GND3  SCONN75K_APCI0155P004A  I178
  J59     15   GND4  SCONN75K_APCI0155P004A  I178
  J59     21   GND5  SCONN75K_APCI0155P004A  I178
  J59     27   GND6  SCONN75K_APCI0155P004A  I178
  J59     33   GND7  SCONN75K_APCI0155P004A  I178
  J59     39   GND8  SCONN75K_APCI0155P004A  I178
  J59     45   GND9  SCONN75K_APCI0155P004A  I178
  J59     51  GND10  SCONN75K_APCI0155P004A  I178
  J59     57  GND11  SCONN75K_APCI0155P004A  I178
  J59     71  GND12  SCONN75K_APCI0155P004A  I178
  J59     73  GND13  SCONN75K_APCI0155P004A  I178
  J59     75  GND14  SCONN75K_APCI0155P004A  I178
  J59     G1     G1  SCONN75K_APCI0155P004A  I178
  J59     G2     G2  SCONN75K_APCI0155P004A  I178
  J61     A1  GNDA1  SCONN84_123318136  I49
  J61     A2  GNDA2  SCONN84_123318136  I49
  J61     A3  GNDA3  SCONN84_123318136  I49
  J61     A4  GNDA4  SCONN84_123318136  I49
  J61     A5  GNDA5  SCONN84_123318136  I49
  J61     A6  GNDA6  SCONN84_123318136  I49
  J61    A13  GNDA13  SCONN84_123318136  I49
  J61    A16  GNDA16  SCONN84_123318136  I49
  J61    A19  GNDA19  SCONN84_123318136  I49
  J61    A22  GNDA22  SCONN84_123318136  I49
  J61    A25  GNDA25  SCONN84_123318136  I49
  J61    A28  GNDA28  SCONN84_123318136  I49
  J61    A29  GNDA29  SCONN84_123318136  I49
  J61    A32  GNDA32  SCONN84_123318136  I49
  J61    A35  GNDA35  SCONN84_123318136  I49
  J61    A38  GNDA38  SCONN84_123318136  I49
  J61    A41  GNDA41  SCONN84_123318136  I49
  J61    B13  GNDB13  SCONN84_123318136  I49
  J61    B16  GNDB16  SCONN84_123318136  I49
  J61    B19  GNDB19  SCONN84_123318136  I49
  J61    B22  GNDB22  SCONN84_123318136  I49
  J61    B25  GNDB25  SCONN84_123318136  I49
  J61    B28  GNDB28  SCONN84_123318136  I49
  J61    B29  GNDB29  SCONN84_123318136  I49
  J61    B32  GNDB32  SCONN84_123318136  I49
  J61    B35  GNDB35  SCONN84_123318136  I49
  J61    B38  GNDB38  SCONN84_123318136  I49
  J61    B41  GNDB41  SCONN84_123318136  I49
  J61     G1     G1  SCONN84_123318136  I49
  J61     G2     G2  SCONN84_123318136  I49
  J61     G3     G3  SCONN84_123318136  I49
  J61     G4     G4  SCONN84_123318136  I49
  J61     G5     G5  SCONN84_123318136  I49
  J62     A1  GNDA1  SCONN84_123318136  I33
  J62     A2  GNDA2  SCONN84_123318136  I33
  J62     A3  GNDA3  SCONN84_123318136  I33
  J62     A4  GNDA4  SCONN84_123318136  I33
  J62     A5  GNDA5  SCONN84_123318136  I33
  J62     A6  GNDA6  SCONN84_123318136  I33
  J62    A13  GNDA13  SCONN84_123318136  I33
  J62    A16  GNDA16  SCONN84_123318136  I33
  J62    A19  GNDA19  SCONN84_123318136  I33
  J62    A22  GNDA22  SCONN84_123318136  I33
  J62    A25  GNDA25  SCONN84_123318136  I33
  J62    A28  GNDA28  SCONN84_123318136  I33
  J62    A29  GNDA29  SCONN84_123318136  I33
  J62    A32  GNDA32  SCONN84_123318136  I33
  J62    A35  GNDA35  SCONN84_123318136  I33
  J62    A38  GNDA38  SCONN84_123318136  I33
  J62    A41  GNDA41  SCONN84_123318136  I33
  J62    B13  GNDB13  SCONN84_123318136  I33
  J62    B16  GNDB16  SCONN84_123318136  I33
  J62    B19  GNDB19  SCONN84_123318136  I33
  J62    B22  GNDB22  SCONN84_123318136  I33
  J62    B25  GNDB25  SCONN84_123318136  I33
  J62    B28  GNDB28  SCONN84_123318136  I33
  J62    B29  GNDB29  SCONN84_123318136  I33
  J62    B32  GNDB32  SCONN84_123318136  I33
  J62    B35  GNDB35  SCONN84_123318136  I33
  J62    B38  GNDB38  SCONN84_123318136  I33
  J62    B41  GNDB41  SCONN84_123318136  I33
  J62     G1     G1  SCONN84_123318136  I33
  J62     G2     G2  SCONN84_123318136  I33
  J62     G3     G3  SCONN84_123318136  I33
  J62     G4     G4  SCONN84_123318136  I33
  J62     G5     G5  SCONN84_123318136  I33
  J87     A1  GNDA1  SCONN84_123318136  I43
  J87     A2  GNDA2  SCONN84_123318136  I43
  J87     A3  GNDA3  SCONN84_123318136  I43
  J87     A4  GNDA4  SCONN84_123318136  I43
  J87     A5  GNDA5  SCONN84_123318136  I43
  J87     A6  GNDA6  SCONN84_123318136  I43
  J87    A13  GNDA13  SCONN84_123318136  I43
  J87    A16  GNDA16  SCONN84_123318136  I43
  J87    A19  GNDA19  SCONN84_123318136  I43
  J87    A22  GNDA22  SCONN84_123318136  I43
  J87    A25  GNDA25  SCONN84_123318136  I43
  J87    A28  GNDA28  SCONN84_123318136  I43
  J87    A29  GNDA29  SCONN84_123318136  I43
  J87    A32  GNDA32  SCONN84_123318136  I43
  J87    A35  GNDA35  SCONN84_123318136  I43
  J87    A38  GNDA38  SCONN84_123318136  I43
  J87    A41  GNDA41  SCONN84_123318136  I43
  J87    B13  GNDB13  SCONN84_123318136  I43
  J87    B16  GNDB16  SCONN84_123318136  I43
  J87    B19  GNDB19  SCONN84_123318136  I43
  J87    B22  GNDB22  SCONN84_123318136  I43
  J87    B25  GNDB25  SCONN84_123318136  I43
  J87    B28  GNDB28  SCONN84_123318136  I43
  J87    B29  GNDB29  SCONN84_123318136  I43
  J87    B32  GNDB32  SCONN84_123318136  I43
  J87    B35  GNDB35  SCONN84_123318136  I43
  J87    B38  GNDB38  SCONN84_123318136  I43
  J87    B41  GNDB41  SCONN84_123318136  I43
  J87     G1     G1  SCONN84_123318136  I43
  J87     G2     G2  SCONN84_123318136  I43
  J87     G3     G3  SCONN84_123318136  I43
  J87     G4     G4  SCONN84_123318136  I43
  J87     G5     G5  SCONN84_123318136  I43
  J88     A1  GNDA1  SCONN84_123318136  I16
  J88     A2  GNDA2  SCONN84_123318136  I16
  J88     A3  GNDA3  SCONN84_123318136  I16
  J88     A4  GNDA4  SCONN84_123318136  I16
  J88     A5  GNDA5  SCONN84_123318136  I16
  J88     A6  GNDA6  SCONN84_123318136  I16
  J88    A13  GNDA13  SCONN84_123318136  I16
  J88    A16  GNDA16  SCONN84_123318136  I16
  J88    A19  GNDA19  SCONN84_123318136  I16
  J88    A22  GNDA22  SCONN84_123318136  I16
  J88    A25  GNDA25  SCONN84_123318136  I16
  J88    A28  GNDA28  SCONN84_123318136  I16
  J88    A29  GNDA29  SCONN84_123318136  I16
  J88    A32  GNDA32  SCONN84_123318136  I16
  J88    A35  GNDA35  SCONN84_123318136  I16
  J88    A38  GNDA38  SCONN84_123318136  I16
  J88    A41  GNDA41  SCONN84_123318136  I16
  J88    B13  GNDB13  SCONN84_123318136  I16
  J88    B16  GNDB16  SCONN84_123318136  I16
  J88    B19  GNDB19  SCONN84_123318136  I16
  J88    B22  GNDB22  SCONN84_123318136  I16
  J88    B25  GNDB25  SCONN84_123318136  I16
  J88    B28  GNDB28  SCONN84_123318136  I16
  J88    B29  GNDB29  SCONN84_123318136  I16
  J88    B32  GNDB32  SCONN84_123318136  I16
  J88    B35  GNDB35  SCONN84_123318136  I16
  J88    B38  GNDB38  SCONN84_123318136  I16
  J88    B41  GNDB41  SCONN84_123318136  I16
  J88     G1     G1  SCONN84_123318136  I16
  J88     G2     G2  SCONN84_123318136  I16
  J88     G3     G3  SCONN84_123318136  I16
  J88     G4     G4  SCONN84_123318136  I16
  J88     G5     G5  SCONN84_123318136  I16
  J89     A8     A8  SCONN280_ME1028040102011  I239
  J89     A9     A9  SCONN280_ME1028040102011  I239
  J89    A10    A10  SCONN280_ME1028040102011  I239
  J89    A11    A11  SCONN280_ME1028040102011  I239
  J89    A12    A12  SCONN280_ME1028040102011  I239
  J89    A13    A13  SCONN280_ME1028040102011  I239
  J89    A14    A14  SCONN280_ME1028040102011  I239
  J89    A15    A15  SCONN280_ME1028040102011  I239
  J89    A16    A16  SCONN280_ME1028040102011  I239
  J89    A17    A17  SCONN280_ME1028040102011  I239
  J89    A18    A18  SCONN280_ME1028040102011  I239
  J89    A19    A19  SCONN280_ME1028040102011  I239
  J89    A28    A28  SCONN280_ME1028040102011  I239
  J89    A29    A29  SCONN280_ME1028040102011  I239
  J89    A32    A32  SCONN280_ME1028040102011  I239
  J89    A35    A35  SCONN280_ME1028040102011  I239
  J89    A38    A38  SCONN280_ME1028040102011  I239
  J89    A41    A41  SCONN280_ME1028040102011  I239
  J89    A44    A44  SCONN280_ME1028040102011  I239
  J89    A47    A47  SCONN280_ME1028040102011  I239
  J89    A50    A50  SCONN280_ME1028040102011  I239
  J89    A53    A53  SCONN280_ME1028040102011  I239
  J89    A56    A56  SCONN280_ME1028040102011  I239
  J89    A57    A57  SCONN280_ME1028040102011  I239
  J89    A60    A60  SCONN280_ME1028040102011  I239
  J89    A63    A63  SCONN280_ME1028040102011  I239
  J89    A66    A66  SCONN280_ME1028040102011  I239
  J89    A69    A69  SCONN280_ME1028040102011  I239
  J89    A72    A72  SCONN280_ME1028040102011  I239
  J89    A75    A75  SCONN280_ME1028040102011  I239
  J89    A78    A78  SCONN280_ME1028040102011  I239
  J89    A81    A81  SCONN280_ME1028040102011  I239
  J89    A84    A84  SCONN280_ME1028040102011  I239
  J89    A85    A85  SCONN280_ME1028040102011  I282
  J89    A88    A88  SCONN280_ME1028040102011  I282
  J89    A91    A91  SCONN280_ME1028040102011  I282
  J89    A94    A94  SCONN280_ME1028040102011  I282
  J89    A97    A97  SCONN280_ME1028040102011  I282
  J89    A100   A100  SCONN280_ME1028040102011  I282
  J89    A103   A103  SCONN280_ME1028040102011  I282
  J89    A106   A106  SCONN280_ME1028040102011  I282
  J89    A109   A109  SCONN280_ME1028040102011  I282
  J89    A112   A112  SCONN280_ME1028040102011  I282
  J89    A113   A113  SCONN280_ME1028040102011  I282
  J89    A116   A116  SCONN280_ME1028040102011  I282
  J89    A119   A119  SCONN280_ME1028040102011  I282
  J89    A122   A122  SCONN280_ME1028040102011  I282
  J89    A125   A125  SCONN280_ME1028040102011  I282
  J89    A128   A128  SCONN280_ME1028040102011  I282
  J89    A131   A131  SCONN280_ME1028040102011  I282
  J89    A134   A134  SCONN280_ME1028040102011  I282
  J89    A135   A135  SCONN280_ME1028040102011  I282
  J89    A136   A136  SCONN280_ME1028040102011  I282
  J89    A137   A137  SCONN280_ME1028040102011  I282
  J89    A138   A138  SCONN280_ME1028040102011  I282
  J89    A139   A139  SCONN280_ME1028040102011  I282
  J89     B8     B8  SCONN280_ME1028040102011  I239
  J89     B9     B9  SCONN280_ME1028040102011  I239
  J89    B10    B10  SCONN280_ME1028040102011  I239
  J89    B11    B11  SCONN280_ME1028040102011  I239
  J89    B12    B12  SCONN280_ME1028040102011  I239
  J89    B19    B19  SCONN280_ME1028040102011  I239
  J89    B23    B23  SCONN280_ME1028040102011  I239
  J89    B26    B26  SCONN280_ME1028040102011  I239
  J89    B29    B29  SCONN280_ME1028040102011  I239
  J89    B32    B32  SCONN280_ME1028040102011  I239
  J89    B35    B35  SCONN280_ME1028040102011  I239
  J89    B38    B38  SCONN280_ME1028040102011  I239
  J89    B41    B41  SCONN280_ME1028040102011  I239
  J89    B44    B44  SCONN280_ME1028040102011  I239
  J89    B47    B47  SCONN280_ME1028040102011  I239
  J89    B50    B50  SCONN280_ME1028040102011  I239
  J89    B53    B53  SCONN280_ME1028040102011  I239
  J89    B56    B56  SCONN280_ME1028040102011  I239
  J89    B57    B57  SCONN280_ME1028040102011  I239
  J89    B60    B60  SCONN280_ME1028040102011  I239
  J89    B63    B63  SCONN280_ME1028040102011  I239
  J89    B66    B66  SCONN280_ME1028040102011  I239
  J89    B69    B69  SCONN280_ME1028040102011  I239
  J89    B72    B72  SCONN280_ME1028040102011  I239
  J89    B75    B75  SCONN280_ME1028040102011  I239
  J89    B78    B78  SCONN280_ME1028040102011  I239
  J89    B81    B81  SCONN280_ME1028040102011  I239
  J89    B84    B84  SCONN280_ME1028040102011  I239
  J89    B85    B85  SCONN280_ME1028040102011  I282
  J89    B88    B88  SCONN280_ME1028040102011  I282
  J89    B91    B91  SCONN280_ME1028040102011  I282
  J89    B94    B94  SCONN280_ME1028040102011  I282
  J89    B97    B97  SCONN280_ME1028040102011  I282
  J89    B100   B100  SCONN280_ME1028040102011  I282
  J89    B103   B103  SCONN280_ME1028040102011  I282
  J89    B106   B106  SCONN280_ME1028040102011  I282
  J89    B109   B109  SCONN280_ME1028040102011  I282
  J89    B112   B112  SCONN280_ME1028040102011  I282
  J89    B113   B113  SCONN280_ME1028040102011  I282
  J89    B116   B116  SCONN280_ME1028040102011  I282
  J89    B119   B119  SCONN280_ME1028040102011  I282
  J89    B122   B122  SCONN280_ME1028040102011  I282
  J89    B125   B125  SCONN280_ME1028040102011  I282
  J89    B128   B128  SCONN280_ME1028040102011  I282
  J89    B131   B131  SCONN280_ME1028040102011  I282
  J89    B134   B134  SCONN280_ME1028040102011  I282
  J89     G1     G1  SCONN280_ME1028040102011  I282
  J89     G2     G2  SCONN280_ME1028040102011  I282
  J89     G3     G3  SCONN280_ME1028040102011  I282
  J89     G4     G4  SCONN280_ME1028040102011  I282
  J90     A1  GND_A1  CONN56_ME2005602311011  I105
  J90     A2  GND_A2  CONN56_ME2005602311011  I105
  J90     A3  GND_A3  CONN56_ME2005602311011  I105
  J90     A4  GND_A4  CONN56_ME2005602311011  I105
  J90     A5  GND_A5  CONN56_ME2005602311011  I105
  J90     A6  GND_A6  CONN56_ME2005602311011  I105
  J90    A13  GND_A13  CONN56_ME2005602311011  I105
  J90    A16  GND_A16  CONN56_ME2005602311011  I105
  J90    A19  GND_A19  CONN56_ME2005602311011  I105
  J90    A22  GND_A22  CONN56_ME2005602311011  I105
  J90    A25  GND_A25  CONN56_ME2005602311011  I105
  J90    A28  GND_A28  CONN56_ME2005602311011  I105
  J90    B13  GND_B13  CONN56_ME2005602311011  I105
  J90    B16  GND_B16  CONN56_ME2005602311011  I105
  J90    B19  GND_B19  CONN56_ME2005602311011  I105
  J90    B22  GND_B22  CONN56_ME2005602311011  I105
  J90    B25  GND_B25  CONN56_ME2005602311011  I105
  J90    B28  GND_B28  CONN56_ME2005602311011  I105
  J91     A1  GND_A1  CONN56_ME2005602311011  I123
  J91     A2  GND_A2  CONN56_ME2005602311011  I123
  J91     A3  GND_A3  CONN56_ME2005602311011  I123
  J91     A4  GND_A4  CONN56_ME2005602311011  I123
  J91     A5  GND_A5  CONN56_ME2005602311011  I123
  J91     A6  GND_A6  CONN56_ME2005602311011  I123
  J91    A13  GND_A13  CONN56_ME2005602311011  I123
  J91    A16  GND_A16  CONN56_ME2005602311011  I123
  J91    A19  GND_A19  CONN56_ME2005602311011  I123
  J91    A22  GND_A22  CONN56_ME2005602311011  I123
  J91    A25  GND_A25  CONN56_ME2005602311011  I123
  J91    A28  GND_A28  CONN56_ME2005602311011  I123
  J91    B13  GND_B13  CONN56_ME2005602311011  I123
  J91    B16  GND_B16  CONN56_ME2005602311011  I123
  J91    B19  GND_B19  CONN56_ME2005602311011  I123
  J91    B22  GND_B22  CONN56_ME2005602311011  I123
  J91    B25  GND_B25  CONN56_ME2005602311011  I123
  J91    B28  GND_B28  CONN56_ME2005602311011  I123
  J92     A1  GND_A1  CONN56_ME2005602311011  I105
  J92     A2  GND_A2  CONN56_ME2005602311011  I105
  J92     A3  GND_A3  CONN56_ME2005602311011  I105
  J92     A4  GND_A4  CONN56_ME2005602311011  I105
  J92     A5  GND_A5  CONN56_ME2005602311011  I105
  J92     A6  GND_A6  CONN56_ME2005602311011  I105
  J92    A13  GND_A13  CONN56_ME2005602311011  I105
  J92    A16  GND_A16  CONN56_ME2005602311011  I105
  J92    A19  GND_A19  CONN56_ME2005602311011  I105
  J92    A22  GND_A22  CONN56_ME2005602311011  I105
  J92    A25  GND_A25  CONN56_ME2005602311011  I105
  J92    A28  GND_A28  CONN56_ME2005602311011  I105
  J92    B13  GND_B13  CONN56_ME2005602311011  I105
  J92    B16  GND_B16  CONN56_ME2005602311011  I105
  J92    B19  GND_B19  CONN56_ME2005602311011  I105
  J92    B22  GND_B22  CONN56_ME2005602311011  I105
  J92    B25  GND_B25  CONN56_ME2005602311011  I105
  J92    B28  GND_B28  CONN56_ME2005602311011  I105
  J93     A1  GND_A1  CONN56_ME2005602311011  I123
  J93     A2  GND_A2  CONN56_ME2005602311011  I123
  J93     A3  GND_A3  CONN56_ME2005602311011  I123
  J93     A4  GND_A4  CONN56_ME2005602311011  I123
  J93     A5  GND_A5  CONN56_ME2005602311011  I123
  J93     A6  GND_A6  CONN56_ME2005602311011  I123
  J93    A13  GND_A13  CONN56_ME2005602311011  I123
  J93    A16  GND_A16  CONN56_ME2005602311011  I123
  J93    A19  GND_A19  CONN56_ME2005602311011  I123
  J93    A22  GND_A22  CONN56_ME2005602311011  I123
  J93    A25  GND_A25  CONN56_ME2005602311011  I123
  J93    A28  GND_A28  CONN56_ME2005602311011  I123
  J93    B13  GND_B13  CONN56_ME2005602311011  I123
  J93    B16  GND_B16  CONN56_ME2005602311011  I123
  J93    B19  GND_B19  CONN56_ME2005602311011  I123
  J93    B22  GND_B22  CONN56_ME2005602311011  I123
  J93    B25  GND_B25  CONN56_ME2005602311011  I123
  J93    B28  GND_B28  CONN56_ME2005602311011  I123
  JP1      1      1  CONN3_210HP1030BR1  I123
  JP5      2      2  CONN3_HFK1030G000LAF  I58
  JP7      2      2  CONN3_210HP1030BR1  I64
  JP8      1      1  CONN3_HFK1030G000LAF  I86
  OSC1     2    GND  OSC4_SIT1602AI2233E50000000D  I58
  OSC2     2    GND  Q_OSC4P     I132
  PC16     2      B  Q_CAPP      I130
  PC113    2      B  Q_CAP        I8
  PC117    2      B  Q_CAPP      I14
  PC175    2      B  Q_CAP       I10
  PC176    2      B  Q_CAP       I18
  PC177    2      B  Q_CAP       I31
  PC179    2      B  Q_CAP       I35
  PC180    2      B  Q_CAP       I32
  PC181    2      B  Q_CAP       I22
  PC184    2      B  Q_CAP       I24
  PC186    2      B  Q_CAP       I25
  PC187    2      B  Q_CAP       I174
  PC188    2      B  Q_CAP       I153
  PC189    2      B  Q_CAPP      I54
  PC207    2      B  Q_CAPP      I213
  PC208    2      B  Q_CAPP      I214
  PC214    2      B  Q_CAP       I35
  PC217    2      B  Q_CAP       I65
  PC218    2      B  Q_CAP       I69
  PC219    2      B  Q_CAP       I37
  PC220    2      B  Q_CAP       I38
  PC221    2      B  Q_CAP       I49
  PC222    2      B  Q_CAP       I55
  PC223    2      B  Q_CAP       I88
  PC224    2      B  Q_CAP       I87
  PC225    2      B  Q_CAP       I92
  PC226    2      B  Q_CAP        I9
  PC227    2      B  Q_CAP       I25
  PC1171    2      B  Q_CAP       I20
  PC1172    2      B  Q_CAP        I9
  PC1173    2      B  Q_CAP       I117
  PC1173_P0_3    2      B  Q_CAP       I43
  PC1174_P0_4    2      B  Q_CAP       I31
  PC1175_P0_3    2      B  Q_CAP       I44
  PC1176_P0_4    2      B  Q_CAP       I32
  PC1179_P0_3    2      B  Q_CAP       I46
  PC1180_P0_4    2      B  Q_CAP       I34
  PC1181_P0_3    2      B  Q_CAP       I50
  PC1182_P0_4    2      B  Q_CAP       I35
  PC1183    2      B  Q_CAPP      I56
  PC1183_P0_3    2      B  Q_CAP       I65
  PC1183_P0_4    2      B  Q_CAP       I53
  PC1185    2      B  Q_CAPP      I57
  PC1185_P0_3    2      B  Q_CAP       I67
  PC1186    2      B  Q_CAPP      I60
  PC1186_P0_4    2      B  Q_CAP       I54
  PC1187    2      B  Q_CAPP      I61
  PC1187_P0_3    2      B  Q_CAP       I68
  PC1188_P0_4    2      B  Q_CAP       I55
  PC1189    2      B  Q_CAPP      I73
  PC1191    2      B  Q_CAP       I20
  PC1192    2      B  Q_CAP        I9
  PC1193    2      B  Q_CAP       I81
  PC1193_P1_3    2      B  Q_CAP       I44
  PC1194    2      B  Q_CAP       I255
  PC1194_P1_4    2      B  Q_CAP       I33
  PC1195_P1_3    2      B  Q_CAP       I45
  PC1196    2      B  Q_CAP       I64
  PC1196_P1_4    2      B  Q_CAP       I35
  PC1199_P1_3    2      B  Q_CAP       I46
  PC1200_P1_4    2      B  Q_CAP       I36
  PC1201    2      B  Q_CAPP      I55
  PC1201_P1_3    2      B  Q_CAP       I51
  PC1202_P1_4    2      B  Q_CAP       I37
  PC1203    2      B  Q_CAPP      I56
  PC1203_P1_4    2      B  Q_CAP       I80
  PC1204    2      B  Q_CAPP      I59
  PC1204_P1_3    2      B  Q_CAP       I66
  PC1205    2      B  Q_CAPP      I61
  PC1206    2      B  Q_CAP       I188
  PC1206_P1_3    2      B  Q_CAP       I67
  PC1207    2      B  Q_CAP       I196
  PC1207_P1_4    2      B  Q_CAP       I75
  PC1208_P1_3    2      B  Q_CAP       I68
  PC1209_P1_4    2      B  Q_CAP       I54
  PC1210    2      B  Q_CAPP      I73
  PC1211_P0_1    2      B  Q_CAP       I48
  PC1212_P0_2    2      B  Q_CAP       I33
  PC1213_P0_3    2      B  Q_CAP       I42
  PC1214_P0_4    2      B  Q_CAP       I26
  PC1215    2      B  Q_CAPP       I5
  PC1216    2      B  Q_CAP       I24
  PC1217    2      B  Q_CAP       I28
  PC1218    2      B  Q_CAP       I32
  PC1219    2      B  Q_CAP       I33
  PC1224    2      B  Q_CAP       I45
  PC1225    2      B  Q_CAP       I47
  PC1226    2      B  Q_CAP       I48
  PC1227    2      B  Q_CAPP      I16
  PC1229    2      B  Q_CAPP      I52
  PC1230    2      B  Q_CAPP      I18
  PC1232    2      B  Q_CAP       I28
  PC1233    2      B  Q_CAP       I30
  PC1234    2      B  Q_CAP       I31
  PC1236    2      B  Q_CAP       I23
  PC1237    2      B  Q_CAP       I25
  PC1238    2      B  Q_CAP       I37
  PC1239    2      B  Q_CAP       I38
  PC1240    2      B  Q_CAP       I39
  PC1241    2      B  Q_CAP       I41
  PC1242_P1_1    2      B  Q_CAP       I234
  PC1243_P1_2    2      B  Q_CAP       I217
  PC1244_P1_3    2      B  Q_CAP       I42
  PC1245_P1_4    2      B  Q_CAP       I26
  PC1247    2      B  Q_CAP       I10
  PC1248    2      B  Q_CAP       I17
  PC1249    2      B  Q_CAP       I18
  PC1254    2      B  Q_CAP       I34
  PC1255    2      B  Q_CAP       I37
  PC1256    2      B  Q_CAP       I38
  PC1257    2      B  Q_CAP       I39
  PC1258    2      B  Q_CAPP      I42
  PC1259    2      B  Q_CAP        I4
  PC1260    2      B  Q_CAP       I19
  PC1261    2      B  Q_CAP       I20
  PC1262    2      B  Q_CAP       I21
  PC1267    2      B  Q_CAP       I30
  PC1268    2      B  Q_CAP       I31
  PC1269    2      B  Q_CAP       I32
  PC1270    2      B  Q_CAP       I35
  PC1271    2      B  Q_CAP       I56
  PC1272    2      B  Q_CAP       I164
  PC1273    2      B  Q_CAP       I165
  PC1274    2      B  Q_CAP       I166
  PC1276    2      B  Q_CAP       I183
  PC1277    2      B  Q_CAP       I184
  PC1278    2      B  Q_CAP       I185
  PC1279    2      B  Q_CAP       I186
  PC1280    2      B  Q_CAP       I169
  PC1281    2      B  Q_CAP       I170
  PC1282    2      B  Q_CAP       I175
  PC1284    2      B  Q_CAP       I184
  PC1285    2      B  Q_CAP       I192
  PC1286    2      B  Q_CAP       I193
  PC1287    2      B  Q_CAP       I194
  PC1289    2      B  Q_CAP       I256
  PC1292    2      B  Q_CAP       I68
  PC1336    2      B  Q_CAP       I210
  PC1337    2      B  Q_CAP       I215
  PC1338    1      A  Q_CAP       I10
  PC1339    1      A  Q_CAP       I30
  PC1340    1      A  Q_CAP       I13
  PC1341    1      A  Q_CAP       I29
  PC1342    1      A  Q_CAP        I8
  PC1343    1      A  Q_CAP       I27
  PC1344    1      A  Q_CAP       I16
  PC1345    1      A  Q_CAP       I28
  PC1346    1      A  Q_CAP       I152
  PC1347    1      A  Q_CAP       I163
  PC1348    1      A  Q_CAP        I7
  PC1349    1      A  Q_CAP       I46
  PC1350    1      A  Q_CAP       I29
  PC1351    1      A  Q_CAP       I39
  PC1352    1      A  Q_CAP       I23
  PC1354    1      A  Q_CAP       I330
  PC1355    1      A  Q_CAP       I10
  PC1356    1      A  Q_CAP       I33
  PC1358    1      A  Q_CAP        I8
  PC1359    1      A  Q_CAP       I23
  PC1360    1      A  Q_CAP       I28
  PC1361    1      A  Q_CAP       I31
  PC1362    1      A  Q_CAP        I8
  PC1363    1      A  Q_CAP       I31
  PC1364    1      A  Q_CAP       I24
  PC1365    1      A  Q_CAP       I11
  PC1366    1      A  Q_CAP        I8
  PC1367    1      A  Q_CAP       I231
  PC1368    1      A  Q_CAP       I209
  PC1369    1      A  Q_CAP       I40
  PC1370    1      A  Q_CAP       I23
  PC1371    1      A  Q_CAP        I8
  PC1372    2      B  Q_CAP       I90
  PC1573    2      B  Q_CAPP      I201
  PC1574    2      B  Q_CAPP      I199
  PC1575    2      B  Q_CAPP      I202
  PC1576    2      B  Q_CAPP      I200
  PC1579    2      B  Q_CAPP      I215
  PC1588    2      B  Q_CAPP      I48
  PC1593    2      B  Q_CAPP      I47
  PC1594    2      B  Q_CAPP      I68
  PC1595    2      B  Q_CAPP      I67
  PC1596    2      B  Q_CAPP      I69
  PC1642    2      B  Q_CAP        I4
  PC1644    2      B  Q_CAPP      I349
  PC1645    2      B  Q_CAPP      I350
  PC1771    2      B  Q_CAPP      I36
  PC1845    2      B  Q_CAPP      I33
  PC1846    2      B  Q_CAP       I18
  PC1848    2      B  Q_CAP        I8
  PC1849    2      B  Q_CAP       I12
  PC1850    2      B  Q_CAP       I14
  PC1852    2      B  Q_CAP       I37
  PC1853    2      B  Q_CAP       I22
  PC1855    2      B  Q_CAP       I34
  PC1856    2      B  Q_CAP       I35
  PC1866    2      B  Q_CAPP      I38
  PC1867    2      B  Q_CAPP      I39
  PC1868    2      B  Q_CAP       I40
  PC1869    2      B  Q_CAP       I45
  PC1870    2      B  Q_CAP       I10
  PC1898    2      B  Q_CAP       I17
  PC189_P0_1    2      B  Q_CAP       I178
  PC1900    2      B  Q_CAPP      I28
  PC190_P0_2    2      B  Q_CAP       I167
  PC1910    2      B  Q_CAPP      I348
  PC191_P0_1    2      B  Q_CAP       I179
  PC1920    2      B  Q_CAPP      I54
  PC192_P0_2    2      B  Q_CAP       I168
  PC1930    2      B  Q_CAPP      I33
  PC1940    2      B  Q_CAPP      I37
  PC195_P0_1    2      B  Q_CAP       I204
  PC196_P0_2    2      B  Q_CAP       I186
  PC197_P0_1    2      B  Q_CAP       I206
  PC198_P0_2    2      B  Q_CAP       I187
  PC1990    2      B  Q_CAPP      I53
  PC199_P0_1    2      B  Q_CAP       I191
  PC2000    2      B  Q_CAP       I35
  PC2001    2      B  Q_CAP       I48
  PC2002    2      B  Q_CAP       I47
  PC202_P0_1    2      B  Q_CAP       I192
  PC203_P0_2    2      B  Q_CAP       I194
  PC204_P0_1    2      B  Q_CAP       I197
  PC205_P0_2    2      B  Q_CAP       I195
  PC2170    2      B  Q_CAPP      I63
  PC2171    2      B  Q_CAPP      I272
  PC2172    2      B  Q_CAPP      I63
  PC2180    2      B  Q_CAPP      I27
  PC2199    2      B  Q_CAPP      I32
  PC2221    2      B  Q_CAP       I159
  PC2222    2      B  Q_CAP       I174
  PC2287    2      B  Q_CAP       I36
  PC228_P0_8    2      B  Q_CAP       I19
  PC229_P0_7    2      B  Q_CAP       I30
  PC230_P0_8    2      B  Q_CAP       I36
  PC231_P0_7    2      B  Q_CAP       I50
  PC232_P0_8    2      B  Q_CAP       I37
  PC2336    2      B  Q_CAPP      I53
  PC233_P0_7    2      B  Q_CAP       I51
  PC236_P0_8    2      B  Q_CAP       I38
  PC237_P0_7    2      B  Q_CAP       I52
  PC238_P0_8    2      B  Q_CAP       I39
  PC239_P0_7    2      B  Q_CAP       I57
  PC240_P0_8    2      B  Q_CAP       I40
  PC241_P0_7    2      B  Q_CAP       I58
  PC242_P0_8    2      B  Q_CAP       I104
  PC243_P0_7    2      B  Q_CAP       I79
  PC244_P0_8    2      B  Q_CAP       I103
  PC245_P0_7    2      B  Q_CAP       I78
  PC246_P0_8    2      B  Q_CAP       I101
  PC247_P0_7    2      B  Q_CAP       I77
  PC248    2      B  Q_CAP       I10
  PC249    2      B  Q_CAP       I30
  PC250_P0_6    2      B  Q_CAP       I12
  PC251_P0_5    2      B  Q_CAP       I34
  PC252_P0_6    2      B  Q_CAP       I15
  PC253_P0_5    2      B  Q_CAP       I38
  PC254_P0_6    2      B  Q_CAP       I18
  PC255_P0_5    2      B  Q_CAP       I39
  PC258_P0_6    2      B  Q_CAP       I19
  PC259_P0_5    2      B  Q_CAP       I40
  PC260_P0_6    2      B  Q_CAP       I41
  PC261_P0_5    2      B  Q_CAP       I59
  PC262_P0_6    2      B  Q_CAP       I45
  PC263_P0_5    2      B  Q_CAP       I60
  PC266_P0_6    2      B  Q_CAP       I95
  PC267_P0_5    2      B  Q_CAP       I80
  PC268_P0_6    2      B  Q_CAP       I94
  PC269_P0_5    2      B  Q_CAP       I79
  PC27     2      B  Q_CAP       I169
  PC270    2      B  Q_CAP        I8
  PC271    2      B  Q_CAP       I26
  PC272_P0_4    2      B  Q_CAP       I17
  PC273_P0_3    2      B  Q_CAP       I32
  PC274_P0_4    2      B  Q_CAP       I36
  PC275_P0_3    2      B  Q_CAP       I48
  PC276_P0_4    2      B  Q_CAP       I37
  PC277_P0_3    2      B  Q_CAP       I50
  PC28     2      B  Q_CAP       I179
  PC280_P0_4    2      B  Q_CAP       I38
  PC281_P0_3    2      B  Q_CAP       I51
  PC282_P0_4    2      B  Q_CAP       I40
  PC283_P0_3    2      B  Q_CAP       I55
  PC284_P0_4    2      B  Q_CAP       I42
  PC285_P0_3    2      B  Q_CAP       I56
  PC288_P0_4    2      B  Q_CAP       I96
  PC289_P0_3    2      B  Q_CAP       I79
  PC290_P0_4    2      B  Q_CAP       I95
  PC291_P0_3    2      B  Q_CAP       I78
  PC292    2      B  Q_CAP        I8
  PC293    2      B  Q_CAP       I30
  PC294_P0_2    2      B  Q_CAP       I18
  PC295_P0_1    2      B  Q_CAP       I35
  PC296_P0_2    2      B  Q_CAP       I22
  PC297_P0_1    2      B  Q_CAP       I40
  PC298_P0_2    2      B  Q_CAP       I23
  PC299_P0_1    2      B  Q_CAP       I41
  PC302_P0_2    2      B  Q_CAP       I24
  PC303_P0_1    2      B  Q_CAP       I65
  PC304_P0_2    2      B  Q_CAP       I46
  PC305_P0_1    2      B  Q_CAP       I66
  PC306_P0_2    2      B  Q_CAP       I47
  PC307_P0_1    2      B  Q_CAP       I67
  PC308_P0_1    2      B  Q_CAP       I111
  PC310_P0_1    2      B  Q_CAP       I110
  PC311_P0_2    2      B  Q_CAP       I128
  PC312_P0_1    2      B  Q_CAP       I109
  PC313_P0_2    2      B  Q_CAP       I127
  PC314_P0_1    2      B  Q_CAP       I108
  PC315    2      B  Q_CAPP      I74
  PC316    2      B  Q_CAPP      I56
  PC318    2      B  Q_CAPP      I76
  PC319    2      B  Q_CAPP      I58
  PC321    2      B  Q_CAPP      I77
  PC322    2      B  Q_CAPP      I59
  PC323    2      B  Q_CAPP      I55
  PC324    2      B  Q_CAPP      I84
  PC325    2      B  Q_CAPP      I81
  PC326    2      B  Q_CAPP      I79
  PC327    2      B  Q_CAP       I104
  PC328    2      B  Q_CAP       I106
  PC329    2      B  Q_CAP       I38
  PC330    2      B  Q_CAP       I45
  PC332    2      B  Q_CAP       I67
  PC333    2      B  Q_CAP       I72
  PC334    2      B  Q_CAP       I75
  PC335    2      B  Q_CAP       I74
  PC336    2      B  Q_CAP       I58
  PC337    2      B  Q_CAP       I119
  PC373    2      B  Q_CAP       I10
  PC374    2      B  Q_CAP       I18
  PC375    2      B  Q_CAP       I20
  PC377    2      B  Q_CAP       I29
  PC378    2      B  Q_CAP       I30
  PC379    2      B  Q_CAP       I27
  PC381    2      B  Q_CAP       I28
  PC382    2      B  Q_CAP       I34
  PC384    2      B  Q_CAPP      I21
  PC385    2      B  Q_CAPP      I23
  PC386    2      B  Q_CAP       I237
  PC388    2      B  Q_CAP       I253
  PC390    2      B  Q_CAP       I240
  PC391    2      B  Q_CAP       I257
  PC392    2      B  Q_CAP       I255
  PC393    2      B  Q_CAP       I251
  PC394    2      B  Q_CAP       I258
  PC395    2      B  Q_CAP       I230
  PC396    2      B  Q_CAP       I214
  PC2643    2      B  Q_CAP        I2
  PC2645    2      B  Q_CAPP      I68
  PC397_P1_1    2      B  Q_CAP       I238
  PC398_P1_2    2      B  Q_CAP       I223
  PC399_P1_1    2      B  Q_CAP       I257
  PC400_P1_2    2      B  Q_CAP       I243
  PC403_P1_1    2      B  Q_CAP       I258
  PC404_P1_2    2      B  Q_CAP       I244
  PC405_P1_1    2      B  Q_CAP       I259
  PC406_P1_2    2      B  Q_CAP       I245
  PC408_P1_2    2      B  Q_CAP       I282
  PC410_P1_1    2      B  Q_CAP       I265
  PC411_P1_2    2      B  Q_CAP       I248
  PC412_P1_1    2      B  Q_CAP       I268
  PC413_P1_2    2      B  Q_CAP       I249
  PC414    2      B  Q_CAPP      I252
  PC415    2      B  Q_CAPP      I253
  PC416    2      B  Q_CAPP      I254
  PC417    2      B  Q_CAPP      I275
  PC418    2      B  Q_CAPP      I270
  PC420    2      B  Q_CAP       I206
  PC421    2      B  Q_CAP       I205
  PC428    2      B  Q_CAP        I9
  PC429    2      B  Q_CAP       I20
  PC430    2      B  Q_CAP       I21
  PC432    2      B  Q_CAP       I22
  PC433    2      B  Q_CAP       I27
  PC434    2      B  Q_CAP       I25
  PC435    2      B  Q_CAP       I30
  PC437    2      B  Q_CAP       I31
  PC440    2      B  Q_CAP       I26
  PC441    2      B  Q_CAP       I14
  PC442_P1_1    2      B  Q_CAP       I50
  PC443_P1_2    2      B  Q_CAP       I34
  PC444_P1_1    2      B  Q_CAP       I51
  PC445_P1_2    2      B  Q_CAP       I36
  PC448_P1_1    2      B  Q_CAP       I56
  PC449_P1_2    2      B  Q_CAP       I38
  PC450_P1_1    2      B  Q_CAP       I57
  PC451_P1_2    2      B  Q_CAP       I39
  PC452_P1_1    2      B  Q_CAP       I58
  PC455_P1_1    2      B  Q_CAP       I59
  PC456_P1_2    2      B  Q_CAP       I41
  PC457_P1_1    2      B  Q_CAP       I62
  PC458_P1_2    2      B  Q_CAP       I43
  PC460    2      B  Q_CAPP      I74
  PC461    2      B  Q_CAPP      I75
  PC467    2      B  Q_CAP       I54
  PC470    2      B  Q_CAP       I74
  PC471    2      B  Q_CAP       I76
  PC472    2      B  Q_CAP       I59
  PC473    2      B  Q_CAP       I58
  PC474    2      B  Q_CAP       I57
  PC475    2      B  Q_CAP       I67
  PC476    2      B  Q_CAP       I82
  PC477    2      B  Q_CAP       I80
  PC478    2      B  Q_CAP       I83
  PC479    2      B  Q_CAP       I25
  PC480    2      B  Q_CAP       I32
  PC481_P1_8    2      B  Q_CAP       I28
  PC482_P1_7    2      B  Q_CAP       I36
  PC483_P1_8    2      B  Q_CAP       I38
  PC484_P1_7    2      B  Q_CAP       I46
  PC485_P1_8    2      B  Q_CAP       I40
  PC486_P1_7    2      B  Q_CAP       I48
  PC489_P1_8    2      B  Q_CAP       I42
  PC490_P1_7    2      B  Q_CAP       I52
  PC491_P1_8    2      B  Q_CAP       I43
  PC492_P1_7    2      B  Q_CAP       I53
  PC493_P1_8    2      B  Q_CAP       I44
  PC494_P1_7    2      B  Q_CAP       I54
  PC495_P1_8    2      B  Q_CAP       I103
  PC496_P1_7    2      B  Q_CAP       I84
  PC497_P1_8    2      B  Q_CAP       I102
  PC498_P1_7    2      B  Q_CAP       I83
  PC499_P1_8    2      B  Q_CAP       I101
  PC500_P1_7    2      B  Q_CAP       I81
  PC501    2      B  Q_CAP        I8
  PC502    2      B  Q_CAP       I20
  PC503_P1_6    2      B  Q_CAP       I29
  PC504_P1_5    2      B  Q_CAP       I34
  PC505_P1_6    2      B  Q_CAP       I37
  PC506_P1_5    2      B  Q_CAP       I48
  PC507_P1_6    2      B  Q_CAP       I38
  PC508_P1_5    2      B  Q_CAP       I49
  PC511_P1_6    2      B  Q_CAP       I39
  PC512_P1_5    2      B  Q_CAP       I50
  PC513_P1_6    2      B  Q_CAP       I44
  PC514_P1_5    2      B  Q_CAP       I54
  PC515_P1_6    2      B  Q_CAP       I45
  PC516_P1_5    2      B  Q_CAP       I56
  PC519_P1_6    2      B  Q_CAP       I95
  PC520_P1_5    2      B  Q_CAP       I79
  PC521_P1_6    2      B  Q_CAP       I94
  PC522_P1_5    2      B  Q_CAP       I78
  PC523    2      B  Q_CAP       I11
  PC524    2      B  Q_CAP       I26
  PC525_P1_4    2      B  Q_CAP       I16
  PC526_P1_3    2      B  Q_CAP       I30
  PC527_P1_4    2      B  Q_CAP       I32
  PC528_P1_3    2      B  Q_CAP       I46
  PC529_P1_4    2      B  Q_CAP       I35
  PC530_P1_3    2      B  Q_CAP       I48
  PC533_P1_4    2      B  Q_CAP       I36
  PC534_P1_3    2      B  Q_CAP       I49
  PC535_P1_4    2      B  Q_CAP       I42
  PC536_P1_3    2      B  Q_CAP       I53
  PC537_P1_4    2      B  Q_CAP       I43
  PC538_P1_3    2      B  Q_CAP       I54
  PC541_P1_4    2      B  Q_CAP       I96
  PC542_P1_3    2      B  Q_CAP       I79
  PC543_P1_4    2      B  Q_CAP       I94
  PC544_P1_3    2      B  Q_CAP       I77
  PC545    2      B  Q_CAP       I271
  PC546    2      B  Q_CAP       I273
  PC547    2      B  Q_CAP       I201
  PC548    2      B  Q_CAP       I209
  PC550    2      B  Q_CAP       I242
  PC551    2      B  Q_CAP       I244
  PC552    2      B  Q_CAP       I254
  PC553    2      B  Q_CAP       I253
  PC554    2      B  Q_CAP       I221
  PC555    2      B  Q_CAP       I258
  PC556    2      B  Q_CAP        I8
  PC557    2      B  Q_CAP       I29
  PC558_P1_2    2      B  Q_CAP       I16
  PC559_P1_1    2      B  Q_CAP       I32
  PC560_P1_2    2      B  Q_CAP       I21
  PC561_P1_1    2      B  Q_CAP       I38
  PC562_P1_2    2      B  Q_CAP       I39
  PC563_P1_1    2      B  Q_CAP       I40
  PC566    2      B  Q_CAPP       I4
  PC566_P1_2    2      B  Q_CAP       I44
  PC567    2      B  Q_CAP        I5
  PC567_P1_1    2      B  Q_CAP       I61
  PC568_P1_2    2      B  Q_CAP       I45
  PC569_P1_1    2      B  Q_CAP       I62
  PC570    2      B  Q_CAP       I18
  PC570_P1_2    2      B  Q_CAP       I46
  PC571    2      B  Q_CAP       I19
  PC571_P1_1    2      B  Q_CAP       I66
  PC572_P1_1    2      B  Q_CAP       I64
  PC574_P1_1    2      B  Q_CAP       I65
  PC575_P1_2    2      B  Q_CAP       I100
  PC576    2      B  Q_CAP       I20
  PC576_P1_1    2      B  Q_CAP       I68
  PC577    2      B  Q_CAP       I21
  PC577_P1_2    2      B  Q_CAP       I99
  PC578_P1_1    2      B  Q_CAP       I69
  PC579    2      B  Q_CAPP      I73
  PC580    2      B  Q_CAPP      I55
  PC581    2      B  Q_CAP        I7
  PC582    2      B  Q_CAPP      I74
  PC583    2      B  Q_CAPP      I56
  PC585    2      B  Q_CAPP      I83
  PC586    2      B  Q_CAPP      I79
  PC587    2      B  Q_CAPP      I75
  PC588    2      B  Q_CAPP      I84
  PC589    2      B  Q_CAPP      I81
  PC590    2      B  Q_CAPP      I77
  PC591    2      B  Q_CAP       I15
  PC592    2      B  Q_CAP       I43
  PC593    2      B  Q_CAP       I42
  PC600    2      B  Q_CAP       I23
  PC601    2      B  Q_CAP        I8
  PC602_P0_1    2      B  Q_CAP       I49
  PC603_P0_2    2      B  Q_CAP       I38
  PC604_P0_1    2      B  Q_CAP       I50
  PC605_P0_2    2      B  Q_CAP       I39
  PC608_P0_1    2      B  Q_CAP       I52
  PC609_P0_2    2      B  Q_CAP       I41
  PC610_P0_1    2      B  Q_CAP       I56
  PC611_P0_2    2      B  Q_CAP       I42
  PC612_P0_1    2      B  Q_CAP       I70
  PC613_P0_2    2      B  Q_CAP       I59
  PC615_P0_1    2      B  Q_CAP       I72
  PC616_P0_2    2      B  Q_CAP       I60
  PC617_P0_1    2      B  Q_CAP       I73
  PC618_P0_2    2      B  Q_CAP       I61
  PC619    2      B  Q_CAPP      I62
  PC620    2      B  Q_CAPP      I63
  PC621    2      B  Q_CAPP      I65
  PC621_P1_1    2      B  Q_CAP       I281
  PC71     2      B  Q_CAP       I22
  PC83     2      B  Q_CAPP      I105
  PC622    2      B  Q_CAPP      I77
  PC623    2      B  Q_CAPP      I66
  PC624    2      B  Q_CAP       I13
  PC626    2      B  Q_CAP       I45
  PC628    2      B  Q_CAP       I48
  PC629    2      B  Q_CAP       I65
  PC630    2      B  Q_CAP       I63
  PC631    2      B  Q_CAP       I55
  PC632    2      B  Q_CAP       I66
  PC633    2      B  Q_CAP       I332
  PC634    2      B  Q_CAP       I340
  PC635    2      B  Q_CAP       I357
  PC637    2      B  Q_CAP       I358
  PC638    2      B  Q_CAP       I359
  PC639    2      B  Q_CAP       I346
  PC641    2      B  Q_CAP       I352
  PC642    2      B  Q_CAP       I353
  PC644    2      B  Q_CAP        I7
  PC720_P0_1    2      B  Q_CAP       I85
  PC721_P0_2    2      B  Q_CAP       I86
  PC722_P0_3    2      B  Q_CAP       I78
  PC723_P0_4    2      B  Q_CAP       I79
  PC724_P1_1    2      B  Q_CAP       I285
  PC725_P1_2    2      B  Q_CAP       I286
  PC726_P1_3    2      B  Q_CAP       I83
  PC727_P1_4    2      B  Q_CAP       I84
  PC831    2      B  Q_CAP       I44
  PJ63     2      2  Q_SHORT     I15
  PJ65     2      2  Q_SHORT     I54
  PJ67     2      2  Q_SHORT     I55
  PL7      3      3  Q_INDUCTOR4P_14  I117
  PL25     3      3  Q_INDUCTOR4P_14  I76
  PL105    2      2  Q_INDUCTOR  I110
  PL106    2      2  Q_INDUCTOR  I107
  PR50     2      B  Q_RES       I172
  PR51     2      B  Q_RES       I180
  PR89     2      B  Q_RES       I16
  PR91     2      B  Q_RES       I25
  PR106    2      B  Q_RES       I25
  PR122    2      B  Q_RES       I33
  PR123    2      B  Q_RES       I36
  PR132    2      B  Q_RES        I2
  PR133    2      B  Q_RES       I13
  PR138    2      B  Q_RES        I2
  PR139    2      B  Q_RES       I21
  PR144    2      B  Q_RES        I2
  PR145    2      B  Q_RES       I19
  PR150    2      B  Q_RES        I2
  PR151    2      B  Q_RES       I14
  PR158    2      B  Q_RES       I36
  PR166    2      B  Q_RES       I44
  PR171    2      B  Q_RES        I5
  PR203    1      A  Q_RES       I201
  PR214    2      B  Q_RES       I236
  PR218    2      B  Q_RES       I238
  PR224    2      B  Q_RES       I202
  PR225    2      B  Q_RES       I213
  PR259    2      B  Q_RES        I6
  PR275    2      B  Q_RES       I13
  PR276    2      B  Q_RES       I56
  PR285    2      B  Q_RES        I2
  PR286    2      B  Q_RES       I18
  PR291    2      B  Q_RES        I2
  PR292    2      B  Q_RES       I13
  PR297    2      B  Q_RES        I2
  PR298    2      B  Q_RES       I20
  PR305    2      B  Q_RES       I199
  PR313    2      B  Q_RES       I208
  PR318    2      B  Q_RES       I165
  PR325    2      B  Q_RES        I2
  PR326    2      B  Q_RES       I12
  PR353    2      B  Q_RES        I2
  PR354    2      B  Q_RES       I17
  PR358    1      A  Q_RES        I6
  PR369    2      B  Q_RES       I12
  PR373    2      B  Q_RES       I46
  PR400    2      B  Q_RES       I77
  PR435    2      B  Q_RES       I73
  PR436    2      B  Q_RES       I79
  PR451    2      B  Q_RES       I81
  PR453    2      B  Q_RES       I262
  PR519    2      B  Q_RES       I11
  PR520    2      B  Q_RES        I8
  PR527    2      B  Q_RES       I21
  PR558    2      B  Q_RES       I206
  PR560    2      B  Q_RES       I171
  PR566    2      B  Q_RES       I22
  PR567    2      B  Q_RES       I19
  PR574    2      B  Q_RES       I176
  PR586    2      B  Q_RES       I16
  PR591    2      B  Q_RES       I78
  PR634    2      B  Q_RES       I57
  PR637    2      B  Q_RES       I260
  PR665    2      B  Q_RES       I70
  PR667    2      B  Q_RES       I93
  PR705    2      B  Q_RES       I263
  PR830    2      B  Q_RES       I34
  PR832    2      B  Q_RES        I9
  PR833    2      B  Q_RES       I11
  PR834    2      B  Q_RES       I13
  PR1297    2      B  Q_RES        I2
  PR1298    2      B  Q_RES       I13
  PR1301    2      B  Q_RES       I162
  PR1303    2      B  Q_RES       I161
  PR1304    2      B  Q_RES        I2
  PR1305    2      B  Q_RES       I13
  PR1311    2      B  Q_RES       I58
  PR1315    2      B  Q_RES       I259
  PR1327    2      B  Q_RES       I10
  PR1330    2      B  Q_RES       I12
  PR1336    2      B  Q_RES       I12
  PR1339    2      B  Q_RES       I14
  PR1707    2      B  Q_RES       I146
  PR1708    2      B  Q_RES       I156
  PR1709    2      B  Q_RES        I2
  PR1726    2      B  Q_RES        I7
  PR1727    2      B  Q_RES        I3
  PR1728    2      B  Q_RES        I2
  PR1746    2      B  Q_RES        I2
  PR1948    2      B  Q_RES        I1
  PR2220    2      B  Q_RES       I171
  PR2222    2      B  Q_RES       I177
  PR2718    2      B  Q_RES       I325
  PU10_P0_4    2   AGND  ISL99390FRZTR5935  I14
  PU10_P0_4    5  PGND1  ISL99390FRZTR5935  I14
  PU10_P0_4   40  PGND3  ISL99390FRZTR5935  I14
  PU10_P0_4  7_9-20_24  PGND2  ISL99390FRZTR5935  I14
  PU11_P0_3    2   AGND  ISL99390FRZTR5935  I30
  PU11_P0_3    5  PGND1  ISL99390FRZTR5935  I30
  PU11_P0_3   40  PGND3  ISL99390FRZTR5935  I30
  PU11_P0_3  7_9-20_24  PGND2  ISL99390FRZTR5935  I30
  PU12_P0_2    2   AGND  ISL99390FRZTR5935  I87
  PU12_P0_2    5  PGND1  ISL99390FRZTR5935  I87
  PU12_P0_2   40  PGND3  ISL99390FRZTR5935  I87
  PU12_P0_2  7_9-20_24  PGND2  ISL99390FRZTR5935  I87
  PU13_P0_1    2   AGND  ISL99390FRZTR5935  I21
  PU13_P0_1    5  PGND1  ISL99390FRZTR5935  I21
  PU13_P0_1   40  PGND3  ISL99390FRZTR5935  I21
  PU13_P0_1  7_9-20_24  PGND2  ISL99390FRZTR5935  I21
  PU14    TH  TH_GND  RAA229126GNPHA0  I48
  PU17     2  FAULT#  RAA2213404GNPHB0  I38
  PU17    23   GND2  RAA2213404GNPHB0  I38
  PU17    26   GND3  RAA2213404GNPHB0  I38
  PU17   6_7-13_15-29   GND1  RAA2213404GNPHB0  I38
  PU18    20    EN1  ISL69260IRAZT  I243
  PU18    31  RGND1  ISL69260IRAZT  I243
  PU18    32  VSEN1  ISL69260IRAZT  I243
  PU18    TH  TH_GND  ISL69260IRAZT  I243
  PU22    TH  TH_GND  ISL69260IRAZT  I61
  PU23_P1_8    2   AGND  ISL99390FRZTR5935   I9
  PU23_P1_8    5  PGND1  ISL99390FRZTR5935   I9
  PU23_P1_8   40  PGND3  ISL99390FRZTR5935   I9
  PU23_P1_8  7_9-20_24  PGND2  ISL99390FRZTR5935   I9
  PU24_P1_7    2   AGND  ISL99390FRZTR5935  I37
  PU24_P1_7    5  PGND1  ISL99390FRZTR5935  I37
  PU24_P1_7   40  PGND3  ISL99390FRZTR5935  I37
  PU24_P1_7  7_9-20_24  PGND2  ISL99390FRZTR5935  I37
  PU25_P1_6    2   AGND  ISL99390FRZTR5935  I23
  PU25_P1_6    5  PGND1  ISL99390FRZTR5935  I23
  PU25_P1_6   40  PGND3  ISL99390FRZTR5935  I23
  PU25_P1_6  7_9-20_24  PGND2  ISL99390FRZTR5935  I23
  PU26_P1_5    2   AGND  ISL99390FRZTR5935  I32
  PU26_P1_5    5  PGND1  ISL99390FRZTR5935  I32
  PU26_P1_5   40  PGND3  ISL99390FRZTR5935  I32
  PU26_P1_5  7_9-20_24  PGND2  ISL99390FRZTR5935  I32
  PU27_P1_4    2   AGND  ISL99390FRZTR5935   I9
  PU27_P1_4    5  PGND1  ISL99390FRZTR5935   I9
  PU27_P1_4   40  PGND3  ISL99390FRZTR5935   I9
  PU27_P1_4  7_9-20_24  PGND2  ISL99390FRZTR5935   I9
  PU28_P1_3    2   AGND  ISL99390FRZTR5935  I18
  PU28_P1_3    5  PGND1  ISL99390FRZTR5935  I18
  PU28_P1_3   40  PGND3  ISL99390FRZTR5935  I18
  PU28_P1_3  7_9-20_24  PGND2  ISL99390FRZTR5935  I18
  PU29    TH  TH_GND  RAA229126GNPHA0  I211
  PU30_P1_2    2   AGND  ISL99390FRZTR5935  I18
  PU30_P1_2    5  PGND1  ISL99390FRZTR5935  I18
  PU30_P1_2   40  PGND3  ISL99390FRZTR5935  I18
  PU30_P1_2  7_9-20_24  PGND2  ISL99390FRZTR5935  I18
  PU31_P1_1    2   AGND  ISL99390FRZTR5935  I20
  PU31_P1_1    5  PGND1  ISL99390FRZTR5935  I20
  PU31_P1_1   40  PGND3  ISL99390FRZTR5935  I20
  PU31_P1_1  7_9-20_24  PGND2  ISL99390FRZTR5935  I20
  PU5     TH  TH_GND  ISL69260IRAZT  I51
  PU35    20    EN1  ISL69260IRAZT  I51
  PU35    31  RGND1  ISL69260IRAZT  I51
  PU35    32  VSEN1  ISL69260IRAZT  I51
  PU35    TH  TH_GND  ISL69260IRAZT  I51
  PU36     2  FAULT#  RAA2213404GNPHB0  I333
  PU36    23   GND2  RAA2213404GNPHB0  I333
  PU36    26   GND3  RAA2213404GNPHB0  I333
  PU36   6_7-13_15-29   GND1  RAA2213404GNPHB0  I333
  PU42     2  FAULT#  RAA2213404GNPHB0  I11
  PU42    23   GND2  RAA2213404GNPHB0  I11
  PU42    26   GND3  RAA2213404GNPHB0  I11
  PU42   6_7-13_15-29   GND1  RAA2213404GNPHB0  I11
  PU181  11_18   PGND  MPQ8633BGLEC838Z  I19
  PU181    2   AGND  MPQ8633BGLEC838Z  I19
  PU181    6   RGND  MPQ8633BGLEC838Z  I19
  PU43_P0_1    2  FAULT#  RAA2213404GNPHB0  I166
  PU43_P0_1   23   GND2  RAA2213404GNPHB0  I166
  PU43_P0_1   26   GND3  RAA2213404GNPHB0  I166
  PU43_P0_1  6_7-13_15-29   GND1  RAA2213404GNPHB0  I166
  PU44_P0_2    2  FAULT#  RAA2213404GNPHB0  I164
  PU44_P0_2   23   GND2  RAA2213404GNPHB0  I164
  PU44_P0_2   26   GND3  RAA2213404GNPHB0  I164
  PU44_P0_2  6_7-13_15-29   GND1  RAA2213404GNPHB0  I164
  PU49     2  FAULT#  RAA2213404GNPHB0  I14
  PU49    23   GND2  RAA2213404GNPHB0  I14
  PU49    26   GND3  RAA2213404GNPHB0  I14
  PU49   6_7-13_15-29   GND1  RAA2213404GNPHB0  I14
  PU50_P1_1    2  FAULT#  RAA2213404GNPHB0  I17
  PU50_P1_1   23   GND2  RAA2213404GNPHB0  I17
  PU50_P1_1   26   GND3  RAA2213404GNPHB0  I17
  PU50_P1_1  6_7-13_15-29   GND1  RAA2213404GNPHB0  I17
  PU51_P1_2    2  FAULT#  RAA2213404GNPHB0  I12
  PU51_P1_2   23   GND2  RAA2213404GNPHB0  I12
  PU51_P1_2   26   GND3  RAA2213404GNPHB0  I12
  PU51_P1_2  6_7-13_15-29   GND1  RAA2213404GNPHB0  I12
  PU69_P0_1    2   AGND  ISL99390FRZTR5935  I35
  PU69_P0_1    5  PGND1  ISL99390FRZTR5935  I35
  PU69_P0_1   40  PGND3  ISL99390FRZTR5935  I35
  PU69_P0_1  7_9-20_24  PGND2  ISL99390FRZTR5935  I35
  PU6_P0_8    2   AGND  ISL99390FRZTR5935  I64
  PU6_P0_8    5  PGND1  ISL99390FRZTR5935  I64
  PU6_P0_8   40  PGND3  ISL99390FRZTR5935  I64
  PU6_P0_8  7_9-20_24  PGND2  ISL99390FRZTR5935  I64
  PU70_P0_2    2   AGND  ISL99390FRZTR5935  I30
  PU70_P0_2    5  PGND1  ISL99390FRZTR5935  I30
  PU70_P0_2   40  PGND3  ISL99390FRZTR5935  I30
  PU70_P0_2  7_9-20_24  PGND2  ISL99390FRZTR5935  I30
  PU71_P0_3    2   AGND  ISL99390FRZTR5935  I40
  PU71_P0_3    5  PGND1  ISL99390FRZTR5935  I40
  PU71_P0_3   40  PGND3  ISL99390FRZTR5935  I40
  PU71_P0_3  7_9-20_24  PGND2  ISL99390FRZTR5935  I40
  PU72_P0_4    2   AGND  ISL99390FRZTR5935  I24
  PU72_P0_4    5  PGND1  ISL99390FRZTR5935  I24
  PU72_P0_4   40  PGND3  ISL99390FRZTR5935  I24
  PU72_P0_4  7_9-20_24  PGND2  ISL99390FRZTR5935  I24
  PU73   11_18   PGND  MPQ8633BGLEC838Z  I34
  PU73     2   AGND  MPQ8633BGLEC838Z  I34
  PU74     2   PGND  NB695GDZ    I20
  PU74     4     C0  NB695GDZ    I20
  PU74    11   AGND  NB695GDZ    I20
  PU75_P1_1    2   AGND  ISL99390FRZTR5935  I278
  PU75_P1_1    5  PGND1  ISL99390FRZTR5935  I278
  PU75_P1_1   40  PGND3  ISL99390FRZTR5935  I278
  PU75_P1_1  7_9-20_24  PGND2  ISL99390FRZTR5935  I278
  PU76_P1_2    2   AGND  ISL99390FRZTR5935  I221
  PU76_P1_2    5  PGND1  ISL99390FRZTR5935  I221
  PU76_P1_2   40  PGND3  ISL99390FRZTR5935  I221
  PU76_P1_2  7_9-20_24  PGND2  ISL99390FRZTR5935  I221
  PU77_P1_3    2   AGND  ISL99390FRZTR5935  I27
  PU77_P1_3    5  PGND1  ISL99390FRZTR5935  I27
  PU77_P1_3   40  PGND3  ISL99390FRZTR5935  I27
  PU77_P1_3  7_9-20_24  PGND2  ISL99390FRZTR5935  I27
  PU78_P1_4    2   AGND  ISL99390FRZTR5935  I24
  PU78_P1_4    5  PGND1  ISL99390FRZTR5935  I24
  PU78_P1_4   40  PGND3  ISL99390FRZTR5935  I24
  PU78_P1_4  7_9-20_24  PGND2  ISL99390FRZTR5935  I24
  PU79   11_18   PGND  MPQ8633AGLEC807Z  I13
  PU79     2   AGND  MPQ8633AGLEC807Z  I13
  PU7_P0_7    2   AGND  ISL99390FRZTR5935  I20
  PU7_P0_7    5  PGND1  ISL99390FRZTR5935  I20
  PU7_P0_7   40  PGND3  ISL99390FRZTR5935  I20
  PU7_P0_7  7_9-20_24  PGND2  ISL99390FRZTR5935  I20
  PU9     31  VSNS-  NCP3284MNTXG  I23
  PU9     32   AGND  NCP3284MNTXG  I23
  PU9    7_10-19   PGND  NCP3284MNTXG  I23
  PU80   11_18   PGND  MPQ8633AGLEC807Z  I15
  PU80     2   AGND  MPQ8633AGLEC807Z  I15
  PU81     1  PGND1  MPQ8626GDZ  I190
  PU81     7   AGND  MPQ8626GDZ  I190
  PU81    14  PGND2  MPQ8626GDZ  I190
  PU82     1  PGND1  MPQ8626GDZ  I198
  PU82     7   AGND  MPQ8626GDZ  I198
  PU82    14  PGND2  MPQ8626GDZ  I198
  PU8_P0_6    2   AGND  ISL99390FRZTR5935  I62
  PU8_P0_6    5  PGND1  ISL99390FRZTR5935  I62
  PU8_P0_6   40  PGND3  ISL99390FRZTR5935  I62
  PU8_P0_6  7_9-20_24  PGND2  ISL99390FRZTR5935  I62
  PU9_P0_5    2   AGND  ISL99390FRZTR5935  I31
  PU9_P0_5    5  PGND1  ISL99390FRZTR5935  I31
  PU9_P0_5   40  PGND3  ISL99390FRZTR5935  I31
  PU9_P0_5  7_9-20_24  PGND2  ISL99390FRZTR5935  I31
  Q15      1     S1  MOSFET_NCH_DUAL  I36
  Q15      4     S2  MOSFET_NCH_DUAL   I9
  Q16      1     S1  MOSFET_NCH_DUAL  I68
  Q16      4     S2  MOSFET_NCH_DUAL  I66
  Q34      S  SOURCE  MOSFET_N_GSD  I81
  Q35      S  SOURCE  MOSFET_N_GSD  I86
  Q37      1     S1  MOSFET_NCH_DUAL  I75
  Q37      4     S2  MOSFET_NCH_DUAL  I76
  Q39      4     S2  MOSFET_NCH_DUAL  I20
  Q45      1     S1  MOSFET_NCH_DUAL  I180
  Q45      4     S2  MOSFET_NCH_DUAL  I181
  R9       2      B  Q_RES       I57
  R26      2      B  Q_RES       I196
  R27      2      B  Q_RES       I10
  R28      2      B  Q_RES       I10
  R29      2      B  Q_RES        I1
  R30      2      B  Q_RES        I3
  R31      2      B  Q_RES       I45
  R32      2      B  Q_RES        I2
  R33      2      B  Q_RES        I2
  R34      2      B  Q_RES       I11
  R35      2      B  Q_RES        I2
  R36      2      B  Q_RES        I2
  R37      2      B  Q_RES        I2
  R38      2      B  Q_RES       I10
  R39      2      B  Q_RES       I46
  R40      2      B  Q_RES       I47
  R41      2      B  Q_RES        I5
  R42      2      B  Q_RES       I11
  R43      2      B  Q_RES        I2
  R44      2      B  Q_RES        I3
  R45      2      B  Q_RES       I46
  R46      2      B  Q_RES        I2
  R47      2      B  Q_RES        I2
  R48      2      B  Q_RES        I2
  R69      2      B  Q_RES       I16
  R70      2      B  Q_RES       I17
  R72      2      B  Q_RES        I2
  R73      2      B  Q_RES        I3
  R74      2      B  Q_RES        I5
  R75      2      B  Q_RES       I47
  R76      2      B  Q_RES       I46
  R77      2      B  Q_RES       I10
  R78      2      B  Q_RES        I2
  R79      2      B  Q_RES        I2
  R80      2      B  Q_RES        I2
  R106     1      A  Q_RES       I304
  R148     2      B  Q_RES        I4
  R288     1      A  Q_RES       I119
  R289     1      A  Q_RES       I118
  R290     1      A  Q_RES       I135
  R291     1      A  Q_RES       I116
  R292     1      A  Q_RES       I69
  R293     1      A  Q_RES       I70
  R294     1      A  Q_RES       I71
  R295     1      A  Q_RES       I72
  R316     2      B  Q_RES       I59
  R318     2      B  Q_RES       I81
  R332     2      B  Q_RES       I21
  R334     2      B  Q_RES        I1
  R372     2      B  Q_RES       I46
  R375     2      B  Q_RES       I61
  R379     2      B  Q_RES       I76
  R381     2      B  Q_RES       I81
  R396     2      B  Q_RES       I78
  R400     2      B  Q_RES       I78
  R404     2      B  Q_RES       I206
  R410     2      B  Q_RES       I148
  R413     1      A  Q_RES       I362
  R415     2      B  Q_RES       I145
  R422     2      B  Q_RES       I12
  R423     2      B  Q_RES       I13
  R462     2      B  Q_RES       I25
  R477     2      B  Q_RES       I69
  R491     2      B  Q_RES       I164
  R496     2      B  Q_RES       I10
  R497     2      B  Q_RES        I2
  R508     2      B  Q_RES       I172
  R509     2      B  Q_RES       I197
  R515     2      B  Q_RES        I7
  R537     2      B  Q_RES        I2
  R539     2      B  Q_RES        I4
  R568     2      B  Q_RES       I178
  R570     2      B  Q_RES       I187
  R574     2      B  Q_RES       I197
  R587     2      B  Q_RES        I6
  R608     2      B  Q_RES       I36
  R610     2      B  Q_RES       I40
  R612     2      B  Q_RES       I44
  R614     2      B  Q_RES       I23
  R618     2      B  Q_RES       I53
  R622     2      B  Q_RES       I56
  R624     2      B  Q_RES       I14
  R626     2      B  Q_RES       I26
  R628     2      B  Q_RES       I17
  R630     2      B  Q_RES       I15
  R642     2      B  Q_RES       I53
  R644     2      B  Q_RES       I55
  R646     2      B  Q_RES       I56
  R661     2      B  Q_RES       I11
  R678     2      B  Q_RES       I63
  R701     2      B  Q_RES       I63
  R702     2      B  Q_RES       I76
  R703     2      B  Q_RES       I79
  R704     2      B  Q_RES       I75
  R705     2      B  Q_RES       I112
  R706     2      B  Q_RES       I103
  R707     2      B  Q_RES       I106
  R708     2      B  Q_RES       I109
  R710     2      B  Q_RES       I57
  R712     2      B  Q_RES       I30
  R714     2      B  Q_RES       I52
  R716     2      B  Q_RES       I31
  R718     2      B  Q_RES       I50
  R720     2      B  Q_RES       I32
  R722     2      B  Q_RES       I61
  R729     2      B  Q_RES       I90
  R731     2      B  Q_RES       I89
  R733     2      B  Q_RES       I88
  R734     2      B  Q_RES       I283
  R736     2      B  Q_RES       I125
  R746     2      B  Q_RES       I90
  R769     2      B  Q_RES       I102
  R774     2      B  Q_RES       I132
  R782     2      B  Q_RES        I6
  R784     2      B  Q_RES        I8
  R786     2      B  Q_RES       I12
  R920     2      B  Q_RES       I76
  R930     2      B  Q_RES       I63
  R932     2      B  Q_RES       I80
  R933     2      B  Q_RES       I82
  R934     2      B  Q_RES       I79
  R935     2      B  Q_RES       I86
  R936     2      B  Q_RES       I78
  R937     2      B  Q_RES       I85
  R938     2      B  Q_RES       I77
  R939     2      B  Q_RES       I83
  R953     2      B  Q_RES       I282
  R990     2      B  Q_RES       I18
  R991     2      B  Q_RES       I20
  R992     2      B  Q_RES       I21
  R997     2      B  Q_RES       I31
  R1005    2      B  Q_RES       I36
  R1024    2      B  Q_RES       I41
  R1025    2      B  Q_RES       I38
  R1103    2      B  Q_RES       I48
  R1124    2      B  Q_RES       I143
  R1126    2      B  Q_RES       I140
  R1128    2      B  Q_RES       I137
  R1134    2      B  Q_RES       I389
  R1135    2      B  Q_RES       I386
  R1136    2      B  Q_RES       I385
  R1137    2      B  Q_RES       I379
  R1142    2      B  Q_RES       I345
  R1144    2      B  Q_RES       I362
  R1196    2      B  Q_RES       I281
  R1197    1      A  Q_RES       I50
  R1221    2      B  Q_RES       I64
  R1226    2      B  Q_RES       I52
  R1227    2      B  Q_RES       I56
  R1234    1      A  Q_RES       I172
  R1235    1      A  Q_RES       I176
  R1236    1      A  Q_RES       I177
  R1237    1      A  Q_RES       I160
  R1238    1      A  Q_RES       I161
  R1239    1      A  Q_RES       I163
  R1241    2      B  Q_RES       I17
  R1243    2      B  Q_RES       I19
  R1267    2      B  Q_RES       I276
  R1269    2      B  Q_RES       I225
  R1270    2      B  Q_RES       I55
  R1289    2      B  Q_RES       I56
  R1299    2      B  Q_RES       I21
  R1302    2      B  Q_RES       I12
  R1308    2      B  Q_RES       I252
  R1311    2      B  Q_RES       I31
  R1312    2      B  Q_RES       I260
  R1324    1      A  Q_RES       I26
  R1326    2      B  Q_RES       I11
  R1327    2      B  Q_RES       I14
  R1328    2      B  Q_RES       I13
  R1329    2      B  Q_RES       I15
  R1330    2      B  Q_RES       I16
  R1333    1      A  Q_RES       I49
  R1334    1      A  Q_RES       I54
  R1335    1      A  Q_RES       I50
  R1337    2      B  Q_RES       I77
  R1338    2      B  Q_RES       I29
  R1341    2      B  Q_RES       I69
  R1346    2      B  Q_RES       I34
  R1347    2      B  Q_RES       I10
  R1350    2      B  Q_RES       I82
  R1351    2      B  Q_RES       I86
  R1352    2      B  Q_RES       I87
  R1353    2      B  Q_RES       I92
  R1354    2      B  Q_RES       I91
  R1355    2      B  Q_RES       I93
  R1356    2      B  Q_RES       I96
  R1365    2      B  Q_RES       I116
  R1368    2      B  Q_RES       I48
  R1369    2      B  Q_RES       I47
  R1371    2      B  Q_RES       I106
  R1372    2      B  Q_RES       I102
  R1373    2      B  Q_RES       I105
  R1374    2      B  Q_RES       I103
  R1375    2      B  Q_RES       I97
  R1388    2      B  Q_RES       I17
  R1389    2      B  Q_RES       I19
  R1390    2      B  Q_RES       I275
  R1391    1      A  Q_RES       I61
  R1392    1      A  Q_RES       I62
  R1393    1      A  Q_RES       I66
  R1394    1      A  Q_RES       I67
  R1398    2      B  Q_RES       I22
  R1402    2      B  Q_RES       I23
  R1403    2      B  Q_RES       I24
  R1404    2      B  Q_RES       I25
  R1405    2      B  Q_RES       I26
  R1406    2      B  Q_RES       I51
  R1407    2      B  Q_RES       I52
  R1408    2      B  Q_RES       I53
  R1409    2      B  Q_RES       I55
  R1410    2      B  Q_RES       I54
  R1411    2      B  Q_RES       I56
  R1412    2      B  Q_RES       I57
  R1413    2      B  Q_RES       I59
  R1414    2      B  Q_RES       I58
  R1415    2      B  Q_RES        I4
  R1416    2      B  Q_RES        I5
  R1417    2      B  Q_RES        I7
  R1418    2      B  Q_RES        I6
  R1419    2      B  Q_RES        I8
  R1420    2      B  Q_RES        I9
  R1421    2      B  Q_RES       I10
  R1441    2      B  Q_RES       I235
  R1445    2      B  Q_RES       I155
  R1457    2      B  Q_RES       I36
  R1462    2      B  Q_RES       I274
  R1476    2      B  Q_RES       I43
  R1478    2      B  Q_RES       I50
  R1484    2      B  Q_RES       I268
  R1487    2      B  Q_RES       I125
  R1491    2      B  Q_RES       I282
  R1494    2      B  Q_RES       I275
  R1495    2      B  Q_RES       I286
  R1497    2      B  Q_RES       I70
  R1499    2      B  Q_RES       I77
  R1500    2      B  Q_RES       I271
  R1502    2      B  Q_RES       I270
  R1527    2      B  Q_RES       I269
  R1530    2      B  Q_RES       I161
  R1531    2      B  Q_RES       I160
  R1535    2      B  Q_RES       I371
  R1536    2      B  Q_RES       I372
  R1539    2      B  Q_RES       I37
  R1541    1      A  Q_RES       I92
  R1574    2      B  Q_RES       I262
  R1578    2      B  Q_RES       I345
  R1605    2      B  Q_RES       I105
  R1614    2      B  Q_RES       I98
  R1616    2      B  Q_RES       I93
  R1618    2      B  Q_RES       I446
  R1641    2      B  Q_RES       I74
  R1646    2      B  Q_RES       I27
  R1649    2      B  Q_RES       I31
  R1676    2      B  Q_RES       I94
  R1689    2      B  Q_RES        I6
  R1692    2      B  Q_RES       I56
  R1698    2      B  Q_RES       I89
  R1701    2      B  Q_RES       I49
  R1738    2      B  Q_RES       I201
  R1739    2      B  Q_RES       I202
  R1742    2      B  Q_RES       I329
  R1749    2      B  Q_RES       I75
  R1764    2      B  Q_RES        I8
  R1785    2      B  Q_RES       I17
  R1787    2      B  Q_RES       I28
  R1789    2      B  Q_RES       I34
  R1791    2      B  Q_RES       I43
  R1800    2      B  Q_RES       I46
  R1801    2      B  Q_RES       I398
  R1810    2      B  Q_RES       I88
  R1814    2      B  Q_RES       I77
  R1850    1      A  Q_RES       I17
  R1895    2      B  Q_RES       I353
  R1896    2      B  Q_RES       I123
  R1897    2      B  Q_RES       I124
  R1898    2      B  Q_RES       I122
  R1929    1      A  Q_RES       I360
  R1930    1      A  Q_RES       I359
  R1962    2      B  Q_RES       I90
  R1969    2      B  Q_RES       I87
  R1970    2      B  Q_RES       I88
  R1972    2      B  Q_RES        I2
  R1980    2      B  Q_RES       I89
  R1982    2      B  Q_RES        I3
  R1990    2      B  Q_RES        I9
  R1992    2      B  Q_RES       I85
  R2002    2      B  Q_RES        I8
  R2004    2      B  Q_RES       I83
  R2016    2      B  Q_RES       I14
  R2020    2      B  Q_RES       I65
  R2021    2      B  Q_RES       I31
  R2038    2      B  Q_RES       I165
  R2039    2      B  Q_RES       I169
  R2044    2      B  Q_RES       I167
  R2045    2      B  Q_RES       I168
  R2074    2      B  Q_RES       I139
  R2075    2      B  Q_RES       I118
  R2076    2      B  Q_RES       I122
  R2082    2      B  Q_RES       I114
  R2083    2      B  Q_RES       I111
  R2086    2      B  Q_RES       I104
  R2087    2      B  Q_RES       I106
  R2088    2      B  Q_RES       I107
  R2090    2      B  Q_RES       I45
  R2092    2      B  Q_RES       I74
  R2094    2      B  Q_RES       I46
  R2096    2      B  Q_RES       I72
  R2098    2      B  Q_RES       I47
  R2100    2      B  Q_RES       I67
  R2134    2      B  Q_RES       I83
  R2137    2      B  Q_RES       I49
  R2141    2      B  Q_RES       I151
  R2142    2      B  Q_RES       I109
  R2156    2      B  Q_RES       I196
  R2172    2      B  Q_RES       I135
  R2178    2      B  Q_RES       I146
  R2179    2      B  Q_RES       I145
  R2192    2      B  Q_RES       I116
  R2194    2      B  Q_RES       I117
  R2196    2      B  Q_RES       I118
  R2332    2      B  Q_RES       I16
  R2374    2      B  Q_RES       I12
  R2385    2      B  Q_RES       I168
  U1     A11   VSS1  SOCKET4677_AZIFS054P001C01   I8
  U1     A13   VSS2  SOCKET4677_AZIFS054P001C01   I8
  U1     A17   VSS3  SOCKET4677_AZIFS054P001C01   I8
  U1     A19   VSS4  SOCKET4677_AZIFS054P001C01   I8
  U1     A23   VSS5  SOCKET4677_AZIFS054P001C01   I8
  U1     A25   VSS6  SOCKET4677_AZIFS054P001C01   I8
  U1     A29   VSS7  SOCKET4677_AZIFS054P001C01   I8
  U1     A31   VSS8  SOCKET4677_AZIFS054P001C01   I8
  U1     A35   VSS9  SOCKET4677_AZIFS054P001C01   I8
  U1     A37  VSS10  SOCKET4677_AZIFS054P001C01   I8
  U1     A41  VSS11  SOCKET4677_AZIFS054P001C01   I8
  U1     A50  VSS12  SOCKET4677_AZIFS054P001C01   I8
  U1     A54  VSS13  SOCKET4677_AZIFS054P001C01   I8
  U1     A56  VSS14  SOCKET4677_AZIFS054P001C01   I8
  U1     A60  VSS15  SOCKET4677_AZIFS054P001C01   I8
  U1     A62  VSS16  SOCKET4677_AZIFS054P001C01   I8
  U1     AA19  VSS17  SOCKET4677_AZIFS054P001C01   I2
  U1     AA23  VSS18  SOCKET4677_AZIFS054P001C01   I2
  U1     AA25  VSS19  SOCKET4677_AZIFS054P001C01   I2
  U1     AA29  VSS20  SOCKET4677_AZIFS054P001C01   I2
  U1     AA31  VSS21  SOCKET4677_AZIFS054P001C01   I2
  U1     AA35  VSS22  SOCKET4677_AZIFS054P001C01   I2
  U1     AA37  VSS23  SOCKET4677_AZIFS054P001C01   I2
  U1     AA41  VSS24  SOCKET4677_AZIFS054P001C01   I2
  U1     AA43  VSS25  SOCKET4677_AZIFS054P001C01   I2
  U1     AA48  VSS26  SOCKET4677_AZIFS054P001C01   I2
  U1     AA50  VSS27  SOCKET4677_AZIFS054P001C01   I2
  U1     AA54  VSS28  SOCKET4677_AZIFS054P001C01   I2
  U1     AA56  VSS29  SOCKET4677_AZIFS054P001C01   I2
  U1     AA60  VSS30  SOCKET4677_AZIFS054P001C01   I2
  U1     AA62  VSS31  SOCKET4677_AZIFS054P001C01   I2
  U1     AA66  VSS32  SOCKET4677_AZIFS054P001C01   I2
  U1     AA68  VSS33  SOCKET4677_AZIFS054P001C01   I2
  U1     AA72  VSS34  SOCKET4677_AZIFS054P001C01   I2
  U1     AA74  VSS35  SOCKET4677_AZIFS054P001C01   I2
  U1     AA78  VSS36  SOCKET4677_AZIFS054P001C01   I2
  U1     AA80  VSS37  SOCKET4677_AZIFS054P001C01   I2
  U1     AA82  VSS38  SOCKET4677_AZIFS054P001C01   I8
  U1     AA84  VSS39  SOCKET4677_AZIFS054P001C01   I8
  U1     AA88  VSS40  SOCKET4677_AZIFS054P001C01   I8
  U1     AB4  VSS50  SOCKET4677_AZIFS054P001C01   I8
  U1     AB8  VSS65  SOCKET4677_AZIFS054P001C01   I8
  U1     AB12  VSS41  SOCKET4677_AZIFS054P001C01   I8
  U1     AB16  VSS42  SOCKET4677_AZIFS054P001C01   I8
  U1     AB20  VSS43  SOCKET4677_AZIFS054P001C01   I8
  U1     AB22  VSS44  SOCKET4677_AZIFS054P001C01   I8
  U1     AB26  VSS45  SOCKET4677_AZIFS054P001C01   I8
  U1     AB28  VSS46  SOCKET4677_AZIFS054P001C01   I8
  U1     AB32  VSS47  SOCKET4677_AZIFS054P001C01   I8
  U1     AB34  VSS48  SOCKET4677_AZIFS054P001C01   I8
  U1     AB38  VSS49  SOCKET4677_AZIFS054P001C01   I8
  U1     AB40  VSS51  SOCKET4677_AZIFS054P001C01   I8
  U1     AB44  VSS52  SOCKET4677_AZIFS054P001C01   I8
  U1     AB47  VSS53  SOCKET4677_AZIFS054P001C01   I8
  U1     AB51  VSS54  SOCKET4677_AZIFS054P001C01   I8
  U1     AB53  VSS55  SOCKET4677_AZIFS054P001C01   I8
  U1     AB57  VSS56  SOCKET4677_AZIFS054P001C01   I8
  U1     AB59  VSS57  SOCKET4677_AZIFS054P001C01   I8
  U1     AB63  VSS58  SOCKET4677_AZIFS054P001C01   I8
  U1     AB65  VSS59  SOCKET4677_AZIFS054P001C01   I8
  U1     AB69  VSS60  SOCKET4677_AZIFS054P001C01   I8
  U1     AB71  VSS61  SOCKET4677_AZIFS054P001C01   I8
  U1     AB75  VSS62  SOCKET4677_AZIFS054P001C01   I8
  U1     AB77  VSS63  SOCKET4677_AZIFS054P001C01   I8
  U1     AB79  VSS64  SOCKET4677_AZIFS054P001C01   I8
  U1     AB81  VSS66  SOCKET4677_AZIFS054P001C01   I8
  U1     AB83  VSS67  SOCKET4677_AZIFS054P001C01   I8
  U1     AB87  VSS68  SOCKET4677_AZIFS054P001C01   I8
  U1     AB91  VSS69  SOCKET4677_AZIFS054P001C01   I8
  U1     AC1  VSS70  SOCKET4677_AZIFS054P001C01   I8
  U1     AC5  VSS77  SOCKET4677_AZIFS054P001C01   I8
  U1     AC9  VSS85  SOCKET4677_AZIFS054P001C01   I8
  U1     AC13  VSS71  SOCKET4677_AZIFS054P001C01   I8
  U1     AC21  VSS72  SOCKET4677_AZIFS054P001C01   I8
  U1     AC27  VSS73  SOCKET4677_AZIFS054P001C01   I8
  U1     AC33  VSS74  SOCKET4677_AZIFS054P001C01   I8
  U1     AC39  VSS75  SOCKET4677_AZIFS054P001C01   I8
  U1     AC45  VSS76  SOCKET4677_AZIFS054P001C01   I8
  U1     AC52  VSS78  SOCKET4677_AZIFS054P001C01   I8
  U1     AC58  VSS79  SOCKET4677_AZIFS054P001C01   I8
  U1     AC64  VSS80  SOCKET4677_AZIFS054P001C01   I8
  U1     AC70  VSS81  SOCKET4677_AZIFS054P001C01   I8
  U1     AC76  VSS82  SOCKET4677_AZIFS054P001C01   I8
  U1     AC84  VSS83  SOCKET4677_AZIFS054P001C01   I8
  U1     AC88  VSS84  SOCKET4677_AZIFS054P001C01   I8
  U1     AD4  VSS88  SOCKET4677_AZIFS054P001C01   I8
  U1     AD8  VSS91  SOCKET4677_AZIFS054P001C01   I8
  U1     AD12  VSS86  SOCKET4677_AZIFS054P001C01   I8
  U1     AD16  VSS87  SOCKET4677_AZIFS054P001C01   I8
  U1     AD42  VSS89  SOCKET4677_AZIFS054P001C01   I8
  U1     AD79  VSS90  SOCKET4677_AZIFS054P001C01   I8
  U1     AD83  VSS92  SOCKET4677_AZIFS054P001C01   I8
  U1     AE17  VSS93  SOCKET4677_AZIFS054P001C01   I8
  U1     AE19  VSS94  SOCKET4677_AZIFS054P001C01   I8
  U1     AE21  VSS95  SOCKET4677_AZIFS054P001C01   I8
  U1     AE23  VSS96  SOCKET4677_AZIFS054P001C01   I8
  U1     AE25  VSS97  SOCKET4677_AZIFS054P001C01   I8
  U1     AE27  VSS98  SOCKET4677_AZIFS054P001C01   I8
  U1     AE29  VSS99  SOCKET4677_AZIFS054P001C01   I8
  U1     AE31  VSS100  SOCKET4677_AZIFS054P001C01   I8
  U1     AE33  VSS101  SOCKET4677_AZIFS054P001C01   I8
  U1     AE35  VSS102  SOCKET4677_AZIFS054P001C01   I8
  U1     AE37  VSS103  SOCKET4677_AZIFS054P001C01   I8
  U1     AE39  VSS104  SOCKET4677_AZIFS054P001C01   I8
  U1     AE41  VSS105  SOCKET4677_AZIFS054P001C01   I8
  U1     AE43  VSS106  SOCKET4677_AZIFS054P001C01   I8
  U1     AE45  VSS107  SOCKET4677_AZIFS054P001C01   I8
  U1     AE48  VSS108  SOCKET4677_AZIFS054P001C01   I8
  U1     AE50  VSS109  SOCKET4677_AZIFS054P001C01   I8
  U1     AE52  VSS110  SOCKET4677_AZIFS054P001C01   I8
  U1     AE54  VSS111  SOCKET4677_AZIFS054P001C01   I8
  U1     AE56  VSS112  SOCKET4677_AZIFS054P001C01   I8
  U1     AE58  VSS113  SOCKET4677_AZIFS054P001C01   I8
  U1     AE60  VSS114  SOCKET4677_AZIFS054P001C01   I8
  U1     AE62  VSS115  SOCKET4677_AZIFS054P001C01   I8
  U1     AE64  VSS116  SOCKET4677_AZIFS054P001C01   I8
  U1     AE66  VSS117  SOCKET4677_AZIFS054P001C01   I8
  U1     AE68  VSS118  SOCKET4677_AZIFS054P001C01   I8
  U1     AE70  VSS119  SOCKET4677_AZIFS054P001C01   I8
  U1     AE72  VSS120  SOCKET4677_AZIFS054P001C01   I8
  U1     AE74  VSS121  SOCKET4677_AZIFS054P001C01   I8
  U1     AE76  VSS122  SOCKET4677_AZIFS054P001C01   I8
  U1     AE78  VSS123  SOCKET4677_AZIFS054P001C01   I8
  U1     AE84  VSS124  SOCKET4677_AZIFS054P001C01   I8
  U1     AE88  VSS125  SOCKET4677_AZIFS054P001C01   I8
  U1     AF4  VSS128  SOCKET4677_AZIFS054P001C01   I8
  U1     AF8  VSS130  SOCKET4677_AZIFS054P001C01   I8
  U1     AF12  VSS126  SOCKET4677_AZIFS054P001C01   I8
  U1     AF16  VSS127  SOCKET4677_AZIFS054P001C01   I8
  U1     AF42  VSS129  SOCKET4677_AZIFS054P001C01   I8
  U1     AF81  VSS131  SOCKET4677_AZIFS054P001C01   I8
  U1     AF87  VSS132  SOCKET4677_AZIFS054P001C01   I8
  U1     AF91  VSS133  SOCKET4677_AZIFS054P001C01   I8
  U1     AG1  VSS134  SOCKET4677_AZIFS054P001C01   I8
  U1     AG5  VSS141  SOCKET4677_AZIFS054P001C01   I8
  U1     AG9  VSS149  SOCKET4677_AZIFS054P001C01   I8
  U1     AG13  VSS135  SOCKET4677_AZIFS054P001C01   I8
  U1     AG21  VSS136  SOCKET4677_AZIFS054P001C01   I8
  U1     AG27  VSS137  SOCKET4677_AZIFS054P001C01   I8
  U1     AG33  VSS138  SOCKET4677_AZIFS054P001C01   I8
  U1     AG39  VSS139  SOCKET4677_AZIFS054P001C01   I8
  U1     AG45  VSS140  SOCKET4677_AZIFS054P001C01   I8
  U1     AG52  VSS142  SOCKET4677_AZIFS054P001C01   I8
  U1     AG58  VSS143  SOCKET4677_AZIFS054P001C01   I8
  U1     AG64  VSS144  SOCKET4677_AZIFS054P001C01   I8
  U1     AG70  VSS145  SOCKET4677_AZIFS054P001C01   I8
  U1     AG76  VSS146  SOCKET4677_AZIFS054P001C01   I8
  U1     AG84  VSS147  SOCKET4677_AZIFS054P001C01   I8
  U1     AG88  VSS148  SOCKET4677_AZIFS054P001C01   I8
  U1     AH4  VSS159  SOCKET4677_AZIFS054P001C01   I8
  U1     AH8  VSS174  SOCKET4677_AZIFS054P001C01   I8
  U1     AH12  VSS150  SOCKET4677_AZIFS054P001C01   I8
  U1     AH16  VSS151  SOCKET4677_AZIFS054P001C01   I8
  U1     AH20  VSS152  SOCKET4677_AZIFS054P001C01   I8
  U1     AH22  VSS153  SOCKET4677_AZIFS054P001C01   I8
  U1     AH26  VSS154  SOCKET4677_AZIFS054P001C01   I8
  U1     AH28  VSS155  SOCKET4677_AZIFS054P001C01   I8
  U1     AH32  VSS156  SOCKET4677_AZIFS054P001C01   I8
  U1     AH34  VSS157  SOCKET4677_AZIFS054P001C01   I8
  U1     AH38  VSS158  SOCKET4677_AZIFS054P001C01   I8
  U1     AH40  VSS160  SOCKET4677_AZIFS054P001C01   I8
  U1     AH44  VSS161  SOCKET4677_AZIFS054P001C01   I8
  U1     AH47  VSS162  SOCKET4677_AZIFS054P001C01   I8
  U1     AH51  VSS163  SOCKET4677_AZIFS054P001C01   I8
  U1     AH53  VSS164  SOCKET4677_AZIFS054P001C01   I8
  U1     AH57  VSS165  SOCKET4677_AZIFS054P001C01   I8
  U1     AH59  VSS166  SOCKET4677_AZIFS054P001C01   I8
  U1     AH63  VSS167  SOCKET4677_AZIFS054P001C01   I8
  U1     AH65  VSS168  SOCKET4677_AZIFS054P001C01   I8
  U1     AH69  VSS169  SOCKET4677_AZIFS054P001C01   I8
  U1     AH71  VSS170  SOCKET4677_AZIFS054P001C01   I8
  U1     AH75  VSS171  SOCKET4677_AZIFS054P001C01   I8
  U1     AH77  VSS172  SOCKET4677_AZIFS054P001C01   I8
  U1     AH79  VSS173  SOCKET4677_AZIFS054P001C01   I8
  U1     AH83  VSS175  SOCKET4677_AZIFS054P001C01   I8
  U1     AJ19  VSS176  SOCKET4677_AZIFS054P001C01   I8
  U1     AJ23  VSS177  SOCKET4677_AZIFS054P001C01   I8
  U1     AJ25  VSS178  SOCKET4677_AZIFS054P001C01   I8
  U1     AJ29  VSS179  SOCKET4677_AZIFS054P001C01   I8
  U1     AJ31  VSS180  SOCKET4677_AZIFS054P001C01   I8
  U1     AJ35  VSS181  SOCKET4677_AZIFS054P001C01   I8
  U1     AJ37  VSS182  SOCKET4677_AZIFS054P001C01   I8
  U1     AJ41  VSS183  SOCKET4677_AZIFS054P001C01   I8
  U1     AJ43  VSS184  SOCKET4677_AZIFS054P001C01   I8
  U1     AJ48  VSS185  SOCKET4677_AZIFS054P001C01   I8
  U1     AJ50  VSS186  SOCKET4677_AZIFS054P001C01   I8
  U1     AJ54  VSS187  SOCKET4677_AZIFS054P001C01   I8
  U1     AJ56  VSS188  SOCKET4677_AZIFS054P001C01   I8
  U1     AJ60  VSS189  SOCKET4677_AZIFS054P001C01   I8
  U1     AJ62  VSS190  SOCKET4677_AZIFS054P001C01   I8
  U1     AJ66  VSS191  SOCKET4677_AZIFS054P001C01   I8
  U1     AJ68  VSS192  SOCKET4677_AZIFS054P001C01   I8
  U1     AJ72  VSS193  SOCKET4677_AZIFS054P001C01   I8
  U1     AJ74  VSS194  SOCKET4677_AZIFS054P001C01   I8
  U1     AJ78  VSS195  SOCKET4677_AZIFS054P001C01   I8
  U1     AJ84  VSS196  SOCKET4677_AZIFS054P001C01   I8
  U1     AJ88  VSS197  SOCKET4677_AZIFS054P001C01   I8
  U1     AK4  VSS204  SOCKET4677_AZIFS054P001C01   I5
  U1     AK8  VSS212  SOCKET4677_AZIFS054P001C01   I5
  U1     AK12  VSS198  SOCKET4677_AZIFS054P001C01   I5
  U1     AK16  VSS199  SOCKET4677_AZIFS054P001C01   I5
  U1     AK18  VSS200  SOCKET4677_AZIFS054P001C01   I5
  U1     AK24  VSS201  SOCKET4677_AZIFS054P001C01   I5
  U1     AK30  VSS202  SOCKET4677_AZIFS054P001C01   I5
  U1     AK36  VSS203  SOCKET4677_AZIFS054P001C01   I5
  U1     AK42  VSS205  SOCKET4677_AZIFS054P001C01   I5
  U1     AK49  VSS206  SOCKET4677_AZIFS054P001C01   I5
  U1     AK55  VSS207  SOCKET4677_AZIFS054P001C01   I5
  U1     AK61  VSS208  SOCKET4677_AZIFS054P001C01   I5
  U1     AK67  VSS209  SOCKET4677_AZIFS054P001C01   I5
  U1     AK73  VSS210  SOCKET4677_AZIFS054P001C01   I5
  U1     AK79  VSS211  SOCKET4677_AZIFS054P001C01   I5
  U1     AK81  VSS213  SOCKET4677_AZIFS054P001C01   I5
  U1     AK83  VSS214  SOCKET4677_AZIFS054P001C01   I5
  U1     AK87  VSS215  SOCKET4677_AZIFS054P001C01   I5
  U1     AK91  VSS216  SOCKET4677_AZIFS054P001C01   I5
  U1     AL1  VSS217  SOCKET4677_AZIFS054P001C01   I5
  U1     AL5  VSS220  SOCKET4677_AZIFS054P001C01   I5
  U1     AL9  VSS226  SOCKET4677_AZIFS054P001C01   I5
  U1     AL13  VSS218  SOCKET4677_AZIFS054P001C01   I5
  U1     AL17  VSS219  SOCKET4677_AZIFS054P001C01   I5
  U1     AL52  VSS221  SOCKET4677_AZIFS054P001C01   I5
  U1     AL80  VSS222  SOCKET4677_AZIFS054P001C01   I5
  U1     AL82  VSS223  SOCKET4677_AZIFS054P001C01   I5
  U1     AL84  VSS224  SOCKET4677_AZIFS054P001C01   I5
  U1     AL88  VSS225  SOCKET4677_AZIFS054P001C01   I5
  U1     AM4  VSS240  SOCKET4677_AZIFS054P001C01   I5
  U1     AM8  VSS260  SOCKET4677_AZIFS054P001C01   I5
  U1     AM12  VSS227  SOCKET4677_AZIFS054P001C01   I5
  U1     AM16  VSS228  SOCKET4677_AZIFS054P001C01   I5
  U1     AM18  VSS229  SOCKET4677_AZIFS054P001C01   I5
  U1     AM20  VSS230  SOCKET4677_AZIFS054P001C01   I5
  U1     AM22  VSS231  SOCKET4677_AZIFS054P001C01   I5
  U1     AM24  VSS232  SOCKET4677_AZIFS054P001C01   I5
  U1     AM26  VSS233  SOCKET4677_AZIFS054P001C01   I5
  U1     AM28  VSS234  SOCKET4677_AZIFS054P001C01   I5
  U1     AM30  VSS235  SOCKET4677_AZIFS054P001C01   I5
  U1     AM32  VSS236  SOCKET4677_AZIFS054P001C01   I5
  U1     AM34  VSS237  SOCKET4677_AZIFS054P001C01   I5
  U1     AM36  VSS238  SOCKET4677_AZIFS054P001C01   I5
  U1     AM38  VSS239  SOCKET4677_AZIFS054P001C01   I5
  U1     AM40  VSS241  SOCKET4677_AZIFS054P001C01   I5
  U1     AM42  VSS242  SOCKET4677_AZIFS054P001C01   I5
  U1     AM44  VSS243  SOCKET4677_AZIFS054P001C01   I5
  U1     AM47  VSS244  SOCKET4677_AZIFS054P001C01   I5
  U1     AM49  VSS245  SOCKET4677_AZIFS054P001C01   I5
  U1     AM51  VSS246  SOCKET4677_AZIFS054P001C01   I5
  U1     AM53  VSS247  SOCKET4677_AZIFS054P001C01   I5
  U1     AM55  VSS248  SOCKET4677_AZIFS054P001C01   I5
  U1     AM57  VSS249  SOCKET4677_AZIFS054P001C01   I5
  U1     AM59  VSS250  SOCKET4677_AZIFS054P001C01   I5
  U1     AM61  VSS251  SOCKET4677_AZIFS054P001C01   I5
  U1     AM63  VSS252  SOCKET4677_AZIFS054P001C01   I5
  U1     AM65  VSS253  SOCKET4677_AZIFS054P001C01   I5
  U1     AM67  VSS254  SOCKET4677_AZIFS054P001C01   I5
  U1     AM69  VSS255  SOCKET4677_AZIFS054P001C01   I5
  U1     AM71  VSS256  SOCKET4677_AZIFS054P001C01   I5
  U1     AM73  VSS257  SOCKET4677_AZIFS054P001C01   I5
  U1     AM75  VSS258  SOCKET4677_AZIFS054P001C01   I5
  U1     AM77  VSS259  SOCKET4677_AZIFS054P001C01   I5
  U1     AN52  VSS261  SOCKET4677_AZIFS054P001C01   I5
  U1     AN84  VSS262  SOCKET4677_AZIFS054P001C01   I5
  U1     AN88  VSS263  SOCKET4677_AZIFS054P001C01   I5
  U1     AP4  VSS270  SOCKET4677_AZIFS054P001C01   I5
  U1     AP8  VSS278  SOCKET4677_AZIFS054P001C01   I5
  U1     AP12  VSS264  SOCKET4677_AZIFS054P001C01   I5
  U1     AP16  VSS265  SOCKET4677_AZIFS054P001C01   I5
  U1     AP18  VSS266  SOCKET4677_AZIFS054P001C01   I5
  U1     AP24  VSS267  SOCKET4677_AZIFS054P001C01   I5
  U1     AP30  VSS268  SOCKET4677_AZIFS054P001C01   I5
  U1     AP36  VSS269  SOCKET4677_AZIFS054P001C01   I5
  U1     AP42  VSS271  SOCKET4677_AZIFS054P001C01   I5
  U1     AP49  VSS272  SOCKET4677_AZIFS054P001C01   I5
  U1     AP55  VSS273  SOCKET4677_AZIFS054P001C01   I5
  U1     AP61  VSS274  SOCKET4677_AZIFS054P001C01   I5
  U1     AP67  VSS275  SOCKET4677_AZIFS054P001C01   I5
  U1     AP73  VSS276  SOCKET4677_AZIFS054P001C01   I5
  U1     AP79  VSS277  SOCKET4677_AZIFS054P001C01   I5
  U1     AP83  VSS279  SOCKET4677_AZIFS054P001C01   I5
  U1     AP87  VSS280  SOCKET4677_AZIFS054P001C01   I5
  U1     AP91  VSS281  SOCKET4677_AZIFS054P001C01   I5
  U1     AR1  VSS282  SOCKET4677_AZIFS054P001C01   I5
  U1     AR5  VSS294  SOCKET4677_AZIFS054P001C01   I5
  U1     AR9  VSS308  SOCKET4677_AZIFS054P001C01   I5
  U1     AR13  VSS283  SOCKET4677_AZIFS054P001C01   I5
  U1     AR19  VSS284  SOCKET4677_AZIFS054P001C01   I5
  U1     AR23  VSS285  SOCKET4677_AZIFS054P001C01   I5
  U1     AR25  VSS286  SOCKET4677_AZIFS054P001C01   I5
  U1     AR29  VSS287  SOCKET4677_AZIFS054P001C01   I5
  U1     AR31  VSS288  SOCKET4677_AZIFS054P001C01   I5
  U1     AR35  VSS289  SOCKET4677_AZIFS054P001C01   I5
  U1     AR37  VSS290  SOCKET4677_AZIFS054P001C01   I5
  U1     AR41  VSS291  SOCKET4677_AZIFS054P001C01   I5
  U1     AR43  VSS292  SOCKET4677_AZIFS054P001C01   I5
  U1     AR48  VSS293  SOCKET4677_AZIFS054P001C01   I5
  U1     AR50  VSS295  SOCKET4677_AZIFS054P001C01   I5
  U1     AR54  VSS296  SOCKET4677_AZIFS054P001C01   I5
  U1     AR56  VSS297  SOCKET4677_AZIFS054P001C01   I5
  U1     AR60  VSS298  SOCKET4677_AZIFS054P001C01   I5
  U1     AR62  VSS299  SOCKET4677_AZIFS054P001C01   I5
  U1     AR66  VSS300  SOCKET4677_AZIFS054P001C01   I5
  U1     AR68  VSS301  SOCKET4677_AZIFS054P001C01   I5
  U1     AR72  VSS302  SOCKET4677_AZIFS054P001C01   I5
  U1     AR74  VSS303  SOCKET4677_AZIFS054P001C01   I5
  U1     AR78  VSS304  SOCKET4677_AZIFS054P001C01   I5
  U1     AR82  VSS305  SOCKET4677_AZIFS054P001C01   I5
  U1     AR84  VSS306  SOCKET4677_AZIFS054P001C01   I5
  U1     AR88  VSS307  SOCKET4677_AZIFS054P001C01   I5
  U1     AT4  VSS318  SOCKET4677_AZIFS054P001C01   I5
  U1     AT8  VSS332  SOCKET4677_AZIFS054P001C01   I5
  U1     AT12  VSS309  SOCKET4677_AZIFS054P001C01   I5
  U1     AT16  VSS310  SOCKET4677_AZIFS054P001C01   I5
  U1     AT20  VSS311  SOCKET4677_AZIFS054P001C01   I5
  U1     AT22  VSS312  SOCKET4677_AZIFS054P001C01   I5
  U1     AT26  VSS313  SOCKET4677_AZIFS054P001C01   I5
  U1     AT28  VSS314  SOCKET4677_AZIFS054P001C01   I5
  U1     AT32  VSS315  SOCKET4677_AZIFS054P001C01   I5
  U1     AT34  VSS316  SOCKET4677_AZIFS054P001C01   I5
  U1     AT38  VSS317  SOCKET4677_AZIFS054P001C01   I5
  U1     AT40  VSS319  SOCKET4677_AZIFS054P001C01   I5
  U1     AT44  VSS320  SOCKET4677_AZIFS054P001C01   I5
  U1     AT51  VSS321  SOCKET4677_AZIFS054P001C01   I5
  U1     AT53  VSS322  SOCKET4677_AZIFS054P001C01   I5
  U1     AT57  VSS323  SOCKET4677_AZIFS054P001C01   I5
  U1     AT59  VSS324  SOCKET4677_AZIFS054P001C01   I5
  U1     AT63  VSS325  SOCKET4677_AZIFS054P001C01   I5
  U1     AT65  VSS326  SOCKET4677_AZIFS054P001C01   I5
  U1     AT69  VSS327  SOCKET4677_AZIFS054P001C01   I5
  U1     AT71  VSS328  SOCKET4677_AZIFS054P001C01   I5
  U1     AT75  VSS329  SOCKET4677_AZIFS054P001C01   I5
  U1     AT77  VSS330  SOCKET4677_AZIFS054P001C01   I5
  U1     AT79  VSS331  SOCKET4677_AZIFS054P001C01   I5
  U1     AU27  VSS333  SOCKET4677_AZIFS054P001C01   I5
  U1     AU31  VSS334  SOCKET4677_AZIFS054P001C01   I5
  U1     AU37  VSS335  SOCKET4677_AZIFS054P001C01   I5
  U1     AU39  VSS336  SOCKET4677_AZIFS054P001C01   I5
  U1     AU41  VSS337  SOCKET4677_AZIFS054P001C01   I5
  U1     AU45  VSS338  SOCKET4677_AZIFS054P001C01   I5
  U1     AU48  VSS339  SOCKET4677_AZIFS054P001C01   I5
  U1     AU70  VSS340  SOCKET4677_AZIFS054P001C01   I5
  U1     AU72  VSS341  SOCKET4677_AZIFS054P001C01   I5
  U1     AU74  VSS342  SOCKET4677_AZIFS054P001C01   I5
  U1     AU76  VSS343  SOCKET4677_AZIFS054P001C01   I5
  U1     AU80  VSS344  SOCKET4677_AZIFS054P001C01   I5
  U1     AU84  VSS345  SOCKET4677_AZIFS054P001C01   I5
  U1     AU88  VSS346  SOCKET4677_AZIFS054P001C01   I5
  U1     AV4  VSS349  SOCKET4677_AZIFS054P001C01   I5
  U1     AV8  VSS351  SOCKET4677_AZIFS054P001C01   I5
  U1     AV12  VSS347  SOCKET4677_AZIFS054P001C01   I5
  U1     AV16  VSS348  SOCKET4677_AZIFS054P001C01   I5
  U1     AV77  VSS350  SOCKET4677_AZIFS054P001C01   I5
  U1     AV87  VSS352  SOCKET4677_AZIFS054P001C01   I5
  U1     AV91  VSS353  SOCKET4677_AZIFS054P001C01   I5
  U1     AW1  VSS354  SOCKET4677_AZIFS054P001C01   I5
  U1     AW5  VSS359  SOCKET4677_AZIFS054P001C01   I5
  U1     AW9  VSS368  SOCKET4677_AZIFS054P001C01   I5
  U1     AW13  VSS355  SOCKET4677_AZIFS054P001C01   I5
  U1     AW21  VSS356  SOCKET4677_AZIFS054P001C01   I2
  U1     AW23  VSS357  SOCKET4677_AZIFS054P001C01   I2
  U1     AW25  VSS358  SOCKET4677_AZIFS054P001C01   I2
  U1     AW62  VSS360  SOCKET4677_AZIFS054P001C01   I2
  U1     AW66  VSS361  SOCKET4677_AZIFS054P001C01   I2
  U1     AW68  VSS362  SOCKET4677_AZIFS054P001C01   I2
  U1     AW72  VSS363  SOCKET4677_AZIFS054P001C01   I2
  U1     AW80  VSS364  SOCKET4677_AZIFS054P001C01   I2
  U1     AW82  VSS365  SOCKET4677_AZIFS054P001C01   I2
  U1     AW84  VSS366  SOCKET4677_AZIFS054P001C01   I2
  U1     AW88  VSS367  SOCKET4677_AZIFS054P001C01   I2
  U1     AY4  VSS371  SOCKET4677_AZIFS054P001C01   I2
  U1     AY8  VSS375  SOCKET4677_AZIFS054P001C01   I2
  U1     AY12  VSS369  SOCKET4677_AZIFS054P001C01   I2
  U1     AY16  VSS370  SOCKET4677_AZIFS054P001C01   I2
  U1     AY71  VSS372  SOCKET4677_AZIFS054P001C01   I2
  U1     AY77  VSS373  SOCKET4677_AZIFS054P001C01   I2
  U1     AY79  VSS374  SOCKET4677_AZIFS054P001C01   I2
  U1     AY81  VSS376  SOCKET4677_AZIFS054P001C01   I2
  U1     AY83  VSS377  SOCKET4677_AZIFS054P001C01   I2
  U1      B6  VSS387  SOCKET4677_AZIFS054P001C01   I8
  U1     B12  VSS378  SOCKET4677_AZIFS054P001C01   I8
  U1     B18  VSS379  SOCKET4677_AZIFS054P001C01   I8
  U1     B24  VSS380  SOCKET4677_AZIFS054P001C01   I8
  U1     B30  VSS381  SOCKET4677_AZIFS054P001C01   I8
  U1     B36  VSS382  SOCKET4677_AZIFS054P001C01   I8
  U1     B42  VSS384  SOCKET4677_AZIFS054P001C01   I8
  U1     B49  VSS385  SOCKET4677_AZIFS054P001C01   I8
  U1     B55  VSS386  SOCKET4677_AZIFS054P001C01   I8
  U1     B61  VSS388  SOCKET4677_AZIFS054P001C01   I8
  U1     B67  VSS389  SOCKET4677_AZIFS054P001C01   I8
  U1     B75  VSS390  SOCKET4677_AZIFS054P001C01   I8
  U1     B83  VSS391  SOCKET4677_AZIFS054P001C01   I8
  U1     B87  VSS392  SOCKET4677_AZIFS054P001C01   I8
  U1     BA17  VSS393  SOCKET4677_AZIFS054P001C01   I2
  U1     BA60  VSS394  SOCKET4677_AZIFS054P001C01   I2
  U1     BA64  VSS395  SOCKET4677_AZIFS054P001C01   I2
  U1     BA74  VSS397  SOCKET4677_AZIFS054P001C01   I2
  U1     BA84  VSS398  SOCKET4677_AZIFS054P001C01   I2
  U1     BA88  VSS399  SOCKET4677_AZIFS054P001C01   I2
  U1     BB4  VSS407  SOCKET4677_AZIFS054P001C01   I2
  U1     BB8  VSS413  SOCKET4677_AZIFS054P001C01   I2
  U1     BB10  VSS400  SOCKET4677_AZIFS054P001C01   I2
  U1     BB12  VSS401  SOCKET4677_AZIFS054P001C01   I2
  U1     BB16  VSS402  SOCKET4677_AZIFS054P001C01   I2
  U1     BB20  VSS403  SOCKET4677_AZIFS054P001C01   I2
  U1     BB22  VSS404  SOCKET4677_AZIFS054P001C01   I2
  U1     BB24  VSS405  SOCKET4677_AZIFS054P001C01   I2
  U1     BB26  VSS406  SOCKET4677_AZIFS054P001C01   I2
  U1     BB63  VSS408  SOCKET4677_AZIFS054P001C01   I2
  U1     BB69  VSS409  SOCKET4677_AZIFS054P001C01   I2
  U1     BB71  VSS410  SOCKET4677_AZIFS054P001C01   I2
  U1     BB77  VSS411  SOCKET4677_AZIFS054P001C01   I2
  U1     BB79  VSS412  SOCKET4677_AZIFS054P001C01   I2
  U1     BB83  VSS414  SOCKET4677_AZIFS054P001C01   I2
  U1     BB87  VSS415  SOCKET4677_AZIFS054P001C01   I2
  U1     BB91  VSS416  SOCKET4677_AZIFS054P001C01   I2
  U1     BC1  VSS417  SOCKET4677_AZIFS054P001C01   I2
  U1     BC5  VSS420  SOCKET4677_AZIFS054P001C01   I2
  U1     BC9  VSS429  SOCKET4677_AZIFS054P001C01   I2
  U1     BC13  VSS418  SOCKET4677_AZIFS054P001C01   I2
  U1     BC17  VSS419  SOCKET4677_AZIFS054P001C01   I2
  U1     BC62  VSS421  SOCKET4677_AZIFS054P001C01   I2
  U1     BC66  VSS422  SOCKET4677_AZIFS054P001C01   I2
  U1     BC72  VSS423  SOCKET4677_AZIFS054P001C01   I2
  U1     BC76  VSS424  SOCKET4677_AZIFS054P001C01   I2
  U1     BC78  VSS425  SOCKET4677_AZIFS054P001C01   I2
  U1     BC84  VSS426  SOCKET4677_AZIFS054P001C01   I2
  U1     BC86  VSS427  SOCKET4677_AZIFS054P001C01   I2
  U1     BC88  VSS428  SOCKET4677_AZIFS054P001C01   I2
  U1     BD4  VSS433  SOCKET4677_AZIFS054P001C01   I2
  U1     BD8  VSS434  SOCKET4677_AZIFS054P001C01   I2
  U1     BD12  VSS430  SOCKET4677_AZIFS054P001C01   I2
  U1     BD16  VSS431  SOCKET4677_AZIFS054P001C01   I2
  U1     BD20  VSS432  SOCKET4677_AZIFS054P001C01   I2
  U1     BD81  VSS435  SOCKET4677_AZIFS054P001C01   I2
  U1     BD85  VSS437  SOCKET4677_AZIFS054P001C01   I2
  U1     BD89  VSS439  SOCKET4677_AZIFS054P001C01   I2
  U1     BE64  VSS440  SOCKET4677_AZIFS054P001C01   I2
  U1     BE66  VSS441  SOCKET4677_AZIFS054P001C01   I2
  U1     BE68  VSS442  SOCKET4677_AZIFS054P001C01   I2
  U1     BE74  VSS443  SOCKET4677_AZIFS054P001C01   I2
  U1     BE76  VSS444  SOCKET4677_AZIFS054P001C01   I2
  U1     BE78  VSS445  SOCKET4677_AZIFS054P001C01   I2
  U1     BE84  VSS446  SOCKET4677_AZIFS054P001C01   I2
  U1     BF4  VSS450  SOCKET4677_AZIFS054P001C01   I2
  U1     BF8  VSS456  SOCKET4677_AZIFS054P001C01   I2
  U1     BF12  VSS447  SOCKET4677_AZIFS054P001C01   I2
  U1     BF16  VSS448  SOCKET4677_AZIFS054P001C01   I2
  U1     BF20  VSS449  SOCKET4677_AZIFS054P001C01   I2
  U1     BF61  VSS451  SOCKET4677_AZIFS054P001C01   I2
  U1     BF63  VSS452  SOCKET4677_AZIFS054P001C01   I2
  U1     BF73  VSS453  SOCKET4677_AZIFS054P001C01   I2
  U1     BF75  VSS454  SOCKET4677_AZIFS054P001C01   I2
  U1     BF79  VSS455  SOCKET4677_AZIFS054P001C01   I2
  U1     BF83  VSS457  SOCKET4677_AZIFS054P001C01   I2
  U1     BG1  VSS458  SOCKET4677_AZIFS054P001C01   I2
  U1     BG5  VSS464  SOCKET4677_AZIFS054P001C01   I2
  U1     BG9  VSS466  SOCKET4677_AZIFS054P001C01   I2
  U1     BG13  VSS459  SOCKET4677_AZIFS054P001C01   I2
  U1     BG17  VSS460  SOCKET4677_AZIFS054P001C01   I2
  U1     BG21  VSS461  SOCKET4677_AZIFS054P001C01   I2
  U1     BG23  VSS462  SOCKET4677_AZIFS054P001C01   I2
  U1     BG25  VSS463  SOCKET4677_AZIFS054P001C01   I2
  U1     BG70  VSS465  SOCKET4677_AZIFS054P001C01   I2
  U1     BH4  VSS470  SOCKET4677_AZIFS054P001C01   I2
  U1     BH8  VSS475  SOCKET4677_AZIFS054P001C01   I2
  U1     BH12  VSS467  SOCKET4677_AZIFS054P001C01   I2
  U1     BH16  VSS468  SOCKET4677_AZIFS054P001C01   I2
  U1     BH20  VSS469  SOCKET4677_AZIFS054P001C01   I2
  U1     BH67  VSS472  SOCKET4677_AZIFS054P001C01   I2
  U1     BH73  VSS473  SOCKET4677_AZIFS054P001C01   I2
  U1     BH77  VSS474  SOCKET4677_AZIFS054P001C01   I2
  U1     BH81  VSS476  SOCKET4677_AZIFS054P001C01   I2
  U1     BH83  VSS477  SOCKET4677_AZIFS054P001C01   I2
  U1     BJ62  VSS479  SOCKET4677_AZIFS054P001C01   I2
  U1     BJ68  VSS480  SOCKET4677_AZIFS054P001C01   I2
  U1     BJ80  VSS481  SOCKET4677_AZIFS054P001C01   I2
  U1     BJ82  VSS482  SOCKET4677_AZIFS054P001C01   I2
  U1     BJ84  VSS483  SOCKET4677_AZIFS054P001C01   I2
  U1     BJ86  VSS484  SOCKET4677_AZIFS054P001C01   I2
  U1     BJ88  VSS485  SOCKET4677_AZIFS054P001C01   I2
  U1     BJ90  VSS486  SOCKET4677_AZIFS054P001C01   I2
  U1     BK4  VSS490  SOCKET4677_AZIFS054P001C01   I2
  U1     BK8  VSS496  SOCKET4677_AZIFS054P001C01   I2
  U1     BK12  VSS487  SOCKET4677_AZIFS054P001C01   I2
  U1     BK16  VSS488  SOCKET4677_AZIFS054P001C01   I2
  U1     BK20  VSS489  SOCKET4677_AZIFS054P001C01   I2
  U1     BK65  VSS491  SOCKET4677_AZIFS054P001C01   I2
  U1     BK71  VSS492  SOCKET4677_AZIFS054P001C01   I2
  U1     BK75  VSS494  SOCKET4677_AZIFS054P001C01   I2
  U1     BK79  VSS495  SOCKET4677_AZIFS054P001C01   I2
  U1     BL1  VSS497  SOCKET4677_AZIFS054P001C01   I2
  U1     BL5  VSS500  SOCKET4677_AZIFS054P001C01   I2
  U1     BL9  VSS505  SOCKET4677_AZIFS054P001C01   I2
  U1     BL13  VSS498  SOCKET4677_AZIFS054P001C01   I2
  U1     BL17  VSS499  SOCKET4677_AZIFS054P001C01   I2
  U1     BL68  VSS501  SOCKET4677_AZIFS054P001C01   I2
  U1     BL70  VSS502  SOCKET4677_AZIFS054P001C01   I2
  U1     BL72  VSS503  SOCKET4677_AZIFS054P001C01   I2
  U1     BL78  VSS504  SOCKET4677_AZIFS054P001C01   I2
  U1     BM4  VSS512  SOCKET4677_AZIFS054P001C01   I2
  U1     BM8  VSS517  SOCKET4677_AZIFS054P001C01   I2
  U1     BM12  VSS506  SOCKET4677_AZIFS054P001C01   I2
  U1     BM16  VSS507  SOCKET4677_AZIFS054P001C01   I2
  U1     BM20  VSS508  SOCKET4677_AZIFS054P001C01   I2
  U1     BM22  VSS509  SOCKET4677_AZIFS054P001C01   I2
  U1     BM24  VSS510  SOCKET4677_AZIFS054P001C01   I2
  U1     BM26  VSS511  SOCKET4677_AZIFS054P001C01   I2
  U1     BM61  VSS513  SOCKET4677_AZIFS054P001C01   I2
  U1     BM73  VSS515  SOCKET4677_AZIFS054P001C01   I2
  U1     BM77  VSS516  SOCKET4677_AZIFS054P001C01   I2
  U1     BN31  VSS518  SOCKET4677_AZIFS054P001C01   I2
  U1     BN62  VSS519  SOCKET4677_AZIFS054P001C01   I2
  U1     BN70  VSS520  SOCKET4677_AZIFS054P001C01   I2
  U1     BP2  VSS524  SOCKET4677_AZIFS054P001C01   I2
  U1     BP4  VSS527  SOCKET4677_AZIFS054P001C01   I2
  U1     BP8  VSS533  SOCKET4677_AZIFS054P001C01   I2
  U1     BP12  VSS522  SOCKET4677_AZIFS054P001C01   I2
  U1     BP16  VSS523  SOCKET4677_AZIFS054P001C01   I2
  U1     BP20  VSS525  SOCKET4677_AZIFS054P001C01   I2
  U1     BP63  VSS528  SOCKET4677_AZIFS054P001C01   I2
  U1     BP71  VSS529  SOCKET4677_AZIFS054P001C01   I2
  U1     BP73  VSS530  SOCKET4677_AZIFS054P001C01   I2
  U1     BP75  VSS531  SOCKET4677_AZIFS054P001C01   I2
  U1     BP77  VSS532  SOCKET4677_AZIFS054P001C01   I2
  U1     BR5   VSS0  SOCKET4677_AZIFS054P001C01   I2
  U1     BR9  VSS572  SOCKET4677_AZIFS054P001C01   I2
  U1     BR13  VSS535  SOCKET4677_AZIFS054P001C01   I2
  U1     BR17  VSS536  SOCKET4677_AZIFS054P001C01   I2
  U1     BR27  VSS538  SOCKET4677_AZIFS054P001C01   I2
  U1     BR29  VSS539  SOCKET4677_AZIFS054P001C01   I2
  U1     BR31  VSS540  SOCKET4677_AZIFS054P001C01   I2
  U1     BR33  VSS541  SOCKET4677_AZIFS054P001C01   I2
  U1     BR35  VSS542  SOCKET4677_AZIFS054P001C01   I8
  U1     BR37  VSS543  SOCKET4677_AZIFS054P001C01   I8
  U1     BR39  VSS545  SOCKET4677_AZIFS054P001C01   I8
  U1     BR41  VSS546  SOCKET4677_AZIFS054P001C01   I8
  U1     BR43  VSS547  SOCKET4677_AZIFS054P001C01   I8
  U1     BR45  VSS548  SOCKET4677_AZIFS054P001C01   I8
  U1     BR48  VSS549  SOCKET4677_AZIFS054P001C01   I8
  U1     BR50  VSS550  SOCKET4677_AZIFS054P001C01   I8
  U1     BR52  VSS551  SOCKET4677_AZIFS054P001C01   I8
  U1     BR54  VSS552  SOCKET4677_AZIFS054P001C01   I8
  U1     BR56  VSS555  SOCKET4677_AZIFS054P001C01   I8
  U1     BR58  VSS556  SOCKET4677_AZIFS054P001C01   I8
  U1     BR64  VSS557  SOCKET4677_AZIFS054P001C01   I8
  U1     BR66  VSS559  SOCKET4677_AZIFS054P001C01   I8
  U1     BR68  VSS560  SOCKET4677_AZIFS054P001C01   I8
  U1     BR70  VSS561  SOCKET4677_AZIFS054P001C01   I8
  U1     BR72  VSS563  SOCKET4677_AZIFS054P001C01   I8
  U1     BR74  VSS564  SOCKET4677_AZIFS054P001C01   I8
  U1     BR76  VSS565  SOCKET4677_AZIFS054P001C01   I8
  U1     BR80  VSS566  SOCKET4677_AZIFS054P001C01   I8
  U1     BR82  VSS567  SOCKET4677_AZIFS054P001C01   I8
  U1     BR84  VSS568  SOCKET4677_AZIFS054P001C01   I8
  U1     BR86  VSS569  SOCKET4677_AZIFS054P001C01   I8
  U1     BR88  VSS570  SOCKET4677_AZIFS054P001C01   I8
  U1     BR90  VSS573  SOCKET4677_AZIFS054P001C01   I8
  U1     BT4  VSS577  SOCKET4677_AZIFS054P001C01   I8
  U1     BT8  VSS578  SOCKET4677_AZIFS054P001C01   I8
  U1     BT12  VSS574  SOCKET4677_AZIFS054P001C01   I8
  U1     BT16  VSS575  SOCKET4677_AZIFS054P001C01   I8
  U1     BT20  VSS576  SOCKET4677_AZIFS054P001C01   I8
  U1     BU7  VSS586  SOCKET4677_AZIFS054P001C01   I8
  U1     BU15  VSS579  SOCKET4677_AZIFS054P001C01   I8
  U1     BU19  VSS580  SOCKET4677_AZIFS054P001C01   I8
  U1     BU21  VSS581  SOCKET4677_AZIFS054P001C01   I8
  U1     BU23  VSS582  SOCKET4677_AZIFS054P001C01   I8
  U1     BU25  VSS584  SOCKET4677_AZIFS054P001C01   I8
  U1     BU31  VSS585  SOCKET4677_AZIFS054P001C01   I8
  U1     BV2  VSS590  SOCKET4677_AZIFS054P001C01   I8
  U1     BV4  VSS592  SOCKET4677_AZIFS054P001C01   I8
  U1     BV6  VSS593  SOCKET4677_AZIFS054P001C01   I8
  U1     BV8  VSS594  SOCKET4677_AZIFS054P001C01   I8
  U1     BV12  VSS587  SOCKET4677_AZIFS054P001C01   I8
  U1     BV16  VSS588  SOCKET4677_AZIFS054P001C01   I8
  U1     BV18  VSS589  SOCKET4677_AZIFS054P001C01   I8
  U1     BV20  VSS591  SOCKET4677_AZIFS054P001C01   I8
  U1     BW3  VSS600  SOCKET4677_AZIFS054P001C01   I8
  U1     BW5  VSS602  SOCKET4677_AZIFS054P001C01   I8
  U1     BW9  VSS603  SOCKET4677_AZIFS054P001C01   I8
  U1     BW13  VSS596  SOCKET4677_AZIFS054P001C01   I8
  U1     BW17  VSS597  SOCKET4677_AZIFS054P001C01   I8
  U1     BW27  VSS598  SOCKET4677_AZIFS054P001C01   I8
  U1     BW29  VSS599  SOCKET4677_AZIFS054P001C01   I8
  U1     BW31  VSS601  SOCKET4677_AZIFS054P001C01   I8
  U1     BY4  VSS607  SOCKET4677_AZIFS054P001C01   I8
  U1     BY8  VSS608  SOCKET4677_AZIFS054P001C01   I8
  U1     BY12  VSS604  SOCKET4677_AZIFS054P001C01   I8
  U1     BY16  VSS605  SOCKET4677_AZIFS054P001C01   I8
  U1     BY20  VSS606  SOCKET4677_AZIFS054P001C01   I8
  U1      C5  VSS612  SOCKET4677_AZIFS054P001C01   I8
  U1     C39  VSS609  SOCKET4677_AZIFS054P001C01   I8
  U1     C45  VSS610  SOCKET4677_AZIFS054P001C01   I8
  U1     C52  VSS613  SOCKET4677_AZIFS054P001C01   I8
  U1     C72  VSS614  SOCKET4677_AZIFS054P001C01   I8
  U1     C74  VSS615  SOCKET4677_AZIFS054P001C01   I8
  U1     C78  VSS616  SOCKET4677_AZIFS054P001C01   I8
  U1     C80  VSS617  SOCKET4677_AZIFS054P001C01   I8
  U1     C82  VSS618  SOCKET4677_AZIFS054P001C01   I8
  U1     C86  VSS619  SOCKET4677_AZIFS054P001C01   I8
  U1     CA3  VSS620  SOCKET4677_AZIFS054P001C01   I8
  U1     CA31  VSS621  SOCKET4677_AZIFS054P001C01   I8
  U1     CB4  VSS633  SOCKET4677_AZIFS054P001C01   I8
  U1     CB8  VSS651  SOCKET4677_AZIFS054P001C01   I8
  U1     CB12  VSS622  SOCKET4677_AZIFS054P001C01   I8
  U1     CB16  VSS623  SOCKET4677_AZIFS054P001C01   I8
  U1     CB20  VSS624  SOCKET4677_AZIFS054P001C01   I8
  U1     CB22  VSS625  SOCKET4677_AZIFS054P001C01   I8
  U1     CB24  VSS626  SOCKET4677_AZIFS054P001C01   I8
  U1     CB26  VSS627  SOCKET4677_AZIFS054P001C01   I8
  U1     CB28  VSS628  SOCKET4677_AZIFS054P001C01   I8
  U1     CB32  VSS629  SOCKET4677_AZIFS054P001C01   I8
  U1     CB34  VSS630  SOCKET4677_AZIFS054P001C01   I8
  U1     CB36  VSS631  SOCKET4677_AZIFS054P001C01   I8
  U1     CB38  VSS632  SOCKET4677_AZIFS054P001C01   I8
  U1     CB40  VSS634  SOCKET4677_AZIFS054P001C01   I8
  U1     CB42  VSS635  SOCKET4677_AZIFS054P001C01   I8
  U1     CB44  VSS636  SOCKET4677_AZIFS054P001C01   I8
  U1     CB47  VSS637  SOCKET4677_AZIFS054P001C01   I8
  U1     CB49  VSS638  SOCKET4677_AZIFS054P001C01   I8
  U1     CB51  VSS639  SOCKET4677_AZIFS054P001C01   I8
  U1     CB53  VSS640  SOCKET4677_AZIFS054P001C01   I8
  U1     CB55  VSS641  SOCKET4677_AZIFS054P001C01   I8
  U1     CB57  VSS642  SOCKET4677_AZIFS054P001C01   I8
  U1     CB59  VSS643  SOCKET4677_AZIFS054P001C01   I8
  U1     CB63  VSS644  SOCKET4677_AZIFS054P001C01   I8
  U1     CB65  VSS645  SOCKET4677_AZIFS054P001C01   I8
  U1     CB67  VSS646  SOCKET4677_AZIFS054P001C01   I8
  U1     CB69  VSS647  SOCKET4677_AZIFS054P001C01   I8
  U1     CB71  VSS648  SOCKET4677_AZIFS054P001C01   I8
  U1     CB73  VSS649  SOCKET4677_AZIFS054P001C01   I8
  U1     CB79  VSS650  SOCKET4677_AZIFS054P001C01   I8
  U1     CB81  VSS652  SOCKET4677_AZIFS054P001C01   I8
  U1     CB83  VSS653  SOCKET4677_AZIFS054P001C01   I8
  U1     CB85  VSS654  SOCKET4677_AZIFS054P001C01   I8
  U1     CB87  VSS655  SOCKET4677_AZIFS054P001C01   I8
  U1     CB89  VSS656  SOCKET4677_AZIFS054P001C01   I8
  U1     CC5  VSS665  SOCKET4677_AZIFS054P001C01   I8
  U1     CC9  VSS670  SOCKET4677_AZIFS054P001C01   I8
  U1     CC13  VSS660  SOCKET4677_AZIFS054P001C01   I8
  U1     CC17  VSS661  SOCKET4677_AZIFS054P001C01   I8
  U1     CC31  VSS664  SOCKET4677_AZIFS054P001C01   I8
  U1     CC62  VSS666  SOCKET4677_AZIFS054P001C01   I8
  U1     CC70  VSS667  SOCKET4677_AZIFS054P001C01   I8
  U1     CC72  VSS668  SOCKET4677_AZIFS054P001C01   I8
  U1     CC74  VSS669  SOCKET4677_AZIFS054P001C01   I8
  U1     CD4  VSS674  SOCKET4677_AZIFS054P001C01   I8
  U1     CD8  VSS678  SOCKET4677_AZIFS054P001C01   I8
  U1     CD12  VSS671  SOCKET4677_AZIFS054P001C01   I8
  U1     CD16  VSS672  SOCKET4677_AZIFS054P001C01   I8
  U1     CD20  VSS673  SOCKET4677_AZIFS054P001C01   I8
  U1     CD61  VSS675  SOCKET4677_AZIFS054P001C01   I8
  U1     CD75  VSS676  SOCKET4677_AZIFS054P001C01   I8
  U1     CD77  VSS677  SOCKET4677_AZIFS054P001C01   I8
  U1     CE3  VSS680  SOCKET4677_AZIFS054P001C01   I8
  U1     CE60  VSS681  SOCKET4677_AZIFS054P001C01   I8
  U1     CE66  VSS682  SOCKET4677_AZIFS054P001C01   I8
  U1     CE72  VSS683  SOCKET4677_AZIFS054P001C01   I8
  U1     CE76  VSS684  SOCKET4677_AZIFS054P001C01   I8
  U1     CE78  VSS685  SOCKET4677_AZIFS054P001C01   I8
  U1     CF4  VSS689  SOCKET4677_AZIFS054P001C01   I8
  U1     CF8  VSS693  SOCKET4677_AZIFS054P001C01   I8
  U1     CF12  VSS686  SOCKET4677_AZIFS054P001C01   I8
  U1     CF16  VSS687  SOCKET4677_AZIFS054P001C01   I8
  U1     CF20  VSS688  SOCKET4677_AZIFS054P001C01   I8
  U1     CF69  VSS691  SOCKET4677_AZIFS054P001C01   I8
  U1     CF71  VSS692  SOCKET4677_AZIFS054P001C01   I8
  U1     CG1  VSS694  SOCKET4677_AZIFS054P001C01   I8
  U1     CG5  VSS703  SOCKET4677_AZIFS054P001C01   I8
  U1     CG9  VSS716  SOCKET4677_AZIFS054P001C01   I8
  U1     CG13  VSS695  SOCKET4677_AZIFS054P001C01   I8
  U1     CG17  VSS696  SOCKET4677_AZIFS054P001C01   I8
  U1     CG21  VSS697  SOCKET4677_AZIFS054P001C01   I8
  U1     CG23  VSS698  SOCKET4677_AZIFS054P001C01   I8
  U1     CG25  VSS701  SOCKET4677_AZIFS054P001C01   I8
  U1     CG62  VSS704  SOCKET4677_AZIFS054P001C01   I8
  U1     CG64  VSS706  SOCKET4677_AZIFS054P001C01   I8
  U1     CG70  VSS707  SOCKET4677_AZIFS054P001C01   I8
  U1     CG72  VSS708  SOCKET4677_AZIFS054P001C01   I8
  U1     CG74  VSS710  SOCKET4677_AZIFS054P001C01   I8
  U1     CG78  VSS713  SOCKET4677_AZIFS054P001C01   I8
  U1     CH4  VSS722  SOCKET4677_AZIFS054P001C01   I8
  U1     CH8  VSS730  SOCKET4677_AZIFS054P001C01   I8
  U1     CH12  VSS718  SOCKET4677_AZIFS054P001C01   I8
  U1     CH16  VSS720  SOCKET4677_AZIFS054P001C01   I8
  U1     CH20  VSS721  SOCKET4677_AZIFS054P001C01   I8
  U1     CH67  VSS727  SOCKET4677_AZIFS054P001C01   I8
  U1     CH73  VSS728  SOCKET4677_AZIFS054P001C01   I8
  U1     CH79  VSS729  SOCKET4677_AZIFS054P001C01   I8
  U1     CH83  VSS731  SOCKET4677_AZIFS054P001C01   I8
  U1     CH85  VSS732  SOCKET4677_AZIFS054P001C01   I8
  U1     CH87  VSS733  SOCKET4677_AZIFS054P001C01   I8
  U1     CH89  VSS734  SOCKET4677_AZIFS054P001C01   I8
  U1     CJ60  VSS736  SOCKET4677_AZIFS054P001C01   I8
  U1     CJ76  VSS383  SOCKET4677_AZIFS054P001C01   I8
  U1     CJ80  VSS737  SOCKET4677_AZIFS054P001C01   I8
  U1     CK4  VSS396  SOCKET4677_AZIFS054P001C01   I8
  U1     CK8  VSS746  SOCKET4677_AZIFS054P001C01   I8
  U1     CK12  VSS740  SOCKET4677_AZIFS054P001C01   I8
  U1     CK16  VSS741  SOCKET4677_AZIFS054P001C01   I8
  U1     CK20  VSS742  SOCKET4677_AZIFS054P001C01   I8
  U1     CK26  VSS743  SOCKET4677_AZIFS054P001C01   I8
  U1     CK63  VSS744  SOCKET4677_AZIFS054P001C01   I5
  U1     CK69  VSS745  SOCKET4677_AZIFS054P001C01   I5
  U1     CK81  VSS749  SOCKET4677_AZIFS054P001C01   I5
  U1     CL1  VSS750  SOCKET4677_AZIFS054P001C01   I5
  U1     CL5  VSS754  SOCKET4677_AZIFS054P001C01   I5
  U1     CL9  VSS760  SOCKET4677_AZIFS054P001C01   I5
  U1     CL13  VSS751  SOCKET4677_AZIFS054P001C01   I5
  U1     CL17  VSS752  SOCKET4677_AZIFS054P001C01   I5
  U1     CL62  VSS755  SOCKET4677_AZIFS054P001C01   I5
  U1     CL74  VSS756  SOCKET4677_AZIFS054P001C01   I5
  U1     CL78  VSS757  SOCKET4677_AZIFS054P001C01   I5
  U1     CL80  VSS758  SOCKET4677_AZIFS054P001C01   I5
  U1     CL82  VSS759  SOCKET4677_AZIFS054P001C01   I5
  U1     CM4  VSS764  SOCKET4677_AZIFS054P001C01   I5
  U1     CM8  VSS769  SOCKET4677_AZIFS054P001C01   I5
  U1     CM12  VSS761  SOCKET4677_AZIFS054P001C01   I5
  U1     CM16  VSS436  SOCKET4677_AZIFS054P001C01   I5
  U1     CM20  VSS762  SOCKET4677_AZIFS054P001C01   I5
  U1     CM22  VSS438  SOCKET4677_AZIFS054P001C01   I5
  U1     CM24  VSS763  SOCKET4677_AZIFS054P001C01   I5
  U1     CM61  VSS765  SOCKET4677_AZIFS054P001C01   I5
  U1     CM65  VSS766  SOCKET4677_AZIFS054P001C01   I5
  U1     CM67  VSS767  SOCKET4677_AZIFS054P001C01   I5
  U1     CM79  VSS768  SOCKET4677_AZIFS054P001C01   I5
  U1     CM81  VSS770  SOCKET4677_AZIFS054P001C01   I5
  U1     CM83  VSS771  SOCKET4677_AZIFS054P001C01   I5
  U1     CM85  VSS772  SOCKET4677_AZIFS054P001C01   I5
  U1     CN68  VSS773  SOCKET4677_AZIFS054P001C01   I5
  U1     CN70  VSS774  SOCKET4677_AZIFS054P001C01   I5
  U1     CN72  VSS775  SOCKET4677_AZIFS054P001C01   I5
  U1     CN74  VSS777  SOCKET4677_AZIFS054P001C01   I5
  U1     CN76  VSS471  SOCKET4677_AZIFS054P001C01   I5
  U1     CN84  VSS778  SOCKET4677_AZIFS054P001C01   I5
  U1     CN86  VSS779  SOCKET4677_AZIFS054P001C01   I5
  U1     CP4  VSS782  SOCKET4677_AZIFS054P001C01   I5
  U1     CP8  VSS785  SOCKET4677_AZIFS054P001C01   I5
  U1     CP12  VSS780  SOCKET4677_AZIFS054P001C01   I5
  U1     CP16  VSS478  SOCKET4677_AZIFS054P001C01   I5
  U1     CP18  VSS781  SOCKET4677_AZIFS054P001C01   I5
  U1     CP75  VSS783  SOCKET4677_AZIFS054P001C01   I5
  U1     CP77  VSS784  SOCKET4677_AZIFS054P001C01   I5
  U1     CP79  VSS493  SOCKET4677_AZIFS054P001C01   I5
  U1     CP83  VSS786  SOCKET4677_AZIFS054P001C01   I5
  U1     CP87  VSS787  SOCKET4677_AZIFS054P001C01   I5
  U1     CP91  VSS788  SOCKET4677_AZIFS054P001C01   I5
  U1     CR1  VSS789  SOCKET4677_AZIFS054P001C01   I5
  U1     CR5  VSS794  SOCKET4677_AZIFS054P001C01   I5
  U1     CR9  VSS801  SOCKET4677_AZIFS054P001C01   I5
  U1     CR11  VSS790  SOCKET4677_AZIFS054P001C01   I5
  U1     CR13  VSS792  SOCKET4677_AZIFS054P001C01   I5
  U1     CR17  VSS793  SOCKET4677_AZIFS054P001C01   I5
  U1     CR62  VSS795  SOCKET4677_AZIFS054P001C01   I5
  U1     CR64  VSS796  SOCKET4677_AZIFS054P001C01   I5
  U1     CR78  VSS514  SOCKET4677_AZIFS054P001C01   I5
  U1     CR84  VSS797  SOCKET4677_AZIFS054P001C01   I5
  U1     CR88  VSS800  SOCKET4677_AZIFS054P001C01   I5
  U1     CR90  VSS803  SOCKET4677_AZIFS054P001C01   I5
  U1     CT4  VSS526  SOCKET4677_AZIFS054P001C01   I5
  U1     CT8  VSS534  SOCKET4677_AZIFS054P001C01   I5
  U1     CT10  VSS804  SOCKET4677_AZIFS054P001C01   I5
  U1     CT12  VSS805  SOCKET4677_AZIFS054P001C01   I5
  U1     CT16  VSS521  SOCKET4677_AZIFS054P001C01   I5
  U1     CT69  VSS810  SOCKET4677_AZIFS054P001C01   I5
  U1     CT73  VSS811  SOCKET4677_AZIFS054P001C01   I5
  U1     CT81  VSS812  SOCKET4677_AZIFS054P001C01   I5
  U1     CT89  VSS537  SOCKET4677_AZIFS054P001C01   I5
  U1     CU19  VSS813  SOCKET4677_AZIFS054P001C01   I5
  U1     CU21  VSS814  SOCKET4677_AZIFS054P001C01   I5
  U1     CU23  VSS815  SOCKET4677_AZIFS054P001C01   I5
  U1     CU25  VSS544  SOCKET4677_AZIFS054P001C01   I5
  U1     CU60  VSS816  SOCKET4677_AZIFS054P001C01   I5
  U1     CU66  VSS818  SOCKET4677_AZIFS054P001C01   I5
  U1     CU68  VSS819  SOCKET4677_AZIFS054P001C01   I5
  U1     CU72  VSS553  SOCKET4677_AZIFS054P001C01   I5
  U1     CU78  VSS554  SOCKET4677_AZIFS054P001C01   I5
  U1     CU84  VSS822  SOCKET4677_AZIFS054P001C01   I5
  U1     CU88  VSS823  SOCKET4677_AZIFS054P001C01   I5
  U1     CV4  VSS825  SOCKET4677_AZIFS054P001C01   I5
  U1     CV8  VSS827  SOCKET4677_AZIFS054P001C01   I5
  U1     CV12  VSS824  SOCKET4677_AZIFS054P001C01   I5
  U1     CV16  VSS558  SOCKET4677_AZIFS054P001C01   I5
  U1     CV26  VSS562  SOCKET4677_AZIFS054P001C01   I5
  U1     CV75  VSS826  SOCKET4677_AZIFS054P001C01   I5
  U1     CV79  VSS571  SOCKET4677_AZIFS054P001C01   I5
  U1     CV83  VSS828  SOCKET4677_AZIFS054P001C01   I5
  U1     CV87  VSS831  SOCKET4677_AZIFS054P001C01   I5
  U1     CV91  VSS833  SOCKET4677_AZIFS054P001C01   I5
  U1     CW1  VSS834  SOCKET4677_AZIFS054P001C01   I5
  U1     CW5  VSS838  SOCKET4677_AZIFS054P001C01   I5
  U1     CW9  VSS850  SOCKET4677_AZIFS054P001C01   I5
  U1     CW13  VSS836  SOCKET4677_AZIFS054P001C01   I5
  U1     CW17  VSS837  SOCKET4677_AZIFS054P001C01   I5
  U1     CW33  VSS583  SOCKET4677_AZIFS054P001C01   I5
  U1     CW70  VSS595  SOCKET4677_AZIFS054P001C01   I5
  U1     CW72  VSS840  SOCKET4677_AZIFS054P001C01   I5
  U1     CW78  VSS843  SOCKET4677_AZIFS054P001C01   I5
  U1     CW84  VSS846  SOCKET4677_AZIFS054P001C01   I5
  U1     CW88  VSS848  SOCKET4677_AZIFS054P001C01   I5
  U1     CY4  VSS611  SOCKET4677_AZIFS054P001C01   I5
  U1     CY8  VSS860  SOCKET4677_AZIFS054P001C01   I5
  U1     CY12  VSS851  SOCKET4677_AZIFS054P001C01   I5
  U1     CY16  VSS852  SOCKET4677_AZIFS054P001C01   I5
  U1     CY18  VSS853  SOCKET4677_AZIFS054P001C01   I5
  U1     CY26  VSS854  SOCKET4677_AZIFS054P001C01   I5
  U1     CY30  VSS855  SOCKET4677_AZIFS054P001C01   I5
  U1     CY63  VSS856  SOCKET4677_AZIFS054P001C01   I5
  U1     CY73  VSS858  SOCKET4677_AZIFS054P001C01   I5
  U1     CY77  VSS859  SOCKET4677_AZIFS054P001C01   I5
  U1     CY81  VSS862  SOCKET4677_AZIFS054P001C01   I5
  U1     CY83  VSS863  SOCKET4677_AZIFS054P001C01   I5
  U1      D6  VSS899  SOCKET4677_AZIFS054P001C01   I8
  U1      D8  VSS663  SOCKET4677_AZIFS054P001C01   I8
  U1     D10  VSS864  SOCKET4677_AZIFS054P001C01   I8
  U1     D12  VSS865  SOCKET4677_AZIFS054P001C01   I8
  U1     D14  VSS866  SOCKET4677_AZIFS054P001C01   I8
  U1     D16  VSS868  SOCKET4677_AZIFS054P001C01   I8
  U1     D18  VSS869  SOCKET4677_AZIFS054P001C01   I8
  U1     D20  VSS871  SOCKET4677_AZIFS054P001C01   I8
  U1     D22  VSS873  SOCKET4677_AZIFS054P001C01   I8
  U1     D24  VSS874  SOCKET4677_AZIFS054P001C01   I8
  U1     D26  VSS875  SOCKET4677_AZIFS054P001C01   I8
  U1     D28  VSS876  SOCKET4677_AZIFS054P001C01   I8
  U1     D30  VSS877  SOCKET4677_AZIFS054P001C01   I8
  U1     D32  VSS878  SOCKET4677_AZIFS054P001C01   I8
  U1     D34  VSS879  SOCKET4677_AZIFS054P001C01   I8
  U1     D36  VSS881  SOCKET4677_AZIFS054P001C01   I8
  U1     D38  VSS884  SOCKET4677_AZIFS054P001C01   I8
  U1     D40  VSS885  SOCKET4677_AZIFS054P001C01   I8
  U1     D42  VSS886  SOCKET4677_AZIFS054P001C01   I8
  U1     D44  VSS888  SOCKET4677_AZIFS054P001C01   I8
  U1     D47  VSS889  SOCKET4677_AZIFS054P001C01   I8
  U1     D49  VSS891  SOCKET4677_AZIFS054P001C01   I8
  U1     D51  VSS892  SOCKET4677_AZIFS054P001C01   I8
  U1     D53  VSS895  SOCKET4677_AZIFS054P001C01   I8
  U1     D55  VSS896  SOCKET4677_AZIFS054P001C01   I8
  U1     D57  VSS897  SOCKET4677_AZIFS054P001C01   I8
  U1     D59  VSS898  SOCKET4677_AZIFS054P001C01   I8
  U1     D61  VSS900  SOCKET4677_AZIFS054P001C01   I8
  U1     D63  VSS657  SOCKET4677_AZIFS054P001C01   I8
  U1     D65  VSS658  SOCKET4677_AZIFS054P001C01   I8
  U1     D67  VSS659  SOCKET4677_AZIFS054P001C01   I8
  U1     D69  VSS901  SOCKET4677_AZIFS054P001C01   I8
  U1     D71  VSS902  SOCKET4677_AZIFS054P001C01   I8
  U1     D79  VSS662  SOCKET4677_AZIFS054P001C01   I8
  U1     D81  VSS906  SOCKET4677_AZIFS054P001C01   I8
  U1     D83  VSS907  SOCKET4677_AZIFS054P001C01   I8
  U1     DA19  VSS910  SOCKET4677_AZIFS054P001C01   I5
  U1     DA23  VSS911  SOCKET4677_AZIFS054P001C01   I5
  U1     DA25  VSS912  SOCKET4677_AZIFS054P001C01   I5
  U1     DA29  VSS913  SOCKET4677_AZIFS054P001C01   I5
  U1     DA31  VSS914  SOCKET4677_AZIFS054P001C01   I5
  U1     DA33  VSS915  SOCKET4677_AZIFS054P001C01   I5
  U1     DA35  VSS916  SOCKET4677_AZIFS054P001C01   I5
  U1     DA37  VSS917  SOCKET4677_AZIFS054P001C01   I5
  U1     DA41  VSS918  SOCKET4677_AZIFS054P001C01   I5
  U1     DA43  VSS679  SOCKET4677_AZIFS054P001C01   I5
  U1     DA48  VSS919  SOCKET4677_AZIFS054P001C01   I5
  U1     DA50  VSS920  SOCKET4677_AZIFS054P001C01   I5
  U1     DA54  VSS921  SOCKET4677_AZIFS054P001C01   I5
  U1     DA56  VSS922  SOCKET4677_AZIFS054P001C01   I5
  U1     DA58  VSS923  SOCKET4677_AZIFS054P001C01   I5
  U1     DA60  VSS924  SOCKET4677_AZIFS054P001C01   I5
  U1     DA62  VSS925  SOCKET4677_AZIFS054P001C01   I5
  U1     DA66  VSS926  SOCKET4677_AZIFS054P001C01   I5
  U1     DA68  VSS690  SOCKET4677_AZIFS054P001C01   I5
  U1     DA72  VSS927  SOCKET4677_AZIFS054P001C01   I5
  U1     DA74  VSS928  SOCKET4677_AZIFS054P001C01   I5
  U1     DA80  VSS929  SOCKET4677_AZIFS054P001C01   I5
  U1     DA82  VSS930  SOCKET4677_AZIFS054P001C01   I5
  U1     DA84  VSS931  SOCKET4677_AZIFS054P001C01   I5
  U1     DA88  VSS932  SOCKET4677_AZIFS054P001C01   I5
  U1     DB4  VSS939  SOCKET4677_AZIFS054P001C01   I5
  U1     DB8  VSS947  SOCKET4677_AZIFS054P001C01   I5
  U1     DB12  VSS933  SOCKET4677_AZIFS054P001C01   I5
  U1     DB16  VSS699  SOCKET4677_AZIFS054P001C01   I5
  U1     DB20  VSS700  SOCKET4677_AZIFS054P001C01   I5
  U1     DB22  VSS935  SOCKET4677_AZIFS054P001C01   I5
  U1     DB26  VSS702  SOCKET4677_AZIFS054P001C01   I5
  U1     DB28  VSS936  SOCKET4677_AZIFS054P001C01   I5
  U1     DB32  VSS937  SOCKET4677_AZIFS054P001C01   I5
  U1     DB34  VSS705  SOCKET4677_AZIFS054P001C01   I5
  U1     DB38  VSS938  SOCKET4677_AZIFS054P001C01   I5
  U1     DB40  VSS940  SOCKET4677_AZIFS054P001C01   I5
  U1     DB44  VSS709  SOCKET4677_AZIFS054P001C01   I5
  U1     DB47  VSS941  SOCKET4677_AZIFS054P001C01   I5
  U1     DB51  VSS711  SOCKET4677_AZIFS054P001C01   I5
  U1     DB53  VSS712  SOCKET4677_AZIFS054P001C01   I5
  U1     DB57  VSS942  SOCKET4677_AZIFS054P001C01   I5
  U1     DB59  VSS714  SOCKET4677_AZIFS054P001C01   I5
  U1     DB63  VSS715  SOCKET4677_AZIFS054P001C01   I5
  U1     DB65  VSS943  SOCKET4677_AZIFS054P001C01   I5
  U1     DB69  VSS717  SOCKET4677_AZIFS054P001C01   I5
  U1     DB71  VSS944  SOCKET4677_AZIFS054P001C01   I5
  U1     DB75  VSS719  SOCKET4677_AZIFS054P001C01   I5
  U1     DB77  VSS946  SOCKET4677_AZIFS054P001C01   I5
  U1     DB87  VSS948  SOCKET4677_AZIFS054P001C01   I5
  U1     DB91  VSS723  SOCKET4677_AZIFS054P001C01   I2
  U1     DC1  VSS724  SOCKET4677_AZIFS054P001C01   I2
  U1     DC5  VSS953  SOCKET4677_AZIFS054P001C01   I2
  U1     DC9  VSS963  SOCKET4677_AZIFS054P001C01   I2
  U1     DC13  VSS725  SOCKET4677_AZIFS054P001C01   I2
  U1     DC21  VSS726  SOCKET4677_AZIFS054P001C01   I2
  U1     DC27  VSS949  SOCKET4677_AZIFS054P001C01   I2
  U1     DC33  VSS950  SOCKET4677_AZIFS054P001C01   I2
  U1     DC39  VSS951  SOCKET4677_AZIFS054P001C01   I2
  U1     DC45  VSS952  SOCKET4677_AZIFS054P001C01   I2
  U1     DC52  VSS735  SOCKET4677_AZIFS054P001C01   I2
  U1     DC58  VSS738  SOCKET4677_AZIFS054P001C01   I2
  U1     DC64  VSS739  SOCKET4677_AZIFS054P001C01   I2
  U1     DC70  VSS954  SOCKET4677_AZIFS054P001C01   I2
  U1     DC76  VSS956  SOCKET4677_AZIFS054P001C01   I2
  U1     DC78  VSS958  SOCKET4677_AZIFS054P001C01   I2
  U1     DC80  VSS960  SOCKET4677_AZIFS054P001C01   I2
  U1     DC84  VSS961  SOCKET4677_AZIFS054P001C01   I2
  U1     DC88  VSS962  SOCKET4677_AZIFS054P001C01   I2
  U1     DD4  VSS964  SOCKET4677_AZIFS054P001C01   I2
  U1     DD8  VSS967  SOCKET4677_AZIFS054P001C01   I2
  U1     DD12  VSS747  SOCKET4677_AZIFS054P001C01   I2
  U1     DD16  VSS748  SOCKET4677_AZIFS054P001C01   I2
  U1     DD49  VSS753  SOCKET4677_AZIFS054P001C01   I2
  U1     DD79  VSS965  SOCKET4677_AZIFS054P001C01   I2
  U1     DE17  VSS970  SOCKET4677_AZIFS054P001C01   I2
  U1     DE19  VSS971  SOCKET4677_AZIFS054P001C01   I2
  U1     DE21  VSS972  SOCKET4677_AZIFS054P001C01   I2
  U1     DE23  VSS974  SOCKET4677_AZIFS054P001C01   I2
  U1     DE25  VSS975  SOCKET4677_AZIFS054P001C01   I2
  U1     DE27  VSS977  SOCKET4677_AZIFS054P001C01   I2
  U1     DE29  VSS978  SOCKET4677_AZIFS054P001C01   I2
  U1     DE31  VSS981  SOCKET4677_AZIFS054P001C01   I2
  U1     DE33  VSS982  SOCKET4677_AZIFS054P001C01   I2
  U1     DE35  VSS983  SOCKET4677_AZIFS054P001C01   I2
  U1     DE37  VSS984  SOCKET4677_AZIFS054P001C01   I2
  U1     DE39  VSS776  SOCKET4677_AZIFS054P001C01   I2
  U1     DE41  VSS986  SOCKET4677_AZIFS054P001C01   I2
  U1     DE43  VSS987  SOCKET4677_AZIFS054P001C01   I2
  U1     DE45  VSS988  SOCKET4677_AZIFS054P001C01   I2
  U1     DE48  VSS989  SOCKET4677_AZIFS054P001C01   I2
  U1     DE50  VSS991  SOCKET4677_AZIFS054P001C01   I2
  U1     DE52  VSS992  SOCKET4677_AZIFS054P001C01   I2
  U1     DE54  VSS994  SOCKET4677_AZIFS054P001C01   I2
  U1     DE56  VSS995  SOCKET4677_AZIFS054P001C01   I2
  U1     DE58  VSS996  SOCKET4677_AZIFS054P001C01   I2
  U1     DE60  VSS997  SOCKET4677_AZIFS054P001C01   I2
  U1     DE62  VSS999  SOCKET4677_AZIFS054P001C01   I2
  U1     DE64  VSS1001  SOCKET4677_AZIFS054P001C01   I2
  U1     DE66  VSS1004  SOCKET4677_AZIFS054P001C01   I2
  U1     DE68  VSS1007  SOCKET4677_AZIFS054P001C01   I2
  U1     DE70  VSS791  SOCKET4677_AZIFS054P001C01   I2
  U1     DE72  VSS1008  SOCKET4677_AZIFS054P001C01   I2
  U1     DE74  VSS1009  SOCKET4677_AZIFS054P001C01   I2
  U1     DE76  VSS1010  SOCKET4677_AZIFS054P001C01   I2
  U1     DE82  VSS1011  SOCKET4677_AZIFS054P001C01   I2
  U1     DE84  VSS1012  SOCKET4677_AZIFS054P001C01   I2
  U1     DE88  VSS1015  SOCKET4677_AZIFS054P001C01   I2
  U1     DF4  VSS1017  SOCKET4677_AZIFS054P001C01   I2
  U1     DF8  VSS1019  SOCKET4677_AZIFS054P001C01   I2
  U1     DF12  VSS798  SOCKET4677_AZIFS054P001C01   I2
  U1     DF16  VSS799  SOCKET4677_AZIFS054P001C01   I2
  U1     DF49  VSS802  SOCKET4677_AZIFS054P001C01   I2
  U1     DF79  VSS1018  SOCKET4677_AZIFS054P001C01   I2
  U1     DF87  VSS1020  SOCKET4677_AZIFS054P001C01   I2
  U1     DF91  VSS806  SOCKET4677_AZIFS054P001C01   I2
  U1     DG1  VSS807  SOCKET4677_AZIFS054P001C01   I2
  U1     DG5  VSS1031  SOCKET4677_AZIFS054P001C01   I2
  U1     DG9  VSS1038  SOCKET4677_AZIFS054P001C01   I2
  U1     DG13  VSS808  SOCKET4677_AZIFS054P001C01   I2
  U1     DG21  VSS809  SOCKET4677_AZIFS054P001C01   I2
  U1     DG27  VSS1022  SOCKET4677_AZIFS054P001C01   I2
  U1     DG33  VSS1024  SOCKET4677_AZIFS054P001C01   I2
  U1     DG39  VSS1027  SOCKET4677_AZIFS054P001C01   I2
  U1     DG45  VSS1030  SOCKET4677_AZIFS054P001C01   I2
  U1     DG52  VSS817  SOCKET4677_AZIFS054P001C01   I2
  U1     DG58  VSS820  SOCKET4677_AZIFS054P001C01   I2
  U1     DG64  VSS821  SOCKET4677_AZIFS054P001C01   I2
  U1     DG70  VSS1032  SOCKET4677_AZIFS054P001C01   I2
  U1     DG76  VSS1033  SOCKET4677_AZIFS054P001C01   I2
  U1     DG80  VSS1034  SOCKET4677_AZIFS054P001C01   I2
  U1     DG84  VSS1035  SOCKET4677_AZIFS054P001C01   I2
  U1     DG88  VSS1037  SOCKET4677_AZIFS054P001C01   I2
  U1     DH4  VSS1044  SOCKET4677_AZIFS054P001C01   I2
  U1     DH8  VSS1057  SOCKET4677_AZIFS054P001C01   I2
  U1     DH12  VSS1039  SOCKET4677_AZIFS054P001C01   I2
  U1     DH16  VSS829  SOCKET4677_AZIFS054P001C01   I2
  U1     DH20  VSS830  SOCKET4677_AZIFS054P001C01   I2
  U1     DH22  VSS1040  SOCKET4677_AZIFS054P001C01   I2
  U1     DH26  VSS832  SOCKET4677_AZIFS054P001C01   I2
  U1     DH28  VSS1041  SOCKET4677_AZIFS054P001C01   I2
  U1     DH32  VSS1042  SOCKET4677_AZIFS054P001C01   I2
  U1     DH34  VSS835  SOCKET4677_AZIFS054P001C01   I2
  U1     DH38  VSS1043  SOCKET4677_AZIFS054P001C01   I2
  U1     DH40  VSS1045  SOCKET4677_AZIFS054P001C01   I2
  U1     DH44  VSS839  SOCKET4677_AZIFS054P001C01   I2
  U1     DH47  VSS1046  SOCKET4677_AZIFS054P001C01   I2
  U1     DH51  VSS841  SOCKET4677_AZIFS054P001C01   I2
  U1     DH53  VSS842  SOCKET4677_AZIFS054P001C01   I2
  U1     DH57  VSS1049  SOCKET4677_AZIFS054P001C01   I2
  U1     DH59  VSS844  SOCKET4677_AZIFS054P001C01   I2
  U1     DH63  VSS845  SOCKET4677_AZIFS054P001C01   I2
  U1     DH65  VSS1053  SOCKET4677_AZIFS054P001C01   I2
  U1     DH69  VSS847  SOCKET4677_AZIFS054P001C01   I2
  U1     DH71  VSS1055  SOCKET4677_AZIFS054P001C01   I2
  U1     DH75  VSS849  SOCKET4677_AZIFS054P001C01   I2
  U1     DH77  VSS1056  SOCKET4677_AZIFS054P001C01   I2
  U1     DH85  VSS1058  SOCKET4677_AZIFS054P001C01   I2
  U1     DJ19  VSS1061  SOCKET4677_AZIFS054P001C01   I2
  U1     DJ23  VSS1062  SOCKET4677_AZIFS054P001C01   I2
  U1     DJ25  VSS857  SOCKET4677_AZIFS054P001C01   I2
  U1     DJ29  VSS1065  SOCKET4677_AZIFS054P001C01   I2
  U1     DJ31  VSS1066  SOCKET4677_AZIFS054P001C01   I2
  U1     DJ35  VSS861  SOCKET4677_AZIFS054P001C01   I2
  U1     DJ37  VSS1067  SOCKET4677_AZIFS054P001C01   I2
  U1     DJ41  VSS1068  SOCKET4677_AZIFS054P001C01   I2
  U1     DJ43  VSS1069  SOCKET4677_AZIFS054P001C01   I2
  U1     DJ48  VSS1070  SOCKET4677_AZIFS054P001C01   I2
  U1     DJ50  VSS1071  SOCKET4677_AZIFS054P001C01   I2
  U1     DJ54  VSS867  SOCKET4677_AZIFS054P001C01   I2
  U1     DJ56  VSS1072  SOCKET4677_AZIFS054P001C01   I2
  U1     DJ60  VSS1073  SOCKET4677_AZIFS054P001C01   I2
  U1     DJ62  VSS870  SOCKET4677_AZIFS054P001C01   I2
  U1     DJ66  VSS1074  SOCKET4677_AZIFS054P001C01   I2
  U1     DJ68  VSS872  SOCKET4677_AZIFS054P001C01   I2
  U1     DJ72  VSS1075  SOCKET4677_AZIFS054P001C01   I2
  U1     DJ74  VSS1076  SOCKET4677_AZIFS054P001C01   I2
  U1     DJ80  VSS1078  SOCKET4677_AZIFS054P001C01   I2
  U1     DJ82  VSS1079  SOCKET4677_AZIFS054P001C01   I2
  U1     DJ84  VSS1080  SOCKET4677_AZIFS054P001C01   I2
  U1     DJ88  VSS1081  SOCKET4677_AZIFS054P001C01   I2
  U1     DK4  VSS1085  SOCKET4677_AZIFS054P001C01   I2
  U1     DK8  VSS1090  SOCKET4677_AZIFS054P001C01   I2
  U1     DK12  VSS880  SOCKET4677_AZIFS054P001C01   I2
  U1     DK16  VSS1082  SOCKET4677_AZIFS054P001C01   I2
  U1     DK18  VSS882  SOCKET4677_AZIFS054P001C01   I2
  U1     DK24  VSS883  SOCKET4677_AZIFS054P001C01   I2
  U1     DK30  VSS1083  SOCKET4677_AZIFS054P001C01   I2
  U1     DK36  VSS1084  SOCKET4677_AZIFS054P001C01   I2
  U1     DK42  VSS887  SOCKET4677_AZIFS054P001C01   I2
  U1     DK49  VSS1086  SOCKET4677_AZIFS054P001C01   I2
  U1     DK55  VSS890  SOCKET4677_AZIFS054P001C01   I2
  U1     DK61  VSS893  SOCKET4677_AZIFS054P001C01   I2
  U1     DK67  VSS894  SOCKET4677_AZIFS054P001C01   I2
  U1     DK73  VSS1087  SOCKET4677_AZIFS054P001C01   I2
  U1     DK77  VSS1088  SOCKET4677_AZIFS054P001C01   I2
  U1     DK79  VSS1089  SOCKET4677_AZIFS054P001C01   I2
  U1     DK81  VSS1091  SOCKET4677_AZIFS054P001C01   I2
  U1     DK83  VSS1092  SOCKET4677_AZIFS054P001C01   I2
  U1     DK87  VSS1093  SOCKET4677_AZIFS054P001C01   I2
  U1     DK91  VSS1094  SOCKET4677_AZIFS054P001C01   I2
  U1     DL1  VSS903  SOCKET4677_AZIFS054P001C01   I2
  U1     DL5  VSS908  SOCKET4677_AZIFS054P001C01   I2
  U1     DL9  VSS1099  SOCKET4677_AZIFS054P001C01   I2
  U1     DL13  VSS904  SOCKET4677_AZIFS054P001C01   I2
  U1     DL17  VSS905  SOCKET4677_AZIFS054P001C01   I2
  U1     DL39  VSS1095  SOCKET4677_AZIFS054P001C01   I2
  U1     DL52  VSS909  SOCKET4677_AZIFS054P001C01   I2
  U1     DL84  VSS1096  SOCKET4677_AZIFS054P001C01   I2
  U1     DL88  VSS1098  SOCKET4677_AZIFS054P001C01   I2
  U1     DM4  VSS1117  SOCKET4677_AZIFS054P001C01   I8
  U1     DM8  VSS1140  SOCKET4677_AZIFS054P001C01   I8
  U1     DM12  VSS1100  SOCKET4677_AZIFS054P001C01   I8
  U1     DM16  VSS1101  SOCKET4677_AZIFS054P001C01   I8
  U1     DM18  VSS1102  SOCKET4677_AZIFS054P001C01   I8
  U1     DM20  VSS1103  SOCKET4677_AZIFS054P001C01   I8
  U1     DM22  VSS1104  SOCKET4677_AZIFS054P001C01   I8
  U1     DM24  VSS1105  SOCKET4677_AZIFS054P001C01   I8
  U1     DM26  VSS1106  SOCKET4677_AZIFS054P001C01   I8
  U1     DM28  VSS1107  SOCKET4677_AZIFS054P001C01   I8
  U1     DM30  VSS1108  SOCKET4677_AZIFS054P001C01   I8
  U1     DM32  VSS1109  SOCKET4677_AZIFS054P001C01   I8
  U1     DM34  VSS1110  SOCKET4677_AZIFS054P001C01   I8
  U1     DM36  VSS1113  SOCKET4677_AZIFS054P001C01   I8
  U1     DM38  VSS1114  SOCKET4677_AZIFS054P001C01   I8
  U1     DM40  VSS1118  SOCKET4677_AZIFS054P001C01   I8
  U1     DM42  VSS1119  SOCKET4677_AZIFS054P001C01   I8
  U1     DM44  VSS1120  SOCKET4677_AZIFS054P001C01   I8
  U1     DM47  VSS1121  SOCKET4677_AZIFS054P001C01   I8
  U1     DM49  VSS1122  SOCKET4677_AZIFS054P001C01   I8
  U1     DM51  VSS934  SOCKET4677_AZIFS054P001C01   I8
  U1     DM53  VSS1123  SOCKET4677_AZIFS054P001C01   I8
  U1     DM55  VSS1124  SOCKET4677_AZIFS054P001C01   I8
  U1     DM57  VSS1127  SOCKET4677_AZIFS054P001C01   I8
  U1     DM59  VSS1128  SOCKET4677_AZIFS054P001C01   I8
  U1     DM61  VSS1130  SOCKET4677_AZIFS054P001C01   I8
  U1     DM63  VSS1132  SOCKET4677_AZIFS054P001C01   I8
  U1     DM65  VSS1133  SOCKET4677_AZIFS054P001C01   I8
  U1     DM67  VSS1134  SOCKET4677_AZIFS054P001C01   I8
  U1     DM69  VSS1135  SOCKET4677_AZIFS054P001C01   I8
  U1     DM71  VSS1136  SOCKET4677_AZIFS054P001C01   I8
  U1     DM73  VSS945  SOCKET4677_AZIFS054P001C01   I8
  U1     DM75  VSS1137  SOCKET4677_AZIFS054P001C01   I8
  U1     DM77  VSS1138  SOCKET4677_AZIFS054P001C01   I8
  U1     DM79  VSS1139  SOCKET4677_AZIFS054P001C01   I8
  U1     DN17  VSS955  SOCKET4677_AZIFS054P001C01   I8
  U1     DN39  VSS957  SOCKET4677_AZIFS054P001C01   I8
  U1     DN52  VSS959  SOCKET4677_AZIFS054P001C01   I8
  U1     DN78  VSS1143  SOCKET4677_AZIFS054P001C01   I8
  U1     DN84  VSS1147  SOCKET4677_AZIFS054P001C01   I8
  U1     DN88  VSS1148  SOCKET4677_AZIFS054P001C01   I8
  U1     DP4  VSS1152  SOCKET4677_AZIFS054P001C01   I8
  U1     DP8  VSS1157  SOCKET4677_AZIFS054P001C01   I8
  U1     DP12  VSS966  SOCKET4677_AZIFS054P001C01   I8
  U1     DP16  VSS1149  SOCKET4677_AZIFS054P001C01   I8
  U1     DP18  VSS968  SOCKET4677_AZIFS054P001C01   I8
  U1     DP24  VSS969  SOCKET4677_AZIFS054P001C01   I8
  U1     DP30  VSS1150  SOCKET4677_AZIFS054P001C01   I8
  U1     DP36  VSS1151  SOCKET4677_AZIFS054P001C01   I8
  U1     DP42  VSS973  SOCKET4677_AZIFS054P001C01   I8
  U1     DP49  VSS1153  SOCKET4677_AZIFS054P001C01   I8
  U1     DP55  VSS976  SOCKET4677_AZIFS054P001C01   I8
  U1     DP61  VSS979  SOCKET4677_AZIFS054P001C01   I8
  U1     DP67  VSS980  SOCKET4677_AZIFS054P001C01   I8
  U1     DP73  VSS1154  SOCKET4677_AZIFS054P001C01   I8
  U1     DP81  VSS1159  SOCKET4677_AZIFS054P001C01   I8
  U1     DP87  VSS1160  SOCKET4677_AZIFS054P001C01   I8
  U1     DP91  VSS985  SOCKET4677_AZIFS054P001C01   I8
  U1     DR1  VSS1162  SOCKET4677_AZIFS054P001C01   I8
  U1     DR5  VSS998  SOCKET4677_AZIFS054P001C01   I8
  U1     DR9  VSS1187  SOCKET4677_AZIFS054P001C01   I8
  U1     DR13  VSS1164  SOCKET4677_AZIFS054P001C01   I8
  U1     DR19  VSS1166  SOCKET4677_AZIFS054P001C01   I8
  U1     DR23  VSS1169  SOCKET4677_AZIFS054P001C01   I8
  U1     DR25  VSS990  SOCKET4677_AZIFS054P001C01   I8
  U1     DR29  VSS1172  SOCKET4677_AZIFS054P001C01   I8
  U1     DR31  VSS1173  SOCKET4677_AZIFS054P001C01   I8
  U1     DR35  VSS993  SOCKET4677_AZIFS054P001C01   I8
  U1     DR37  VSS1174  SOCKET4677_AZIFS054P001C01   I8
  U1     DR41  VSS1175  SOCKET4677_AZIFS054P001C01   I8
  U1     DR43  VSS1176  SOCKET4677_AZIFS054P001C01   I8
  U1     DR48  VSS1177  SOCKET4677_AZIFS054P001C01   I8
  U1     DR50  VSS1178  SOCKET4677_AZIFS054P001C01   I8
  U1     DR54  VSS1000  SOCKET4677_AZIFS054P001C01   I8
  U1     DR56  VSS1179  SOCKET4677_AZIFS054P001C01   I8
  U1     DR60  VSS1002  SOCKET4677_AZIFS054P001C01   I8
  U1     DR62  VSS1003  SOCKET4677_AZIFS054P001C01   I8
  U1     DR66  VSS1181  SOCKET4677_AZIFS054P001C01   I8
  U1     DR68  VSS1005  SOCKET4677_AZIFS054P001C01   I8
  U1     DR72  VSS1006  SOCKET4677_AZIFS054P001C01   I8
  U1     DR74  VSS1182  SOCKET4677_AZIFS054P001C01   I8
  U1     DR78  VSS1183  SOCKET4677_AZIFS054P001C01   I8
  U1     DR84  VSS1184  SOCKET4677_AZIFS054P001C01   I8
  U1     DR88  VSS1186  SOCKET4677_AZIFS054P001C01   I8
  U1     DT4  VSS1021  SOCKET4677_AZIFS054P001C01   I8
  U1     DT8  VSS1207  SOCKET4677_AZIFS054P001C01   I8
  U1     DT12  VSS1189  SOCKET4677_AZIFS054P001C01   I8
  U1     DT16  VSS1013  SOCKET4677_AZIFS054P001C01   I8
  U1     DT20  VSS1014  SOCKET4677_AZIFS054P001C01   I8
  U1     DT22  VSS1190  SOCKET4677_AZIFS054P001C01   I8
  U1     DT26  VSS1016  SOCKET4677_AZIFS054P001C01   I8
  U1     DT28  VSS1191  SOCKET4677_AZIFS054P001C01   I8
  U1     DT32  VSS1192  SOCKET4677_AZIFS054P001C01   I8
  U1     DT34  VSS1194  SOCKET4677_AZIFS054P001C01   I8
  U1     DT38  VSS1196  SOCKET4677_AZIFS054P001C01   I8
  U1     DT40  VSS1199  SOCKET4677_AZIFS054P001C01   I8
  U1     DT44  VSS1023  SOCKET4677_AZIFS054P001C01   I8
  U1     DT47  VSS1201  SOCKET4677_AZIFS054P001C01   I8
  U1     DT51  VSS1025  SOCKET4677_AZIFS054P001C01   I8
  U1     DT53  VSS1026  SOCKET4677_AZIFS054P001C01   I8
  U1     DT57  VSS1202  SOCKET4677_AZIFS054P001C01   I8
  U1     DT59  VSS1028  SOCKET4677_AZIFS054P001C01   I8
  U1     DT63  VSS1029  SOCKET4677_AZIFS054P001C01   I8
  U1     DT65  VSS1203  SOCKET4677_AZIFS054P001C01   I8
  U1     DT69  VSS1204  SOCKET4677_AZIFS054P001C01   I8
  U1     DT71  VSS1205  SOCKET4677_AZIFS054P001C01   I8
  U1     DT75  VSS1206  SOCKET4677_AZIFS054P001C01   I8
  U1     DT83  VSS1036  SOCKET4677_AZIFS054P001C01   I8
  U1     DU21  VSS1209  SOCKET4677_AZIFS054P001C01   I8
  U1     DU27  VSS1211  SOCKET4677_AZIFS054P001C01   I8
  U1     DU33  VSS1212  SOCKET4677_AZIFS054P001C01   I8
  U1     DU39  VSS1047  SOCKET4677_AZIFS054P001C01   I8
  U1     DU45  VSS1048  SOCKET4677_AZIFS054P001C01   I8
  U1     DU52  VSS1050  SOCKET4677_AZIFS054P001C01   I8
  U1     DU58  VSS1051  SOCKET4677_AZIFS054P001C01   I8
  U1     DU64  VSS1052  SOCKET4677_AZIFS054P001C01   I8
  U1     DU70  VSS1054  SOCKET4677_AZIFS054P001C01   I8
  U1     DU76  VSS1213  SOCKET4677_AZIFS054P001C01   I8
  U1     DU78  VSS1214  SOCKET4677_AZIFS054P001C01   I8
  U1     DU84  VSS1215  SOCKET4677_AZIFS054P001C01   I8
  U1     DU88  VSS1216  SOCKET4677_AZIFS054P001C01   I8
  U1     DV4  VSS1063  SOCKET4677_AZIFS054P001C01   I8
  U1     DV8  VSS1221  SOCKET4677_AZIFS054P001C01   I8
  U1     DV12  VSS1059  SOCKET4677_AZIFS054P001C01   I8
  U1     DV16  VSS1060  SOCKET4677_AZIFS054P001C01   I8
  U1     DV42  VSS1064  SOCKET4677_AZIFS054P001C01   I8
  U1     DV77  VSS1218  SOCKET4677_AZIFS054P001C01   I8
  U1     DV79  VSS1219  SOCKET4677_AZIFS054P001C01   I8
  U1     DV81  VSS1222  SOCKET4677_AZIFS054P001C01   I8
  U1     DV83  VSS1226  SOCKET4677_AZIFS054P001C01   I8
  U1     DV87  VSS1227  SOCKET4677_AZIFS054P001C01   I8
  U1     DV91  VSS1228  SOCKET4677_AZIFS054P001C01   I8
  U1     DW1  VSS1229  SOCKET4677_AZIFS054P001C01   I8
  U1     DW5  VSS1249  SOCKET4677_AZIFS054P001C01   I8
  U1     DW9  VSS1268  SOCKET4677_AZIFS054P001C01   I8
  U1     DW13  VSS1230  SOCKET4677_AZIFS054P001C01   I8
  U1     DW17  VSS1231  SOCKET4677_AZIFS054P001C01   I8
  U1     DW19  VSS1233  SOCKET4677_AZIFS054P001C01   I8
  U1     DW21  VSS1077  SOCKET4677_AZIFS054P001C01   I8
  U1     DW23  VSS1234  SOCKET4677_AZIFS054P001C01   I8
  U1     DW25  VSS1236  SOCKET4677_AZIFS054P001C01   I8
  U1     DW27  VSS1238  SOCKET4677_AZIFS054P001C01   I8
  U1     DW29  VSS1239  SOCKET4677_AZIFS054P001C01   I8
  U1     DW31  VSS1240  SOCKET4677_AZIFS054P001C01   I8
  U1     DW33  VSS1241  SOCKET4677_AZIFS054P001C01   I8
  U1     DW35  VSS1242  SOCKET4677_AZIFS054P001C01   I8
  U1     DW37  VSS1243  SOCKET4677_AZIFS054P001C01   I8
  U1     DW39  VSS1244  SOCKET4677_AZIFS054P001C01   I8
  U1     DW41  VSS1245  SOCKET4677_AZIFS054P001C01   I8
  U1     DW43  VSS1246  SOCKET4677_AZIFS054P001C01   I8
  U1     DW45  VSS1247  SOCKET4677_AZIFS054P001C01   I8
  U1     DW48  VSS1248  SOCKET4677_AZIFS054P001C01   I8
  U1     DW50  VSS1250  SOCKET4677_AZIFS054P001C01   I8
  U1     DW52  VSS1251  SOCKET4677_AZIFS054P001C01   I8
  U1     DW54  VSS1252  SOCKET4677_AZIFS054P001C01   I8
  U1     DW56  VSS1253  SOCKET4677_AZIFS054P001C01   I8
  U1     DW58  VSS1254  SOCKET4677_AZIFS054P001C01   I8
  U1     DW60  VSS1097  SOCKET4677_AZIFS054P001C01   I8
  U1     DW62  VSS1255  SOCKET4677_AZIFS054P001C01   I8
  U1     DW64  VSS1256  SOCKET4677_AZIFS054P001C01   I8
  U1     DW66  VSS1257  SOCKET4677_AZIFS054P001C01   I5
  U1     DW68  VSS1258  SOCKET4677_AZIFS054P001C01   I5
  U1     DW70  VSS1259  SOCKET4677_AZIFS054P001C01   I5
  U1     DW72  VSS1260  SOCKET4677_AZIFS054P001C01   I5
  U1     DW74  VSS1261  SOCKET4677_AZIFS054P001C01   I5
  U1     DW76  VSS1262  SOCKET4677_AZIFS054P001C01   I5
  U1     DW80  VSS1263  SOCKET4677_AZIFS054P001C01   I5
  U1     DW82  VSS1264  SOCKET4677_AZIFS054P001C01   I5
  U1     DW84  VSS1266  SOCKET4677_AZIFS054P001C01   I5
  U1     DW88  VSS1267  SOCKET4677_AZIFS054P001C01   I5
  U1     DY4  VSS1115  SOCKET4677_AZIFS054P001C01   I5
  U1     DY8  VSS1270  SOCKET4677_AZIFS054P001C01   I5
  U1     DY12  VSS1111  SOCKET4677_AZIFS054P001C01   I5
  U1     DY16  VSS1112  SOCKET4677_AZIFS054P001C01   I5
  U1     DY42  VSS1116  SOCKET4677_AZIFS054P001C01   I5
  U1     DY77  VSS1269  SOCKET4677_AZIFS054P001C01   I5
  U1      E5  VSS1125  SOCKET4677_AZIFS054P001C01   I8
  U1     E39  VSS1271  SOCKET4677_AZIFS054P001C01   I8
  U1     E52  VSS1126  SOCKET4677_AZIFS054P001C01   I5
  U1     E74  VSS1129  SOCKET4677_AZIFS054P001C01   I5
  U1     E76  VSS1272  SOCKET4677_AZIFS054P001C01   I5
  U1     E78  VSS1131  SOCKET4677_AZIFS054P001C01   I5
  U1     E86  VSS1273  SOCKET4677_AZIFS054P001C01   I5
  U1     EA21  VSS1274  SOCKET4677_AZIFS054P001C01   I5
  U1     EA27  VSS1275  SOCKET4677_AZIFS054P001C01   I5
  U1     EA33  VSS1278  SOCKET4677_AZIFS054P001C01   I5
  U1     EA39  VSS1141  SOCKET4677_AZIFS054P001C01   I5
  U1     EA45  VSS1142  SOCKET4677_AZIFS054P001C01   I5
  U1     EA52  VSS1144  SOCKET4677_AZIFS054P001C01   I5
  U1     EA58  VSS1145  SOCKET4677_AZIFS054P001C01   I5
  U1     EA64  VSS1146  SOCKET4677_AZIFS054P001C01   I5
  U1     EA70  VSS1279  SOCKET4677_AZIFS054P001C01   I5
  U1     EA76  VSS1280  SOCKET4677_AZIFS054P001C01   I5
  U1     EA78  VSS1281  SOCKET4677_AZIFS054P001C01   I5
  U1     EA80  VSS1282  SOCKET4677_AZIFS054P001C01   I5
  U1     EA84  VSS1285  SOCKET4677_AZIFS054P001C01   I5
  U1     EA88  VSS1286  SOCKET4677_AZIFS054P001C01   I5
  U1     EB4  VSS1163  SOCKET4677_AZIFS054P001C01   I5
  U1     EB8  VSS1306  SOCKET4677_AZIFS054P001C01   I5
  U1     EB12  VSS1287  SOCKET4677_AZIFS054P001C01   I5
  U1     EB16  VSS1155  SOCKET4677_AZIFS054P001C01   I5
  U1     EB20  VSS1156  SOCKET4677_AZIFS054P001C01   I5
  U1     EB22  VSS1288  SOCKET4677_AZIFS054P001C01   I5
  U1     EB26  VSS1158  SOCKET4677_AZIFS054P001C01   I5
  U1     EB28  VSS1289  SOCKET4677_AZIFS054P001C01   I5
  U1     EB32  VSS1292  SOCKET4677_AZIFS054P001C01   I5
  U1     EB34  VSS1161  SOCKET4677_AZIFS054P001C01   I5
  U1     EB38  VSS1293  SOCKET4677_AZIFS054P001C01   I5
  U1     EB40  VSS1295  SOCKET4677_AZIFS054P001C01   I5
  U1     EB44  VSS1165  SOCKET4677_AZIFS054P001C01   I5
  U1     EB47  VSS1296  SOCKET4677_AZIFS054P001C01   I5
  U1     EB51  VSS1167  SOCKET4677_AZIFS054P001C01   I5
  U1     EB53  VSS1168  SOCKET4677_AZIFS054P001C01   I5
  U1     EB57  VSS1297  SOCKET4677_AZIFS054P001C01   I5
  U1     EB59  VSS1170  SOCKET4677_AZIFS054P001C01   I5
  U1     EB63  VSS1171  SOCKET4677_AZIFS054P001C01   I5
  U1     EB65  VSS1298  SOCKET4677_AZIFS054P001C01   I5
  U1     EB69  VSS1299  SOCKET4677_AZIFS054P001C01   I5
  U1     EB71  VSS1300  SOCKET4677_AZIFS054P001C01   I5
  U1     EB75  VSS1301  SOCKET4677_AZIFS054P001C01   I5
  U1     EB79  VSS1304  SOCKET4677_AZIFS054P001C01   I5
  U1     EB83  VSS1307  SOCKET4677_AZIFS054P001C01   I5
  U1     EB87  VSS1308  SOCKET4677_AZIFS054P001C01   I5
  U1     EB91  VSS1180  SOCKET4677_AZIFS054P001C01   I5
  U1     EC1  VSS1309  SOCKET4677_AZIFS054P001C01   I5
  U1     EC5  VSS1193  SOCKET4677_AZIFS054P001C01   I5
  U1     EC9  VSS1337  SOCKET4677_AZIFS054P001C01   I5
  U1     EC13  VSS1310  SOCKET4677_AZIFS054P001C01   I5
  U1     EC19  VSS1311  SOCKET4677_AZIFS054P001C01   I5
  U1     EC23  VSS1313  SOCKET4677_AZIFS054P001C01   I5
  U1     EC25  VSS1185  SOCKET4677_AZIFS054P001C01   I5
  U1     EC29  VSS1314  SOCKET4677_AZIFS054P001C01   I5
  U1     EC31  VSS1316  SOCKET4677_AZIFS054P001C01   I5
  U1     EC35  VSS1188  SOCKET4677_AZIFS054P001C01   I5
  U1     EC37  VSS1317  SOCKET4677_AZIFS054P001C01   I5
  U1     EC41  VSS1321  SOCKET4677_AZIFS054P001C01   I5
  U1     EC43  VSS1323  SOCKET4677_AZIFS054P001C01   I5
  U1     EC48  VSS1324  SOCKET4677_AZIFS054P001C01   I5
  U1     EC50  VSS1326  SOCKET4677_AZIFS054P001C01   I5
  U1     EC54  VSS1195  SOCKET4677_AZIFS054P001C01   I5
  U1     EC56  VSS1327  SOCKET4677_AZIFS054P001C01   I5
  U1     EC60  VSS1197  SOCKET4677_AZIFS054P001C01   I5
  U1     EC62  VSS1198  SOCKET4677_AZIFS054P001C01   I5
  U1     EC66  VSS1329  SOCKET4677_AZIFS054P001C01   I5
  U1     EC68  VSS1200  SOCKET4677_AZIFS054P001C01   I5
  U1     EC72  VSS1330  SOCKET4677_AZIFS054P001C01   I5
  U1     EC74  VSS1332  SOCKET4677_AZIFS054P001C01   I5
  U1     EC82  VSS1333  SOCKET4677_AZIFS054P001C01   I5
  U1     EC84  VSS1335  SOCKET4677_AZIFS054P001C01   I5
  U1     EC88  VSS1336  SOCKET4677_AZIFS054P001C01   I5
  U1     ED4  VSS1344  SOCKET4677_AZIFS054P001C01   I5
  U1     ED8  VSS1348  SOCKET4677_AZIFS054P001C01   I5
  U1     ED12  VSS1208  SOCKET4677_AZIFS054P001C01   I5
  U1     ED16  VSS1338  SOCKET4677_AZIFS054P001C01   I5
  U1     ED18  VSS1210  SOCKET4677_AZIFS054P001C01   I5
  U1     ED24  VSS1339  SOCKET4677_AZIFS054P001C01   I5
  U1     ED30  VSS1341  SOCKET4677_AZIFS054P001C01   I5
  U1     ED36  VSS1342  SOCKET4677_AZIFS054P001C01   I5
  U1     ED42  VSS1217  SOCKET4677_AZIFS054P001C01   I5
  U1     ED49  VSS1346  SOCKET4677_AZIFS054P001C01   I5
  U1     ED55  VSS1220  SOCKET4677_AZIFS054P001C01   I5
  U1     ED61  VSS1223  SOCKET4677_AZIFS054P001C01   I5
  U1     ED67  VSS1224  SOCKET4677_AZIFS054P001C01   I5
  U1     ED73  VSS1225  SOCKET4677_AZIFS054P001C01   I5
  U1     EE17  VSS1232  SOCKET4677_AZIFS054P001C01   I5
  U1     EE39  VSS1235  SOCKET4677_AZIFS054P001C01   I5
  U1     EE52  VSS1237  SOCKET4677_AZIFS054P001C01   I5
  U1     EE78  VSS1349  SOCKET4677_AZIFS054P001C01   I5
  U1     EE80  VSS1350  SOCKET4677_AZIFS054P001C01   I5
  U1     EE88  VSS1351  SOCKET4677_AZIFS054P001C01   I5
  U1     EF2  VSS1356  SOCKET4677_AZIFS054P001C01   I5
  U1     EF4  VSS1374  SOCKET4677_AZIFS054P001C01   I5
  U1     EF8  VSS1404  SOCKET4677_AZIFS054P001C01   I5
  U1     EF12  VSS1352  SOCKET4677_AZIFS054P001C01   I5
  U1     EF16  VSS1353  SOCKET4677_AZIFS054P001C01   I5
  U1     EF18  VSS1354  SOCKET4677_AZIFS054P001C01   I5
  U1     EF20  VSS1358  SOCKET4677_AZIFS054P001C01   I5
  U1     EF22  VSS1360  SOCKET4677_AZIFS054P001C01   I5
  U1     EF24  VSS1361  SOCKET4677_AZIFS054P001C01   I5
  U1     EF26  VSS1362  SOCKET4677_AZIFS054P001C01   I5
  U1     EF28  VSS1363  SOCKET4677_AZIFS054P001C01   I5
  U1     EF30  VSS1364  SOCKET4677_AZIFS054P001C01   I5
  U1     EF32  VSS1365  SOCKET4677_AZIFS054P001C01   I5
  U1     EF34  VSS1367  SOCKET4677_AZIFS054P001C01   I5
  U1     EF36  VSS1370  SOCKET4677_AZIFS054P001C01   I5
  U1     EF38  VSS1373  SOCKET4677_AZIFS054P001C01   I5
  U1     EF40  VSS1376  SOCKET4677_AZIFS054P001C01   I5
  U1     EF42  VSS1382  SOCKET4677_AZIFS054P001C01   I5
  U1     EF44  VSS1383  SOCKET4677_AZIFS054P001C01   I5
  U1     EF47  VSS1384  SOCKET4677_AZIFS054P001C01   I5
  U1     EF49  VSS1385  SOCKET4677_AZIFS054P001C01   I5
  U1     EF51  VSS1265  SOCKET4677_AZIFS054P001C01   I5
  U1     EF53  VSS1386  SOCKET4677_AZIFS054P001C01   I5
  U1     EF55  VSS1387  SOCKET4677_AZIFS054P001C01   I5
  U1     EF57  VSS1388  SOCKET4677_AZIFS054P001C01   I5
  U1     EF59  VSS1389  SOCKET4677_AZIFS054P001C01   I5
  U1     EF61  VSS1390  SOCKET4677_AZIFS054P001C01   I5
  U1     EF63  VSS1392  SOCKET4677_AZIFS054P001C01   I5
  U1     EF65  VSS1393  SOCKET4677_AZIFS054P001C01   I5
  U1     EF67  VSS1395  SOCKET4677_AZIFS054P001C01   I5
  U1     EF69  VSS1399  SOCKET4677_AZIFS054P001C01   I5
  U1     EF71  VSS1402  SOCKET4677_AZIFS054P001C01   I5
  U1     EF73  VSS1276  SOCKET4677_AZIFS054P001C01   I5
  U1     EF75  VSS1277  SOCKET4677_AZIFS054P001C01   I5
  U1     EF77  VSS1403  SOCKET4677_AZIFS054P001C01   I5
  U1     EF85  VSS1406  SOCKET4677_AZIFS054P001C01   I5
  U1     EF87  VSS1407  SOCKET4677_AZIFS054P001C01   I5
  U1     EF89  VSS1283  SOCKET4677_AZIFS054P001C01   I5
  U1     EG5  VSS1290  SOCKET4677_AZIFS054P001C01   I5
  U1     EG7  VSS1294  SOCKET4677_AZIFS054P001C01   I5
  U1     EG9  VSS1414  SOCKET4677_AZIFS054P001C01   I5
  U1     EG13  VSS1284  SOCKET4677_AZIFS054P001C01   I5
  U1     EG39  VSS1408  SOCKET4677_AZIFS054P001C01   I5
  U1     EG52  VSS1291  SOCKET4677_AZIFS054P001C01   I5
  U1     EG82  VSS1410  SOCKET4677_AZIFS054P001C01   I5
  U1     EG84  VSS1411  SOCKET4677_AZIFS054P001C01   I5
  U1     EG86  VSS1412  SOCKET4677_AZIFS054P001C01   I5
  U1     EG88  VSS1413  SOCKET4677_AZIFS054P001C01   I5
  U1     EG90  VSS1415  SOCKET4677_AZIFS054P001C01   I5
  U1     EH4  VSS1420  SOCKET4677_AZIFS054P001C01   I5
  U1     EH6  VSS1318  SOCKET4677_AZIFS054P001C01   I5
  U1     EH12  VSS1302  SOCKET4677_AZIFS054P001C01   I5
  U1     EH14  VSS1303  SOCKET4677_AZIFS054P001C01   I5
  U1     EH16  VSS1416  SOCKET4677_AZIFS054P001C01   I5
  U1     EH18  VSS1305  SOCKET4677_AZIFS054P001C01   I5
  U1     EH24  VSS1417  SOCKET4677_AZIFS054P001C01   I5
  U1     EH30  VSS1418  SOCKET4677_AZIFS054P001C01   I5
  U1     EH36  VSS1419  SOCKET4677_AZIFS054P001C01   I2
  U1     EH42  VSS1312  SOCKET4677_AZIFS054P001C01   I2
  U1     EH49  VSS1421  SOCKET4677_AZIFS054P001C01   I2
  U1     EH55  VSS1315  SOCKET4677_AZIFS054P001C01   I2
  U1     EH61  VSS1319  SOCKET4677_AZIFS054P001C01   I2
  U1     EH67  VSS1320  SOCKET4677_AZIFS054P001C01   I2
  U1     EH73  VSS1422  SOCKET4677_AZIFS054P001C01   I2
  U1     EH79  VSS1322  SOCKET4677_AZIFS054P001C01   I2
  U1     EH81  VSS1423  SOCKET4677_AZIFS054P001C01   I2
  U1     EH83  VSS1424  SOCKET4677_AZIFS054P001C01   I2
  U1     EJ7  VSS1444  SOCKET4677_AZIFS054P001C01   I2
  U1     EJ9  VSS1450  SOCKET4677_AZIFS054P001C01   I2
  U1     EJ11  VSS1325  SOCKET4677_AZIFS054P001C01   I2
  U1     EJ13  VSS1425  SOCKET4677_AZIFS054P001C01   I2
  U1     EJ17  VSS1328  SOCKET4677_AZIFS054P001C01   I2
  U1     EJ19  VSS1426  SOCKET4677_AZIFS054P001C01   I2
  U1     EJ23  VSS1428  SOCKET4677_AZIFS054P001C01   I2
  U1     EJ25  VSS1331  SOCKET4677_AZIFS054P001C01   I2
  U1     EJ29  VSS1429  SOCKET4677_AZIFS054P001C01   I2
  U1     EJ31  VSS1430  SOCKET4677_AZIFS054P001C01   I2
  U1     EJ35  VSS1334  SOCKET4677_AZIFS054P001C01   I2
  U1     EJ37  VSS1431  SOCKET4677_AZIFS054P001C01   I2
  U1     EJ41  VSS1432  SOCKET4677_AZIFS054P001C01   I2
  U1     EJ43  VSS1433  SOCKET4677_AZIFS054P001C01   I2
  U1     EJ48  VSS1434  SOCKET4677_AZIFS054P001C01   I2
  U1     EJ50  VSS1435  SOCKET4677_AZIFS054P001C01   I2
  U1     EJ54  VSS1340  SOCKET4677_AZIFS054P001C01   I2
  U1     EJ56  VSS1439  SOCKET4677_AZIFS054P001C01   I2
  U1     EJ60  VSS1442  SOCKET4677_AZIFS054P001C01   I2
  U1     EJ62  VSS1343  SOCKET4677_AZIFS054P001C01   I2
  U1     EJ66  VSS1443  SOCKET4677_AZIFS054P001C01   I2
  U1     EJ68  VSS1345  SOCKET4677_AZIFS054P001C01   I2
  U1     EJ72  VSS1347  SOCKET4677_AZIFS054P001C01   I2
  U1     EJ74  VSS1447  SOCKET4677_AZIFS054P001C01   I2
  U1     EJ78  VSS1448  SOCKET4677_AZIFS054P001C01   I2
  U1     EJ88  VSS1449  SOCKET4677_AZIFS054P001C01   I2
  U1     EK2  VSS1458  SOCKET4677_AZIFS054P001C01   I2
  U1     EK4  VSS1466  SOCKET4677_AZIFS054P001C01   I2
  U1     EK10  VSS1451  SOCKET4677_AZIFS054P001C01   I2
  U1     EK14  VSS1455  SOCKET4677_AZIFS054P001C01   I2
  U1     EK16  VSS1355  SOCKET4677_AZIFS054P001C01   I2
  U1     EK20  VSS1357  SOCKET4677_AZIFS054P001C01   I2
  U1     EK22  VSS1459  SOCKET4677_AZIFS054P001C01   I2
  U1     EK26  VSS1359  SOCKET4677_AZIFS054P001C01   I2
  U1     EK28  VSS1460  SOCKET4677_AZIFS054P001C01   I2
  U1     EK32  VSS1461  SOCKET4677_AZIFS054P001C01   I2
  U1     EK34  VSS1463  SOCKET4677_AZIFS054P001C01   I2
  U1     EK38  VSS1465  SOCKET4677_AZIFS054P001C01   I2
  U1     EK40  VSS1469  SOCKET4677_AZIFS054P001C01   I2
  U1     EK44  VSS1366  SOCKET4677_AZIFS054P001C01   I2
  U1     EK47  VSS1470  SOCKET4677_AZIFS054P001C01   I2
  U1     EK51  VSS1368  SOCKET4677_AZIFS054P001C01   I2
  U1     EK53  VSS1369  SOCKET4677_AZIFS054P001C01   I2
  U1     EK57  VSS1471  SOCKET4677_AZIFS054P001C01   I2
  U1     EK59  VSS1371  SOCKET4677_AZIFS054P001C01   I2
  U1     EK63  VSS1372  SOCKET4677_AZIFS054P001C01   I2
  U1     EK65  VSS1472  SOCKET4677_AZIFS054P001C01   I2
  U1     EK69  VSS1473  SOCKET4677_AZIFS054P001C01   I2
  U1     EK71  VSS1375  SOCKET4677_AZIFS054P001C01   I2
  U1     EK75  VSS1474  SOCKET4677_AZIFS054P001C01   I2
  U1     EK77  VSS1377  SOCKET4677_AZIFS054P001C01   I2
  U1     EK79  VSS1378  SOCKET4677_AZIFS054P001C01   I2
  U1     EK83  VSS1379  SOCKET4677_AZIFS054P001C01   I2
  U1     EK89  VSS1380  SOCKET4677_AZIFS054P001C01   I2
  U1     EL3  VSS1479  SOCKET4677_AZIFS054P001C01   I2
  U1     EL5  VSS1486  SOCKET4677_AZIFS054P001C01   I2
  U1     EL7  VSS1396  SOCKET4677_AZIFS054P001C01   I2
  U1     EL9  VSS1401  SOCKET4677_AZIFS054P001C01   I2
  U1     EL15  VSS1381  SOCKET4677_AZIFS054P001C01   I2
  U1     EL21  VSS1475  SOCKET4677_AZIFS054P001C01   I2
  U1     EL27  VSS1477  SOCKET4677_AZIFS054P001C01   I2
  U1     EL33  VSS1481  SOCKET4677_AZIFS054P001C01   I2
  U1     EL39  VSS1483  SOCKET4677_AZIFS054P001C01   I2
  U1     EL45  VSS1485  SOCKET4677_AZIFS054P001C01   I2
  U1     EL52  VSS1391  SOCKET4677_AZIFS054P001C01   I2
  U1     EL58  VSS1394  SOCKET4677_AZIFS054P001C01   I2
  U1     EL64  VSS1488  SOCKET4677_AZIFS054P001C01   I2
  U1     EL70  VSS1397  SOCKET4677_AZIFS054P001C01   I2
  U1     EL72  VSS1398  SOCKET4677_AZIFS054P001C01   I2
  U1     EL76  VSS1489  SOCKET4677_AZIFS054P001C01   I2
  U1     EL86  VSS1400  SOCKET4677_AZIFS054P001C01   I2
  U1     EM8  VSS1497  SOCKET4677_AZIFS054P001C01   I2
  U1     EM42  VSS1492  SOCKET4677_AZIFS054P001C01   I2
  U1     EM49  VSS1405  SOCKET4677_AZIFS054P001C01   I2
  U1     EM73  VSS1496  SOCKET4677_AZIFS054P001C01   I2
  U1     EM79  VSS1409  SOCKET4677_AZIFS054P001C01   I2
  U1     EM81  VSS1498  SOCKET4677_AZIFS054P001C01   I2
  U1     EM83  VSS1499  SOCKET4677_AZIFS054P001C01   I2
  U1     EN9  VSS1446  SOCKET4677_AZIFS054P001C01   I2
  U1     EN11  VSS1500  SOCKET4677_AZIFS054P001C01   I2
  U1     EN13  VSS1501  SOCKET4677_AZIFS054P001C01   I2
  U1     EN15  VSS1503  SOCKET4677_AZIFS054P001C01   I2
  U1     EN17  VSS1505  SOCKET4677_AZIFS054P001C01   I2
  U1     EN19  VSS1506  SOCKET4677_AZIFS054P001C01   I2
  U1     EN21  VSS1512  SOCKET4677_AZIFS054P001C01   I2
  U1     EN23  VSS1513  SOCKET4677_AZIFS054P001C01   I2
  U1     EN25  VSS1515  SOCKET4677_AZIFS054P001C01   I2
  U1     EN27  VSS1517  SOCKET4677_AZIFS054P001C01   I2
  U1     EN29  VSS1518  SOCKET4677_AZIFS054P001C01   I2
  U1     EN31  VSS1520  SOCKET4677_AZIFS054P001C01   I2
  U1     EN33  VSS1522  SOCKET4677_AZIFS054P001C01   I2
  U1     EN35  VSS1524  SOCKET4677_AZIFS054P001C01   I2
  U1     EN37  VSS1525  SOCKET4677_AZIFS054P001C01   I2
  U1     EN39  VSS1427  SOCKET4677_AZIFS054P001C01   I2
  U1     EN41  VSS1526  SOCKET4677_AZIFS054P001C01   I2
  U1     EN43  VSS1528  SOCKET4677_AZIFS054P001C01   I2
  U1     EN45  VSS1529  SOCKET4677_AZIFS054P001C01   I2
  U1     EN48  VSS1530  SOCKET4677_AZIFS054P001C01   I2
  U1     EN50  VSS1531  SOCKET4677_AZIFS054P001C01   I2
  U1     EN52  VSS1533  SOCKET4677_AZIFS054P001C01   I2
  U1     EN54  VSS1537  SOCKET4677_AZIFS054P001C01   I2
  U1     EN56  VSS1539  SOCKET4677_AZIFS054P001C01   I2
  U1     EN58  VSS1436  SOCKET4677_AZIFS054P001C01   I2
  U1     EN60  VSS1437  SOCKET4677_AZIFS054P001C01   I2
  U1     EN62  VSS1438  SOCKET4677_AZIFS054P001C01   I2
  U1     EN64  VSS1540  SOCKET4677_AZIFS054P001C01   I2
  U1     EN66  VSS1440  SOCKET4677_AZIFS054P001C01   I2
  U1     EN72  VSS1441  SOCKET4677_AZIFS054P001C01   I2
  U1     EN78  VSS1541  SOCKET4677_AZIFS054P001C01   I2
  U1     EN80  VSS1542  SOCKET4677_AZIFS054P001C01   I2
  U1     EN88  VSS1445  SOCKET4677_AZIFS054P001C01   I2
  U1     EP67  VSS1543  SOCKET4677_AZIFS054P001C01   I2
  U1     EP69  VSS1452  SOCKET4677_AZIFS054P001C01   I2
  U1     EP71  VSS1453  SOCKET4677_AZIFS054P001C01   I2
  U1     EP77  VSS1454  SOCKET4677_AZIFS054P001C01   I2
  U1     EP83  VSS1545  SOCKET4677_AZIFS054P001C01   I2
  U1     ER5  VSS1549  SOCKET4677_AZIFS054P001C01   I2
  U1     ER7  VSS1550  SOCKET4677_AZIFS054P001C01   I2
  U1     ER9  VSS1476  SOCKET4677_AZIFS054P001C01   I2
  U1     ER15  VSS1456  SOCKET4677_AZIFS054P001C01   I2
  U1     ER21  VSS1457  SOCKET4677_AZIFS054P001C01   I2
  U1     ER27  VSS1547  SOCKET4677_AZIFS054P001C01   I2
  U1     ER33  VSS1548  SOCKET4677_AZIFS054P001C01   I2
  U1     ER39  VSS1462  SOCKET4677_AZIFS054P001C01   I2
  U1     ER41  GND_ER41  SOCKET4677_AZIFS054P001C01   I2
  U1     ER43  GND_ER43  SOCKET4677_AZIFS054P001C01   I2
  U1     ER48  GND_ER48  SOCKET4677_AZIFS054P001C01   I2
  U1     ER50  GND_ER50  SOCKET4677_AZIFS054P001C01   I2
  U1     ER52  VSS1464  SOCKET4677_AZIFS054P001C01   I2
  U1     ER58  VSS1467  SOCKET4677_AZIFS054P001C01   I2
  U1     ER64  VSS1468  SOCKET4677_AZIFS054P001C01   I2
  U1     ER70  VSS1551  SOCKET4677_AZIFS054P001C01   I2
  U1     ER74  VSS1552  SOCKET4677_AZIFS054P001C01   I2
  U1     ER78  VSS1553  SOCKET4677_AZIFS054P001C01   I2
  U1     ER80  VSS1554  SOCKET4677_AZIFS054P001C01   I2
  U1     ER84  VSS1555  SOCKET4677_AZIFS054P001C01   I2
  U1     ER86  VSS1556  SOCKET4677_AZIFS054P001C01   I2
  U1     ET10  VSS1557  SOCKET4677_AZIFS054P001C01   I2
  U1     ET14  VSS1478  SOCKET4677_AZIFS054P001C01   I2
  U1     ET16  VSS1559  SOCKET4677_AZIFS054P001C01   I2
  U1     ET20  VSS1480  SOCKET4677_AZIFS054P001C01   I2
  U1     ET22  VSS1561  SOCKET4677_AZIFS054P001C01   I2
  U1     ET26  VSS1482  SOCKET4677_AZIFS054P001C01   I2
  U1     ET28  VSS1562  SOCKET4677_AZIFS054P001C01   I2
  U1     ET32  VSS1484  SOCKET4677_AZIFS054P001C01   I2
  U1     ET34  VSS1563  SOCKET4677_AZIFS054P001C01   I2
  U1     ET38  VSS1565  SOCKET4677_AZIFS054P001C01   I2
  U1     ET53  VSS1491  SOCKET4677_AZIFS054P001C01   I2
  U1     ET57  VSS1569  SOCKET4677_AZIFS054P001C01   I2
  U1     ET59  VSS1493  SOCKET4677_AZIFS054P001C01   I2
  U1      F4  VSS1573  SOCKET4677_AZIFS054P001C01   I5
  U1      F6  VSS1507  SOCKET4677_AZIFS054P001C01   I5
  U1     F12  VSS1494  SOCKET4677_AZIFS054P001C01   I5
  U1     F18  VSS1495  SOCKET4677_AZIFS054P001C01   I5
  U1     F24  VSS1570  SOCKET4677_AZIFS054P001C01   I5
  U1     F30  VSS1571  SOCKET4677_AZIFS054P001C01   I5
  U1     F36  VSS1572  SOCKET4677_AZIFS054P001C01   I5
  U1     F42  VSS1502  SOCKET4677_AZIFS054P001C01   I5
  U1     F49  VSS1574  SOCKET4677_AZIFS054P001C01   I5
  U1     F55  VSS1504  SOCKET4677_AZIFS054P001C01   I5
  U1     F61  VSS1508  SOCKET4677_AZIFS054P001C01   I5
  U1     F67  VSS1509  SOCKET4677_AZIFS054P001C01   I5
  U1     F73  VSS1510  SOCKET4677_AZIFS054P001C01   I5
  U1     F79  VSS1511  SOCKET4677_AZIFS054P001C01   I5
  U1     F83  VSS1576  SOCKET4677_AZIFS054P001C01   I5
  U1     F89  VSS1577  SOCKET4677_AZIFS054P001C01   I5
  U1      G3  VSS1521  SOCKET4677_AZIFS054P001C01   I5
  U1      G7  VSS1536  SOCKET4677_AZIFS054P001C01   I5
  U1     G11  VSS1514  SOCKET4677_AZIFS054P001C01   I5
  U1     G13  VSS1578  SOCKET4677_AZIFS054P001C01   I5
  U1     G17  VSS1516  SOCKET4677_AZIFS054P001C01   I5
  U1     G19  VSS1579  SOCKET4677_AZIFS054P001C01   I5
  U1     G23  VSS1581  SOCKET4677_AZIFS054P001C01   I5
  U1     G25  VSS1519  SOCKET4677_AZIFS054P001C01   I5
  U1     G29  VSS1583  SOCKET4677_AZIFS054P001C01   I5
  U1     G31  VSS1584  SOCKET4677_AZIFS054P001C01   I5
  U1     G35  VSS1523  SOCKET4677_AZIFS054P001C01   I5
  U1     G37  VSS1585  SOCKET4677_AZIFS054P001C01   I5
  U1     G41  VSS1586  SOCKET4677_AZIFS054P001C01   I5
  U1     G43  VSS1588  SOCKET4677_AZIFS054P001C01   I5
  U1     G48  VSS1527  SOCKET4677_AZIFS054P001C01   I5
  U1     G50  VSS1590  SOCKET4677_AZIFS054P001C01   I5
  U1     G54  VSS1591  SOCKET4677_AZIFS054P001C01   I5
  U1     G56  VSS1592  SOCKET4677_AZIFS054P001C01   I5
  U1     G60  VSS1532  SOCKET4677_AZIFS054P001C01   I5
  U1     G62  VSS1593  SOCKET4677_AZIFS054P001C01   I5
  U1     G66  VSS1534  SOCKET4677_AZIFS054P001C01   I5
  U1     G68  VSS1535  SOCKET4677_AZIFS054P001C01   I5
  U1     G72  VSS1594  SOCKET4677_AZIFS054P001C01   I5
  U1     G74  VSS1538  SOCKET4677_AZIFS054P001C01   I5
  U1     G84  VSS1600  SOCKET4677_AZIFS054P001C01   I5
  U1     G88  VSS1601  SOCKET4677_AZIFS054P001C01   I5
  U1     G90  VSS1604  SOCKET4677_AZIFS054P001C01   I5
  U1      H2  VSS1546  SOCKET4677_AZIFS054P001C01   I5
  U1      H4  VSS1615  SOCKET4677_AZIFS054P001C01   I5
  U1      H6  VSS1621  SOCKET4677_AZIFS054P001C01   I5
  U1      H8  VSS1626  SOCKET4677_AZIFS054P001C01   I5
  U1     H10  VSS1605  SOCKET4677_AZIFS054P001C01   I5
  U1     H14  VSS1544  SOCKET4677_AZIFS054P001C01   I5
  U1     H16  VSS1606  SOCKET4677_AZIFS054P001C01   I5
  U1     H20  VSS1607  SOCKET4677_AZIFS054P001C01   I5
  U1     H22  VSS1608  SOCKET4677_AZIFS054P001C01   I5
  U1     H26  VSS1609  SOCKET4677_AZIFS054P001C01   I5
  U1     H28  VSS1610  SOCKET4677_AZIFS054P001C01   I5
  U1     H32  VSS1611  SOCKET4677_AZIFS054P001C01   I5
  U1     H34  VSS1612  SOCKET4677_AZIFS054P001C01   I5
  U1     H38  VSS1613  SOCKET4677_AZIFS054P001C01   I5
  U1     H40  VSS1616  SOCKET4677_AZIFS054P001C01   I5
  U1     H44  VSS1617  SOCKET4677_AZIFS054P001C01   I5
  U1     H47  VSS1618  SOCKET4677_AZIFS054P001C01   I5
  U1     H51  VSS1558  SOCKET4677_AZIFS054P001C01   I5
  U1     H53  VSS1619  SOCKET4677_AZIFS054P001C01   I5
  U1     H57  VSS1560  SOCKET4677_AZIFS054P001C01   I5
  U1     H59  VSS1620  SOCKET4677_AZIFS054P001C01   I5
  U1     H63  VSS1622  SOCKET4677_AZIFS054P001C01   I5
  U1     H65  VSS1564  SOCKET4677_AZIFS054P001C01   I5
  U1     H69  VSS1623  SOCKET4677_AZIFS054P001C01   I5
  U1     H71  VSS1624  SOCKET4677_AZIFS054P001C01   I5
  U1     H75  VSS1567  SOCKET4677_AZIFS054P001C01   I5
  U1     H79  VSS1625  SOCKET4677_AZIFS054P001C01   I5
  U1     H81  VSS1627  SOCKET4677_AZIFS054P001C01   I5
  U1      J5  VSS1582  SOCKET4677_AZIFS054P001C01   I5
  U1      J9  VSS1596  SOCKET4677_AZIFS054P001C01   I5
  U1     J15  VSS1628  SOCKET4677_AZIFS054P001C01   I5
  U1     J21  VSS1575  SOCKET4677_AZIFS054P001C01   I5
  U1     J27  VSS1629  SOCKET4677_AZIFS054P001C01   I5
  U1     J33  VSS1630  SOCKET4677_AZIFS054P001C01   I5
  U1     J39  VSS1580  SOCKET4677_AZIFS054P001C01   I5
  U1     J45  VSS1631  SOCKET4677_AZIFS054P001C01   I5
  U1     J52  VSS1632  SOCKET4677_AZIFS054P001C01   I5
  U1     J58  VSS1633  SOCKET4677_AZIFS054P001C01   I5
  U1     J64  VSS1587  SOCKET4677_AZIFS054P001C01   I5
  U1     J70  VSS1589  SOCKET4677_AZIFS054P001C01   I5
  U1     J76  VSS1635  SOCKET4677_AZIFS054P001C01   I5
  U1     J78  VSS1636  SOCKET4677_AZIFS054P001C01   I5
  U1     J84  VSS1637  SOCKET4677_AZIFS054P001C01   I5
  U1     J86  VSS1638  SOCKET4677_AZIFS054P001C01   I5
  U1     J88  VSS1595  SOCKET4677_AZIFS054P001C01   I5
  U1      K2  VSS1599  SOCKET4677_AZIFS054P001C01   I5
  U1      K8  VSS1641  SOCKET4677_AZIFS054P001C01   I5
  U1     K12  VSS1597  SOCKET4677_AZIFS054P001C01   I5
  U1     K14  VSS1598  SOCKET4677_AZIFS054P001C01   I5
  U1     K42  VSS1602  SOCKET4677_AZIFS054P001C01   I5
  U1     K49  VSS1603  SOCKET4677_AZIFS054P001C01   I5
  U1     K77  VSS1639  SOCKET4677_AZIFS054P001C01   I5
  U1     K83  VSS1642  SOCKET4677_AZIFS054P001C01   I5
  U1     K85  VSS1643  SOCKET4677_AZIFS054P001C01   I5
  U1      L5  VSS1671  SOCKET4677_AZIFS054P001C01   I5
  U1      L9  VSS1647  SOCKET4677_AZIFS054P001C01   I5
  U1     L13  VSS1644  SOCKET4677_AZIFS054P001C01   I5
  U1     L15  VSS1645  SOCKET4677_AZIFS054P001C01   I5
  U1     L17  VSS1650  SOCKET4677_AZIFS054P001C01   I5
  U1     L19  VSS1614  SOCKET4677_AZIFS054P001C01   I5
  U1     L21  VSS1651  SOCKET4677_AZIFS054P001C01   I5
  U1     L23  VSS1655  SOCKET4677_AZIFS054P001C01   I5
  U1     L25  VSS1656  SOCKET4677_AZIFS054P001C01   I5
  U1     L27  VSS1658  SOCKET4677_AZIFS054P001C01   I5
  U1     L29  VSS1659  SOCKET4677_AZIFS054P001C01   I5
  U1     L31  VSS1660  SOCKET4677_AZIFS054P001C01   I5
  U1     L33  VSS1661  SOCKET4677_AZIFS054P001C01   I5
  U1     L35  VSS1662  SOCKET4677_AZIFS054P001C01   I5
  U1     L37  VSS1663  SOCKET4677_AZIFS054P001C01   I5
  U1     L39  VSS1665  SOCKET4677_AZIFS054P001C01   I5
  U1     L41  VSS1666  SOCKET4677_AZIFS054P001C01   I5
  U1     L43  VSS1667  SOCKET4677_AZIFS054P001C01   I5
  U1     L45  VSS1668  SOCKET4677_AZIFS054P001C01   I5
  U1     L48  VSS1670  SOCKET4677_AZIFS054P001C01   I5
  U1     L50  VSS1672  SOCKET4677_AZIFS054P001C01   I5
  U1     L52  VSS1673  SOCKET4677_AZIFS054P001C01   I5
  U1     L54  VSS1674  SOCKET4677_AZIFS054P001C01   I5
  U1     L56  VSS1676  SOCKET4677_AZIFS054P001C01   I5
  U1     L58  VSS1634  SOCKET4677_AZIFS054P001C01   I5
  U1     L60  VSS1677  SOCKET4677_AZIFS054P001C01   I5
  U1     L62  VSS1678  SOCKET4677_AZIFS054P001C01   I5
  U1     L64  VSS1679  SOCKET4677_AZIFS054P001C01   I5
  U1     L66  VSS1680  SOCKET4677_AZIFS054P001C01   I5
  U1     L68  VSS1681  SOCKET4677_AZIFS054P001C01   I5
  U1     L70  VSS1640  SOCKET4677_AZIFS054P001C01   I5
  U1     L72  VSS1682  SOCKET4677_AZIFS054P001C01   I5
  U1     L74  VSS1683  SOCKET4677_AZIFS054P001C01   I5
  U1     L76  VSS1684  SOCKET4677_AZIFS054P001C01   I5
  U1     L78  VSS1685  SOCKET4677_AZIFS054P001C01   I5
  U1     L88  VSS1646  SOCKET4677_AZIFS054P001C01   I5
  U1     L90  VSS1648  SOCKET4677_AZIFS054P001C01   I5
  U1      M4  VSS1652  SOCKET4677_AZIFS054P001C01   I5
  U1      M8  VSS1657  SOCKET4677_AZIFS054P001C01   I5
  U1     M12  VSS1649  SOCKET4677_AZIFS054P001C01   I5
  U1     M42  VSS1653  SOCKET4677_AZIFS054P001C01   I5
  U1     M49  VSS1654  SOCKET4677_AZIFS054P001C01   I5
  U1     M81  VSS1686  SOCKET4677_AZIFS054P001C01   I5
  U1     M83  VSS1687  SOCKET4677_AZIFS054P001C01   I5
  U1     N15  VSS1688  SOCKET4677_AZIFS054P001C01   I5
  U1     N21  VSS1664  SOCKET4677_AZIFS054P001C01   I5
  U1     N27  VSS1689  SOCKET4677_AZIFS054P001C01   I5
  U1     N33  VSS1691  SOCKET4677_AZIFS054P001C01   I5
  U1     N39  VSS1669  SOCKET4677_AZIFS054P001C01   I5
  U1     N45  VSS1692  SOCKET4677_AZIFS054P001C01   I5
  U1     N52  VSS1693  SOCKET4677_AZIFS054P001C01   I5
  U1     N58  VSS1694  SOCKET4677_AZIFS054P001C01   I5
  U1     N64  VSS1675  SOCKET4677_AZIFS054P001C01   I5
  U1     N70  VSS1695  SOCKET4677_AZIFS054P001C01   I5
  U1     N76  VSS1696  SOCKET4677_AZIFS054P001C01   I2
  U1     N78  VSS1698  SOCKET4677_AZIFS054P001C01   I2
  U1     N80  VSS1700  SOCKET4677_AZIFS054P001C01   I2
  U1     N82  VSS1701  SOCKET4677_AZIFS054P001C01   I2
  U1     N84  VSS1702  SOCKET4677_AZIFS054P001C01   I2
  U1     N88  VSS1703  SOCKET4677_AZIFS054P001C01   I2
  U1      P4  VSS1716  SOCKET4677_AZIFS054P001C01   I2
  U1      P8  VSS1729  SOCKET4677_AZIFS054P001C01   I2
  U1     P12  VSS1705  SOCKET4677_AZIFS054P001C01   I2
  U1     P16  VSS1706  SOCKET4677_AZIFS054P001C01   I2
  U1     P20  VSS1707  SOCKET4677_AZIFS054P001C01   I2
  U1     P22  VSS1708  SOCKET4677_AZIFS054P001C01   I2
  U1     P26  VSS1709  SOCKET4677_AZIFS054P001C01   I2
  U1     P28  VSS1710  SOCKET4677_AZIFS054P001C01   I2
  U1     P32  VSS1690  SOCKET4677_AZIFS054P001C01   I2
  U1     P34  VSS1712  SOCKET4677_AZIFS054P001C01   I2
  U1     P38  VSS1713  SOCKET4677_AZIFS054P001C01   I2
  U1     P40  VSS1717  SOCKET4677_AZIFS054P001C01   I2
  U1     P44  VSS1718  SOCKET4677_AZIFS054P001C01   I2
  U1     P47  VSS1719  SOCKET4677_AZIFS054P001C01   I2
  U1     P51  VSS1697  SOCKET4677_AZIFS054P001C01   I2
  U1     P53  VSS1720  SOCKET4677_AZIFS054P001C01   I2
  U1     P57  VSS1699  SOCKET4677_AZIFS054P001C01   I2
  U1     P59  VSS1721  SOCKET4677_AZIFS054P001C01   I2
  U1     P63  VSS1722  SOCKET4677_AZIFS054P001C01   I2
  U1     P65  VSS1724  SOCKET4677_AZIFS054P001C01   I2
  U1     P69  VSS1725  SOCKET4677_AZIFS054P001C01   I2
  U1     P71  VSS1704  SOCKET4677_AZIFS054P001C01   I2
  U1     P75  VSS1726  SOCKET4677_AZIFS054P001C01   I2
  U1     P77  VSS1727  SOCKET4677_AZIFS054P001C01   I2
  U1     P87  VSS1731  SOCKET4677_AZIFS054P001C01   I2
  U1     P91  VSS1732  SOCKET4677_AZIFS054P001C01   I2
  U1      R1  VSS1711  SOCKET4677_AZIFS054P001C01   I2
  U1      R5  VSS1745  SOCKET4677_AZIFS054P001C01   I2
  U1      R9  VSS1759  SOCKET4677_AZIFS054P001C01   I2
  U1     R13  VSS1733  SOCKET4677_AZIFS054P001C01   I2
  U1     R17  VSS1734  SOCKET4677_AZIFS054P001C01   I2
  U1     R19  VSS1714  SOCKET4677_AZIFS054P001C01   I2
  U1     R23  VSS1715  SOCKET4677_AZIFS054P001C01   I2
  U1     R25  VSS1735  SOCKET4677_AZIFS054P001C01   I2
  U1     R29  VSS1736  SOCKET4677_AZIFS054P001C01   I2
  U1     R31  VSS1737  SOCKET4677_AZIFS054P001C01   I2
  U1     R35  VSS1738  SOCKET4677_AZIFS054P001C01   I2
  U1     R37  VSS1742  SOCKET4677_AZIFS054P001C01   I2
  U1     R41  VSS1743  SOCKET4677_AZIFS054P001C01   I2
  U1     R43  VSS1744  SOCKET4677_AZIFS054P001C01   I2
  U1     R48  VSS1723  SOCKET4677_AZIFS054P001C01   I2
  U1     R50  VSS1747  SOCKET4677_AZIFS054P001C01   I2
  U1     R54  VSS1748  SOCKET4677_AZIFS054P001C01   I2
  U1     R56  VSS1751  SOCKET4677_AZIFS054P001C01   I2
  U1     R60  VSS1728  SOCKET4677_AZIFS054P001C01   I2
  U1     R62  VSS1752  SOCKET4677_AZIFS054P001C01   I2
  U1     R66  VSS1730  SOCKET4677_AZIFS054P001C01   I2
  U1     R68  VSS1753  SOCKET4677_AZIFS054P001C01   I2
  U1     R72  VSS1754  SOCKET4677_AZIFS054P001C01   I2
  U1     R74  VSS1755  SOCKET4677_AZIFS054P001C01   I2
  U1     R78  VSS1756  SOCKET4677_AZIFS054P001C01   I2
  U1     R84  VSS1757  SOCKET4677_AZIFS054P001C01   I2
  U1     R88  VSS1758  SOCKET4677_AZIFS054P001C01   I2
  U1      T4  VSS1762  SOCKET4677_AZIFS054P001C01   I2
  U1      T8  VSS1769  SOCKET4677_AZIFS054P001C01   I2
  U1     T12  VSS1739  SOCKET4677_AZIFS054P001C01   I2
  U1     T16  VSS1740  SOCKET4677_AZIFS054P001C01   I2
  U1     T18  VSS1741  SOCKET4677_AZIFS054P001C01   I2
  U1     T24  VSS1760  SOCKET4677_AZIFS054P001C01   I2
  U1     T30  VSS1761  SOCKET4677_AZIFS054P001C01   I2
  U1     T36  VSS1746  SOCKET4677_AZIFS054P001C01   I2
  U1     T42  VSS1763  SOCKET4677_AZIFS054P001C01   I2
  U1     T49  VSS1749  SOCKET4677_AZIFS054P001C01   I2
  U1     T55  VSS1750  SOCKET4677_AZIFS054P001C01   I2
  U1     T61  VSS1764  SOCKET4677_AZIFS054P001C01   I2
  U1     T67  VSS1765  SOCKET4677_AZIFS054P001C01   I2
  U1     T73  VSS1767  SOCKET4677_AZIFS054P001C01   I2
  U1     T79  VSS1768  SOCKET4677_AZIFS054P001C01   I2
  U1     T83  VSS1770  SOCKET4677_AZIFS054P001C01   I2
  U1     U39  VSS1771  SOCKET4677_AZIFS054P001C01   I2
  U1     U52  VSS1766  SOCKET4677_AZIFS054P001C01   I2
  U1     U82  VSS1772  SOCKET4677_AZIFS054P001C01   I2
  U1     U84  VSS1773  SOCKET4677_AZIFS054P001C01   I2
  U1     U88  VSS1774  SOCKET4677_AZIFS054P001C01   I2
  U1      V4  VSS1788  SOCKET4677_AZIFS054P001C01   I2
  U1      V8  VSS1812  SOCKET4677_AZIFS054P001C01   I2
  U1     V12  VSS1775  SOCKET4677_AZIFS054P001C01   I2
  U1     V16  VSS1776  SOCKET4677_AZIFS054P001C01   I2
  U1     V18  VSS1777  SOCKET4677_AZIFS054P001C01   I2
  U1     V20  VSS1778  SOCKET4677_AZIFS054P001C01   I2
  U1     V22  VSS1779  SOCKET4677_AZIFS054P001C01   I2
  U1     V24  VSS1780  SOCKET4677_AZIFS054P001C01   I2
  U1     V26  VSS1781  SOCKET4677_AZIFS054P001C01   I2
  U1     V28  VSS1782  SOCKET4677_AZIFS054P001C01   I2
  U1     V30  VSS1783  SOCKET4677_AZIFS054P001C01   I2
  U1     V32  VSS1784  SOCKET4677_AZIFS054P001C01   I2
  U1     V34  VSS1785  SOCKET4677_AZIFS054P001C01   I2
  U1     V36  VSS1786  SOCKET4677_AZIFS054P001C01   I2
  U1     V38  VSS1787  SOCKET4677_AZIFS054P001C01   I2
  U1     V40  VSS1790  SOCKET4677_AZIFS054P001C01   I2
  U1     V42  VSS1791  SOCKET4677_AZIFS054P001C01   I2
  U1     V44  VSS1792  SOCKET4677_AZIFS054P001C01   I2
  U1     V47  VSS1793  SOCKET4677_AZIFS054P001C01   I2
  U1     V49  VSS1789  SOCKET4677_AZIFS054P001C01   I2
  U1     V51  VSS1794  SOCKET4677_AZIFS054P001C01   I2
  U1     V53  VSS1795  SOCKET4677_AZIFS054P001C01   I2
  U1     V55  VSS1796  SOCKET4677_AZIFS054P001C01   I2
  U1     V57  VSS1797  SOCKET4677_AZIFS054P001C01   I2
  U1     V59  VSS1798  SOCKET4677_AZIFS054P001C01   I2
  U1     V61  VSS1799  SOCKET4677_AZIFS054P001C01   I2
  U1     V63  VSS1802  SOCKET4677_AZIFS054P001C01   I2
  U1     V65  VSS1803  SOCKET4677_AZIFS054P001C01   I2
  U1     V67  VSS1804  SOCKET4677_AZIFS054P001C01   I2
  U1     V69  VSS1805  SOCKET4677_AZIFS054P001C01   I2
  U1     V71  VSS1800  SOCKET4677_AZIFS054P001C01   I2
  U1     V73  VSS1801  SOCKET4677_AZIFS054P001C01   I2
  U1     V75  VSS1806  SOCKET4677_AZIFS054P001C01   I2
  U1     V77  VSS1810  SOCKET4677_AZIFS054P001C01   I2
  U1     V79  VSS1811  SOCKET4677_AZIFS054P001C01   I2
  U1     V87  VSS1813  SOCKET4677_AZIFS054P001C01   I2
  U1     V91  VSS1807  SOCKET4677_AZIFS054P001C01   I2
  U1      W1  VSS1808  SOCKET4677_AZIFS054P001C01   I2
  U1      W5  VSS1814  SOCKET4677_AZIFS054P001C01   I2
  U1      W9  VSS1819  SOCKET4677_AZIFS054P001C01   I2
  U1     W13  VSS1809  SOCKET4677_AZIFS054P001C01   I2
  U1     W39  VSS1816  SOCKET4677_AZIFS054P001C01   I2
  U1     W52  VSS1815  SOCKET4677_AZIFS054P001C01   I2
  U1     W84  VSS1817  SOCKET4677_AZIFS054P001C01   I2
  U1     W88  VSS1818  SOCKET4677_AZIFS054P001C01   I2
  U1      Y4  VSS1826  SOCKET4677_AZIFS054P001C01   I2
  U1      Y8  VSS1832  SOCKET4677_AZIFS054P001C01   I2
  U1     Y12  VSS1820  SOCKET4677_AZIFS054P001C01   I2
  U1     Y16  VSS1821  SOCKET4677_AZIFS054P001C01   I2
  U1     Y18  VSS1822  SOCKET4677_AZIFS054P001C01   I2
  U1     Y24  VSS1823  SOCKET4677_AZIFS054P001C01   I2
  U1     Y30  VSS1824  SOCKET4677_AZIFS054P001C01   I2
  U1     Y36  VSS1825  SOCKET4677_AZIFS054P001C01   I2
  U1     Y42  VSS1827  SOCKET4677_AZIFS054P001C01   I2
  U1     Y49  VSS1830  SOCKET4677_AZIFS054P001C01   I2
  U1     Y55  VSS1831  SOCKET4677_AZIFS054P001C01   I2
  U1     Y61  VSS1828  SOCKET4677_AZIFS054P001C01   I2
  U1     Y67  VSS1829  SOCKET4677_AZIFS054P001C01   I2
  U1     Y73  VSS1833  SOCKET4677_AZIFS054P001C01   I2
  U2     A11   VSS1  SOCKET4677_AZIFS054P001C01  I12
  U2     A13   VSS2  SOCKET4677_AZIFS054P001C01  I12
  U2     A17   VSS3  SOCKET4677_AZIFS054P001C01  I12
  U2     A19   VSS4  SOCKET4677_AZIFS054P001C01  I12
  U2     A23   VSS5  SOCKET4677_AZIFS054P001C01  I12
  U2     A25   VSS6  SOCKET4677_AZIFS054P001C01  I12
  U2     A29   VSS7  SOCKET4677_AZIFS054P001C01  I12
  U2     A31   VSS8  SOCKET4677_AZIFS054P001C01  I12
  U2     A35   VSS9  SOCKET4677_AZIFS054P001C01  I12
  U2     A37  VSS10  SOCKET4677_AZIFS054P001C01  I12
  U2     A41  VSS11  SOCKET4677_AZIFS054P001C01  I12
  U2     A50  VSS12  SOCKET4677_AZIFS054P001C01  I12
  U2     A54  VSS13  SOCKET4677_AZIFS054P001C01  I12
  U2     A56  VSS14  SOCKET4677_AZIFS054P001C01  I12
  U2     A60  VSS15  SOCKET4677_AZIFS054P001C01  I12
  U2     A62  VSS16  SOCKET4677_AZIFS054P001C01  I12
  U2     AA19  VSS17  SOCKET4677_AZIFS054P001C01  I10
  U2     AA23  VSS18  SOCKET4677_AZIFS054P001C01  I10
  U2     AA25  VSS19  SOCKET4677_AZIFS054P001C01  I10
  U2     AA29  VSS20  SOCKET4677_AZIFS054P001C01  I10
  U2     AA31  VSS21  SOCKET4677_AZIFS054P001C01  I10
  U2     AA35  VSS22  SOCKET4677_AZIFS054P001C01  I10
  U2     AA37  VSS23  SOCKET4677_AZIFS054P001C01  I10
  U2     AA41  VSS24  SOCKET4677_AZIFS054P001C01  I10
  U2     AA43  VSS25  SOCKET4677_AZIFS054P001C01  I10
  U2     AA48  VSS26  SOCKET4677_AZIFS054P001C01  I10
  U2     AA50  VSS27  SOCKET4677_AZIFS054P001C01  I10
  U2     AA54  VSS28  SOCKET4677_AZIFS054P001C01  I10
  U2     AA56  VSS29  SOCKET4677_AZIFS054P001C01  I10
  U2     AA60  VSS30  SOCKET4677_AZIFS054P001C01  I10
  U2     AA62  VSS31  SOCKET4677_AZIFS054P001C01  I10
  U2     AA66  VSS32  SOCKET4677_AZIFS054P001C01  I10
  U2     AA68  VSS33  SOCKET4677_AZIFS054P001C01  I10
  U2     AA72  VSS34  SOCKET4677_AZIFS054P001C01  I10
  U2     AA74  VSS35  SOCKET4677_AZIFS054P001C01  I10
  U2     AA78  VSS36  SOCKET4677_AZIFS054P001C01  I10
  U2     AA80  VSS37  SOCKET4677_AZIFS054P001C01  I10
  U2     AA82  VSS38  SOCKET4677_AZIFS054P001C01  I11
  U2     AA84  VSS39  SOCKET4677_AZIFS054P001C01  I11
  U2     AA88  VSS40  SOCKET4677_AZIFS054P001C01  I11
  U2     AB4  VSS50  SOCKET4677_AZIFS054P001C01  I11
  U2     AB8  VSS65  SOCKET4677_AZIFS054P001C01  I11
  U2     AB12  VSS41  SOCKET4677_AZIFS054P001C01  I11
  U2     AB16  VSS42  SOCKET4677_AZIFS054P001C01  I11
  U2     AB20  VSS43  SOCKET4677_AZIFS054P001C01  I11
  U2     AB22  VSS44  SOCKET4677_AZIFS054P001C01  I11
  U2     AB26  VSS45  SOCKET4677_AZIFS054P001C01  I11
  U2     AB28  VSS46  SOCKET4677_AZIFS054P001C01  I11
  U2     AB32  VSS47  SOCKET4677_AZIFS054P001C01  I11
  U2     AB34  VSS48  SOCKET4677_AZIFS054P001C01  I11
  U2     AB38  VSS49  SOCKET4677_AZIFS054P001C01  I11
  U2     AB40  VSS51  SOCKET4677_AZIFS054P001C01  I11
  U2     AB44  VSS52  SOCKET4677_AZIFS054P001C01  I11
  U2     AB47  VSS53  SOCKET4677_AZIFS054P001C01  I11
  U2     AB51  VSS54  SOCKET4677_AZIFS054P001C01  I11
  U2     AB53  VSS55  SOCKET4677_AZIFS054P001C01  I11
  U2     AB57  VSS56  SOCKET4677_AZIFS054P001C01  I11
  U2     AB59  VSS57  SOCKET4677_AZIFS054P001C01  I11
  U2     AB63  VSS58  SOCKET4677_AZIFS054P001C01  I11
  U2     AB65  VSS59  SOCKET4677_AZIFS054P001C01  I11
  U2     AB69  VSS60  SOCKET4677_AZIFS054P001C01  I11
  U2     AB71  VSS61  SOCKET4677_AZIFS054P001C01  I11
  U2     AB75  VSS62  SOCKET4677_AZIFS054P001C01  I11
  U2     AB77  VSS63  SOCKET4677_AZIFS054P001C01  I11
  U2     AB79  VSS64  SOCKET4677_AZIFS054P001C01  I11
  U2     AB81  VSS66  SOCKET4677_AZIFS054P001C01  I11
  U2     AB83  VSS67  SOCKET4677_AZIFS054P001C01  I11
  U2     AB87  VSS68  SOCKET4677_AZIFS054P001C01  I11
  U2     AB91  VSS69  SOCKET4677_AZIFS054P001C01  I11
  U2     AC1  VSS70  SOCKET4677_AZIFS054P001C01  I11
  U2     AC5  VSS77  SOCKET4677_AZIFS054P001C01  I11
  U2     AC9  VSS85  SOCKET4677_AZIFS054P001C01  I11
  U2     AC13  VSS71  SOCKET4677_AZIFS054P001C01  I11
  U2     AC21  VSS72  SOCKET4677_AZIFS054P001C01  I11
  U2     AC27  VSS73  SOCKET4677_AZIFS054P001C01  I11
  U2     AC33  VSS74  SOCKET4677_AZIFS054P001C01  I11
  U2     AC39  VSS75  SOCKET4677_AZIFS054P001C01  I11
  U2     AC45  VSS76  SOCKET4677_AZIFS054P001C01  I11
  U2     AC52  VSS78  SOCKET4677_AZIFS054P001C01  I11
  U2     AC58  VSS79  SOCKET4677_AZIFS054P001C01  I11
  U2     AC64  VSS80  SOCKET4677_AZIFS054P001C01  I11
  U2     AC70  VSS81  SOCKET4677_AZIFS054P001C01  I11
  U2     AC76  VSS82  SOCKET4677_AZIFS054P001C01  I11
  U2     AC84  VSS83  SOCKET4677_AZIFS054P001C01  I11
  U2     AC88  VSS84  SOCKET4677_AZIFS054P001C01  I11
  U2     AD4  VSS88  SOCKET4677_AZIFS054P001C01  I11
  U2     AD8  VSS91  SOCKET4677_AZIFS054P001C01  I11
  U2     AD12  VSS86  SOCKET4677_AZIFS054P001C01  I11
  U2     AD16  VSS87  SOCKET4677_AZIFS054P001C01  I11
  U2     AD42  VSS89  SOCKET4677_AZIFS054P001C01  I11
  U2     AD79  VSS90  SOCKET4677_AZIFS054P001C01  I11
  U2     AD83  VSS92  SOCKET4677_AZIFS054P001C01  I11
  U2     AE17  VSS93  SOCKET4677_AZIFS054P001C01  I11
  U2     AE19  VSS94  SOCKET4677_AZIFS054P001C01  I11
  U2     AE21  VSS95  SOCKET4677_AZIFS054P001C01  I11
  U2     AE23  VSS96  SOCKET4677_AZIFS054P001C01  I11
  U2     AE25  VSS97  SOCKET4677_AZIFS054P001C01  I11
  U2     AE27  VSS98  SOCKET4677_AZIFS054P001C01  I11
  U2     AE29  VSS99  SOCKET4677_AZIFS054P001C01  I11
  U2     AE31  VSS100  SOCKET4677_AZIFS054P001C01  I11
  U2     AE33  VSS101  SOCKET4677_AZIFS054P001C01  I11
  U2     AE35  VSS102  SOCKET4677_AZIFS054P001C01  I11
  U2     AE37  VSS103  SOCKET4677_AZIFS054P001C01  I11
  U2     AE39  VSS104  SOCKET4677_AZIFS054P001C01  I11
  U2     AE41  VSS105  SOCKET4677_AZIFS054P001C01  I11
  U2     AE43  VSS106  SOCKET4677_AZIFS054P001C01  I11
  U2     AE45  VSS107  SOCKET4677_AZIFS054P001C01  I11
  U2     AE48  VSS108  SOCKET4677_AZIFS054P001C01  I11
  U2     AE50  VSS109  SOCKET4677_AZIFS054P001C01  I11
  U2     AE52  VSS110  SOCKET4677_AZIFS054P001C01  I11
  U2     AE54  VSS111  SOCKET4677_AZIFS054P001C01  I11
  U2     AE56  VSS112  SOCKET4677_AZIFS054P001C01  I11
  U2     AE58  VSS113  SOCKET4677_AZIFS054P001C01  I11
  U2     AE60  VSS114  SOCKET4677_AZIFS054P001C01  I11
  U2     AE62  VSS115  SOCKET4677_AZIFS054P001C01  I11
  U2     AE64  VSS116  SOCKET4677_AZIFS054P001C01  I11
  U2     AE66  VSS117  SOCKET4677_AZIFS054P001C01  I11
  U2     AE68  VSS118  SOCKET4677_AZIFS054P001C01  I11
  U2     AE70  VSS119  SOCKET4677_AZIFS054P001C01  I11
  U2     AE72  VSS120  SOCKET4677_AZIFS054P001C01  I11
  U2     AE74  VSS121  SOCKET4677_AZIFS054P001C01  I11
  U2     AE76  VSS122  SOCKET4677_AZIFS054P001C01  I11
  U2     AE78  VSS123  SOCKET4677_AZIFS054P001C01  I11
  U2     AE84  VSS124  SOCKET4677_AZIFS054P001C01  I11
  U2     AE88  VSS125  SOCKET4677_AZIFS054P001C01  I11
  U2     AF4  VSS128  SOCKET4677_AZIFS054P001C01  I11
  U2     AF8  VSS130  SOCKET4677_AZIFS054P001C01  I11
  U2     AF12  VSS126  SOCKET4677_AZIFS054P001C01  I11
  U2     AF16  VSS127  SOCKET4677_AZIFS054P001C01  I11
  U2     AF42  VSS129  SOCKET4677_AZIFS054P001C01  I11
  U2     AF81  VSS131  SOCKET4677_AZIFS054P001C01  I11
  U2     AF87  VSS132  SOCKET4677_AZIFS054P001C01  I11
  U2     AF91  VSS133  SOCKET4677_AZIFS054P001C01  I11
  U2     AG1  VSS134  SOCKET4677_AZIFS054P001C01  I11
  U2     AG5  VSS141  SOCKET4677_AZIFS054P001C01  I11
  U2     AG9  VSS149  SOCKET4677_AZIFS054P001C01  I11
  U2     AG13  VSS135  SOCKET4677_AZIFS054P001C01  I11
  U2     AG21  VSS136  SOCKET4677_AZIFS054P001C01  I11
  U2     AG27  VSS137  SOCKET4677_AZIFS054P001C01  I11
  U2     AG33  VSS138  SOCKET4677_AZIFS054P001C01  I11
  U2     AG39  VSS139  SOCKET4677_AZIFS054P001C01  I11
  U2     AG45  VSS140  SOCKET4677_AZIFS054P001C01  I11
  U2     AG52  VSS142  SOCKET4677_AZIFS054P001C01  I11
  U2     AG58  VSS143  SOCKET4677_AZIFS054P001C01  I11
  U2     AG64  VSS144  SOCKET4677_AZIFS054P001C01  I11
  U2     AG70  VSS145  SOCKET4677_AZIFS054P001C01  I11
  U2     AG76  VSS146  SOCKET4677_AZIFS054P001C01  I11
  U2     AG84  VSS147  SOCKET4677_AZIFS054P001C01  I11
  U2     AG88  VSS148  SOCKET4677_AZIFS054P001C01  I11
  U2     AH4  VSS159  SOCKET4677_AZIFS054P001C01  I11
  U2     AH8  VSS174  SOCKET4677_AZIFS054P001C01  I11
  U2     AH12  VSS150  SOCKET4677_AZIFS054P001C01  I11
  U2     AH16  VSS151  SOCKET4677_AZIFS054P001C01  I11
  U2     AH20  VSS152  SOCKET4677_AZIFS054P001C01  I11
  U2     AH22  VSS153  SOCKET4677_AZIFS054P001C01  I11
  U2     AH26  VSS154  SOCKET4677_AZIFS054P001C01  I11
  U2     AH28  VSS155  SOCKET4677_AZIFS054P001C01  I11
  U2     AH32  VSS156  SOCKET4677_AZIFS054P001C01  I11
  U2     AH34  VSS157  SOCKET4677_AZIFS054P001C01  I11
  U2     AH38  VSS158  SOCKET4677_AZIFS054P001C01  I11
  U2     AH40  VSS160  SOCKET4677_AZIFS054P001C01  I11
  U2     AH44  VSS161  SOCKET4677_AZIFS054P001C01  I11
  U2     AH47  VSS162  SOCKET4677_AZIFS054P001C01  I11
  U2     AH51  VSS163  SOCKET4677_AZIFS054P001C01  I11
  U2     AH53  VSS164  SOCKET4677_AZIFS054P001C01  I11
  U2     AH57  VSS165  SOCKET4677_AZIFS054P001C01  I11
  U2     AH59  VSS166  SOCKET4677_AZIFS054P001C01  I11
  U2     AH63  VSS167  SOCKET4677_AZIFS054P001C01  I11
  U2     AH65  VSS168  SOCKET4677_AZIFS054P001C01  I11
  U2     AH69  VSS169  SOCKET4677_AZIFS054P001C01  I11
  U2     AH71  VSS170  SOCKET4677_AZIFS054P001C01  I11
  U2     AH75  VSS171  SOCKET4677_AZIFS054P001C01  I11
  U2     AH77  VSS172  SOCKET4677_AZIFS054P001C01  I11
  U2     AH79  VSS173  SOCKET4677_AZIFS054P001C01  I11
  U2     AH83  VSS175  SOCKET4677_AZIFS054P001C01  I11
  U2     AJ19  VSS176  SOCKET4677_AZIFS054P001C01  I11
  U2     AJ23  VSS177  SOCKET4677_AZIFS054P001C01  I11
  U2     AJ25  VSS178  SOCKET4677_AZIFS054P001C01  I11
  U2     AJ29  VSS179  SOCKET4677_AZIFS054P001C01  I11
  U2     AJ31  VSS180  SOCKET4677_AZIFS054P001C01  I11
  U2     AJ35  VSS181  SOCKET4677_AZIFS054P001C01  I11
  U2     AJ37  VSS182  SOCKET4677_AZIFS054P001C01  I11
  U2     AJ41  VSS183  SOCKET4677_AZIFS054P001C01  I11
  U2     AJ43  VSS184  SOCKET4677_AZIFS054P001C01  I11
  U2     AJ48  VSS185  SOCKET4677_AZIFS054P001C01  I11
  U2     AJ50  VSS186  SOCKET4677_AZIFS054P001C01  I11
  U2     AJ54  VSS187  SOCKET4677_AZIFS054P001C01  I11
  U2     AJ56  VSS188  SOCKET4677_AZIFS054P001C01  I11
  U2     AJ60  VSS189  SOCKET4677_AZIFS054P001C01  I11
  U2     AJ62  VSS190  SOCKET4677_AZIFS054P001C01  I11
  U2     AJ66  VSS191  SOCKET4677_AZIFS054P001C01  I11
  U2     AJ68  VSS192  SOCKET4677_AZIFS054P001C01  I11
  U2     AJ72  VSS193  SOCKET4677_AZIFS054P001C01  I11
  U2     AJ74  VSS194  SOCKET4677_AZIFS054P001C01  I11
  U2     AJ78  VSS195  SOCKET4677_AZIFS054P001C01  I11
  U2     AJ84  VSS196  SOCKET4677_AZIFS054P001C01  I11
  U2     AJ88  VSS197  SOCKET4677_AZIFS054P001C01  I11
  U2     AK4  VSS204  SOCKET4677_AZIFS054P001C01  I10
  U2     AK8  VSS212  SOCKET4677_AZIFS054P001C01  I10
  U2     AK12  VSS198  SOCKET4677_AZIFS054P001C01  I10
  U2     AK16  VSS199  SOCKET4677_AZIFS054P001C01  I10
  U2     AK18  VSS200  SOCKET4677_AZIFS054P001C01  I10
  U2     AK24  VSS201  SOCKET4677_AZIFS054P001C01  I10
  U2     AK30  VSS202  SOCKET4677_AZIFS054P001C01  I10
  U2     AK36  VSS203  SOCKET4677_AZIFS054P001C01  I10
  U2     AK42  VSS205  SOCKET4677_AZIFS054P001C01  I10
  U2     AK49  VSS206  SOCKET4677_AZIFS054P001C01  I10
  U2     AK55  VSS207  SOCKET4677_AZIFS054P001C01  I10
  U2     AK61  VSS208  SOCKET4677_AZIFS054P001C01  I10
  U2     AK67  VSS209  SOCKET4677_AZIFS054P001C01  I10
  U2     AK73  VSS210  SOCKET4677_AZIFS054P001C01  I10
  U2     AK79  VSS211  SOCKET4677_AZIFS054P001C01  I10
  U2     AK81  VSS213  SOCKET4677_AZIFS054P001C01  I10
  U2     AK83  VSS214  SOCKET4677_AZIFS054P001C01  I10
  U2     AK87  VSS215  SOCKET4677_AZIFS054P001C01  I10
  U2     AK91  VSS216  SOCKET4677_AZIFS054P001C01  I10
  U2     AL1  VSS217  SOCKET4677_AZIFS054P001C01  I10
  U2     AL5  VSS220  SOCKET4677_AZIFS054P001C01  I10
  U2     AL9  VSS226  SOCKET4677_AZIFS054P001C01  I10
  U2     AL13  VSS218  SOCKET4677_AZIFS054P001C01  I10
  U2     AL17  VSS219  SOCKET4677_AZIFS054P001C01  I10
  U2     AL52  VSS221  SOCKET4677_AZIFS054P001C01  I10
  U2     AL80  VSS222  SOCKET4677_AZIFS054P001C01  I10
  U2     AL82  VSS223  SOCKET4677_AZIFS054P001C01  I10
  U2     AL84  VSS224  SOCKET4677_AZIFS054P001C01  I10
  U2     AL88  VSS225  SOCKET4677_AZIFS054P001C01  I10
  U2     AM4  VSS240  SOCKET4677_AZIFS054P001C01  I10
  U2     AM8  VSS260  SOCKET4677_AZIFS054P001C01  I10
  U2     AM12  VSS227  SOCKET4677_AZIFS054P001C01  I10
  U2     AM16  VSS228  SOCKET4677_AZIFS054P001C01  I10
  U2     AM18  VSS229  SOCKET4677_AZIFS054P001C01  I10
  U2     AM20  VSS230  SOCKET4677_AZIFS054P001C01  I10
  U2     AM22  VSS231  SOCKET4677_AZIFS054P001C01  I10
  U2     AM24  VSS232  SOCKET4677_AZIFS054P001C01  I10
  U2     AM26  VSS233  SOCKET4677_AZIFS054P001C01  I10
  U2     AM28  VSS234  SOCKET4677_AZIFS054P001C01  I10
  U2     AM30  VSS235  SOCKET4677_AZIFS054P001C01  I10
  U2     AM32  VSS236  SOCKET4677_AZIFS054P001C01  I10
  U2     AM34  VSS237  SOCKET4677_AZIFS054P001C01  I10
  U2     AM36  VSS238  SOCKET4677_AZIFS054P001C01  I10
  U2     AM38  VSS239  SOCKET4677_AZIFS054P001C01  I10
  U2     AM40  VSS241  SOCKET4677_AZIFS054P001C01  I10
  U2     AM42  VSS242  SOCKET4677_AZIFS054P001C01  I10
  U2     AM44  VSS243  SOCKET4677_AZIFS054P001C01  I10
  U2     AM47  VSS244  SOCKET4677_AZIFS054P001C01  I10
  U2     AM49  VSS245  SOCKET4677_AZIFS054P001C01  I10
  U2     AM51  VSS246  SOCKET4677_AZIFS054P001C01  I10
  U2     AM53  VSS247  SOCKET4677_AZIFS054P001C01  I10
  U2     AM55  VSS248  SOCKET4677_AZIFS054P001C01  I10
  U2     AM57  VSS249  SOCKET4677_AZIFS054P001C01  I10
  U2     AM59  VSS250  SOCKET4677_AZIFS054P001C01  I10
  U2     AM61  VSS251  SOCKET4677_AZIFS054P001C01  I10
  U2     AM63  VSS252  SOCKET4677_AZIFS054P001C01  I10
  U2     AM65  VSS253  SOCKET4677_AZIFS054P001C01  I10
  U2     AM67  VSS254  SOCKET4677_AZIFS054P001C01  I10
  U2     AM69  VSS255  SOCKET4677_AZIFS054P001C01  I10
  U2     AM71  VSS256  SOCKET4677_AZIFS054P001C01  I10
  U2     AM73  VSS257  SOCKET4677_AZIFS054P001C01  I10
  U2     AM75  VSS258  SOCKET4677_AZIFS054P001C01  I10
  U2     AM77  VSS259  SOCKET4677_AZIFS054P001C01  I10
  U2     AN52  VSS261  SOCKET4677_AZIFS054P001C01  I10
  U2     AN84  VSS262  SOCKET4677_AZIFS054P001C01  I10
  U2     AN88  VSS263  SOCKET4677_AZIFS054P001C01  I10
  U2     AP4  VSS270  SOCKET4677_AZIFS054P001C01  I10
  U2     AP8  VSS278  SOCKET4677_AZIFS054P001C01  I10
  U2     AP12  VSS264  SOCKET4677_AZIFS054P001C01  I10
  U2     AP16  VSS265  SOCKET4677_AZIFS054P001C01  I10
  U2     AP18  VSS266  SOCKET4677_AZIFS054P001C01  I10
  U2     AP24  VSS267  SOCKET4677_AZIFS054P001C01  I10
  U2     AP30  VSS268  SOCKET4677_AZIFS054P001C01  I10
  U2     AP36  VSS269  SOCKET4677_AZIFS054P001C01  I10
  U2     AP42  VSS271  SOCKET4677_AZIFS054P001C01  I10
  U2     AP49  VSS272  SOCKET4677_AZIFS054P001C01  I10
  U2     AP55  VSS273  SOCKET4677_AZIFS054P001C01  I10
  U2     AP61  VSS274  SOCKET4677_AZIFS054P001C01  I10
  U2     AP67  VSS275  SOCKET4677_AZIFS054P001C01  I10
  U2     AP73  VSS276  SOCKET4677_AZIFS054P001C01  I10
  U2     AP79  VSS277  SOCKET4677_AZIFS054P001C01  I10
  U2     AP83  VSS279  SOCKET4677_AZIFS054P001C01  I10
  U2     AP87  VSS280  SOCKET4677_AZIFS054P001C01  I10
  U2     AP91  VSS281  SOCKET4677_AZIFS054P001C01  I10
  U2     AR1  VSS282  SOCKET4677_AZIFS054P001C01  I10
  U2     AR5  VSS294  SOCKET4677_AZIFS054P001C01  I10
  U2     AR9  VSS308  SOCKET4677_AZIFS054P001C01  I10
  U2     AR13  VSS283  SOCKET4677_AZIFS054P001C01  I10
  U2     AR19  VSS284  SOCKET4677_AZIFS054P001C01  I10
  U2     AR23  VSS285  SOCKET4677_AZIFS054P001C01  I10
  U2     AR25  VSS286  SOCKET4677_AZIFS054P001C01  I10
  U2     AR29  VSS287  SOCKET4677_AZIFS054P001C01  I10
  U2     AR31  VSS288  SOCKET4677_AZIFS054P001C01  I10
  U2     AR35  VSS289  SOCKET4677_AZIFS054P001C01  I10
  U2     AR37  VSS290  SOCKET4677_AZIFS054P001C01  I10
  U2     AR41  VSS291  SOCKET4677_AZIFS054P001C01  I10
  U2     AR43  VSS292  SOCKET4677_AZIFS054P001C01  I10
  U2     AR48  VSS293  SOCKET4677_AZIFS054P001C01  I10
  U2     AR50  VSS295  SOCKET4677_AZIFS054P001C01  I10
  U2     AR54  VSS296  SOCKET4677_AZIFS054P001C01  I10
  U2     AR56  VSS297  SOCKET4677_AZIFS054P001C01  I10
  U2     AR60  VSS298  SOCKET4677_AZIFS054P001C01  I10
  U2     AR62  VSS299  SOCKET4677_AZIFS054P001C01  I10
  U2     AR66  VSS300  SOCKET4677_AZIFS054P001C01  I10
  U2     AR68  VSS301  SOCKET4677_AZIFS054P001C01  I10
  U2     AR72  VSS302  SOCKET4677_AZIFS054P001C01  I10
  U2     AR74  VSS303  SOCKET4677_AZIFS054P001C01  I10
  U2     AR78  VSS304  SOCKET4677_AZIFS054P001C01  I10
  U2     AR82  VSS305  SOCKET4677_AZIFS054P001C01  I10
  U2     AR84  VSS306  SOCKET4677_AZIFS054P001C01  I10
  U2     AR88  VSS307  SOCKET4677_AZIFS054P001C01  I10
  U2     AT4  VSS318  SOCKET4677_AZIFS054P001C01  I10
  U2     AT8  VSS332  SOCKET4677_AZIFS054P001C01  I10
  U2     AT12  VSS309  SOCKET4677_AZIFS054P001C01  I10
  U2     AT16  VSS310  SOCKET4677_AZIFS054P001C01  I10
  U2     AT20  VSS311  SOCKET4677_AZIFS054P001C01  I10
  U2     AT22  VSS312  SOCKET4677_AZIFS054P001C01  I10
  U2     AT26  VSS313  SOCKET4677_AZIFS054P001C01  I10
  U2     AT28  VSS314  SOCKET4677_AZIFS054P001C01  I10
  U2     AT32  VSS315  SOCKET4677_AZIFS054P001C01  I10
  U2     AT34  VSS316  SOCKET4677_AZIFS054P001C01  I10
  U2     AT38  VSS317  SOCKET4677_AZIFS054P001C01  I10
  U2     AT40  VSS319  SOCKET4677_AZIFS054P001C01  I10
  U2     AT44  VSS320  SOCKET4677_AZIFS054P001C01  I10
  U2     AT51  VSS321  SOCKET4677_AZIFS054P001C01  I10
  U2     AT53  VSS322  SOCKET4677_AZIFS054P001C01  I10
  U2     AT57  VSS323  SOCKET4677_AZIFS054P001C01  I10
  U2     AT59  VSS324  SOCKET4677_AZIFS054P001C01  I10
  U2     AT63  VSS325  SOCKET4677_AZIFS054P001C01  I10
  U2     AT65  VSS326  SOCKET4677_AZIFS054P001C01  I10
  U2     AT69  VSS327  SOCKET4677_AZIFS054P001C01  I10
  U2     AT71  VSS328  SOCKET4677_AZIFS054P001C01  I10
  U2     AT75  VSS329  SOCKET4677_AZIFS054P001C01  I10
  U2     AT77  VSS330  SOCKET4677_AZIFS054P001C01  I10
  U2     AT79  VSS331  SOCKET4677_AZIFS054P001C01  I10
  U2     AU27  VSS333  SOCKET4677_AZIFS054P001C01  I10
  U2     AU31  VSS334  SOCKET4677_AZIFS054P001C01  I10
  U2     AU37  VSS335  SOCKET4677_AZIFS054P001C01  I10
  U2     AU39  VSS336  SOCKET4677_AZIFS054P001C01  I10
  U2     AU41  VSS337  SOCKET4677_AZIFS054P001C01  I10
  U2     AU45  VSS338  SOCKET4677_AZIFS054P001C01  I10
  U2     AU48  VSS339  SOCKET4677_AZIFS054P001C01  I10
  U2     AU70  VSS340  SOCKET4677_AZIFS054P001C01  I10
  U2     AU72  VSS341  SOCKET4677_AZIFS054P001C01  I10
  U2     AU74  VSS342  SOCKET4677_AZIFS054P001C01  I10
  U2     AU76  VSS343  SOCKET4677_AZIFS054P001C01  I10
  U2     AU80  VSS344  SOCKET4677_AZIFS054P001C01  I10
  U2     AU84  VSS345  SOCKET4677_AZIFS054P001C01  I10
  U2     AU88  VSS346  SOCKET4677_AZIFS054P001C01  I10
  U2     AV4  VSS349  SOCKET4677_AZIFS054P001C01  I10
  U2     AV8  VSS351  SOCKET4677_AZIFS054P001C01  I10
  U2     AV12  VSS347  SOCKET4677_AZIFS054P001C01  I10
  U2     AV16  VSS348  SOCKET4677_AZIFS054P001C01  I10
  U2     AV77  VSS350  SOCKET4677_AZIFS054P001C01  I10
  U2     AV87  VSS352  SOCKET4677_AZIFS054P001C01  I10
  U2     AV91  VSS353  SOCKET4677_AZIFS054P001C01  I10
  U2     AW1  VSS354  SOCKET4677_AZIFS054P001C01  I10
  U2     AW5  VSS359  SOCKET4677_AZIFS054P001C01  I10
  U2     AW9  VSS368  SOCKET4677_AZIFS054P001C01  I10
  U2     AW13  VSS355  SOCKET4677_AZIFS054P001C01  I10
  U2     AW21  VSS356  SOCKET4677_AZIFS054P001C01   I9
  U2     AW23  VSS357  SOCKET4677_AZIFS054P001C01   I9
  U2     AW25  VSS358  SOCKET4677_AZIFS054P001C01   I9
  U2     AW62  VSS360  SOCKET4677_AZIFS054P001C01   I9
  U2     AW66  VSS361  SOCKET4677_AZIFS054P001C01   I9
  U2     AW68  VSS362  SOCKET4677_AZIFS054P001C01   I9
  U2     AW72  VSS363  SOCKET4677_AZIFS054P001C01   I9
  U2     AW80  VSS364  SOCKET4677_AZIFS054P001C01   I9
  U2     AW82  VSS365  SOCKET4677_AZIFS054P001C01   I9
  U2     AW84  VSS366  SOCKET4677_AZIFS054P001C01   I9
  U2     AW88  VSS367  SOCKET4677_AZIFS054P001C01   I9
  U2     AY4  VSS371  SOCKET4677_AZIFS054P001C01   I9
  U2     AY8  VSS375  SOCKET4677_AZIFS054P001C01   I9
  U2     AY12  VSS369  SOCKET4677_AZIFS054P001C01   I9
  U2     AY16  VSS370  SOCKET4677_AZIFS054P001C01   I9
  U2     AY71  VSS372  SOCKET4677_AZIFS054P001C01   I9
  U2     AY77  VSS373  SOCKET4677_AZIFS054P001C01   I9
  U2     AY79  VSS374  SOCKET4677_AZIFS054P001C01   I9
  U2     AY81  VSS376  SOCKET4677_AZIFS054P001C01   I9
  U2     AY83  VSS377  SOCKET4677_AZIFS054P001C01   I9
  U2      B6  VSS387  SOCKET4677_AZIFS054P001C01  I12
  U2     B12  VSS378  SOCKET4677_AZIFS054P001C01  I12
  U2     B18  VSS379  SOCKET4677_AZIFS054P001C01  I12
  U2     B24  VSS380  SOCKET4677_AZIFS054P001C01  I12
  U2     B30  VSS381  SOCKET4677_AZIFS054P001C01  I12
  U2     B36  VSS382  SOCKET4677_AZIFS054P001C01  I12
  U2     B42  VSS384  SOCKET4677_AZIFS054P001C01  I12
  U2     B49  VSS385  SOCKET4677_AZIFS054P001C01  I12
  U2     B55  VSS386  SOCKET4677_AZIFS054P001C01  I12
  U2     B61  VSS388  SOCKET4677_AZIFS054P001C01  I12
  U2     B67  VSS389  SOCKET4677_AZIFS054P001C01  I12
  U2     B75  VSS390  SOCKET4677_AZIFS054P001C01  I12
  U2     B83  VSS391  SOCKET4677_AZIFS054P001C01  I12
  U2     B87  VSS392  SOCKET4677_AZIFS054P001C01  I12
  U2     BA17  VSS393  SOCKET4677_AZIFS054P001C01   I9
  U2     BA60  VSS394  SOCKET4677_AZIFS054P001C01   I9
  U2     BA64  VSS395  SOCKET4677_AZIFS054P001C01   I9
  U2     BA74  VSS397  SOCKET4677_AZIFS054P001C01   I9
  U2     BA84  VSS398  SOCKET4677_AZIFS054P001C01   I9
  U2     BA88  VSS399  SOCKET4677_AZIFS054P001C01   I9
  U2     BB4  VSS407  SOCKET4677_AZIFS054P001C01   I9
  U2     BB8  VSS413  SOCKET4677_AZIFS054P001C01   I9
  U2     BB10  VSS400  SOCKET4677_AZIFS054P001C01   I9
  U2     BB12  VSS401  SOCKET4677_AZIFS054P001C01   I9
  U2     BB16  VSS402  SOCKET4677_AZIFS054P001C01   I9
  U2     BB20  VSS403  SOCKET4677_AZIFS054P001C01   I9
  U2     BB22  VSS404  SOCKET4677_AZIFS054P001C01   I9
  U2     BB24  VSS405  SOCKET4677_AZIFS054P001C01   I9
  U2     BB26  VSS406  SOCKET4677_AZIFS054P001C01   I9
  U2     BB63  VSS408  SOCKET4677_AZIFS054P001C01   I9
  U2     BB69  VSS409  SOCKET4677_AZIFS054P001C01   I9
  U2     BB71  VSS410  SOCKET4677_AZIFS054P001C01   I9
  U2     BB77  VSS411  SOCKET4677_AZIFS054P001C01   I9
  U2     BB79  VSS412  SOCKET4677_AZIFS054P001C01   I9
  U2     BB83  VSS414  SOCKET4677_AZIFS054P001C01   I9
  U2     BB87  VSS415  SOCKET4677_AZIFS054P001C01   I9
  U2     BB91  VSS416  SOCKET4677_AZIFS054P001C01   I9
  U2     BC1  VSS417  SOCKET4677_AZIFS054P001C01   I9
  U2     BC5  VSS420  SOCKET4677_AZIFS054P001C01   I9
  U2     BC9  VSS429  SOCKET4677_AZIFS054P001C01   I9
  U2     BC13  VSS418  SOCKET4677_AZIFS054P001C01   I9
  U2     BC17  VSS419  SOCKET4677_AZIFS054P001C01   I9
  U2     BC62  VSS421  SOCKET4677_AZIFS054P001C01   I9
  U2     BC66  VSS422  SOCKET4677_AZIFS054P001C01   I9
  U2     BC72  VSS423  SOCKET4677_AZIFS054P001C01   I9
  U2     BC76  VSS424  SOCKET4677_AZIFS054P001C01   I9
  U2     BC78  VSS425  SOCKET4677_AZIFS054P001C01   I9
  U2     BC84  VSS426  SOCKET4677_AZIFS054P001C01   I9
  U2     BC86  VSS427  SOCKET4677_AZIFS054P001C01   I9
  U2     BC88  VSS428  SOCKET4677_AZIFS054P001C01   I9
  U2     BD4  VSS433  SOCKET4677_AZIFS054P001C01   I9
  U2     BD8  VSS434  SOCKET4677_AZIFS054P001C01   I9
  U2     BD12  VSS430  SOCKET4677_AZIFS054P001C01   I9
  U2     BD16  VSS431  SOCKET4677_AZIFS054P001C01   I9
  U2     BD20  VSS432  SOCKET4677_AZIFS054P001C01   I9
  U2     BD81  VSS435  SOCKET4677_AZIFS054P001C01   I9
  U2     BD85  VSS437  SOCKET4677_AZIFS054P001C01   I9
  U2     BD89  VSS439  SOCKET4677_AZIFS054P001C01   I9
  U2     BE64  VSS440  SOCKET4677_AZIFS054P001C01   I9
  U2     BE66  VSS441  SOCKET4677_AZIFS054P001C01   I9
  U2     BE68  VSS442  SOCKET4677_AZIFS054P001C01   I9
  U2     BE74  VSS443  SOCKET4677_AZIFS054P001C01   I9
  U2     BE76  VSS444  SOCKET4677_AZIFS054P001C01   I9
  U2     BE78  VSS445  SOCKET4677_AZIFS054P001C01   I9
  U2     BE84  VSS446  SOCKET4677_AZIFS054P001C01   I9
  U2     BF4  VSS450  SOCKET4677_AZIFS054P001C01   I9
  U2     BF8  VSS456  SOCKET4677_AZIFS054P001C01   I9
  U2     BF12  VSS447  SOCKET4677_AZIFS054P001C01   I9
  U2     BF16  VSS448  SOCKET4677_AZIFS054P001C01   I9
  U2     BF20  VSS449  SOCKET4677_AZIFS054P001C01   I9
  U2     BF61  VSS451  SOCKET4677_AZIFS054P001C01   I9
  U2     BF63  VSS452  SOCKET4677_AZIFS054P001C01   I9
  U2     BF73  VSS453  SOCKET4677_AZIFS054P001C01   I9
  U2     BF75  VSS454  SOCKET4677_AZIFS054P001C01   I9
  U2     BF79  VSS455  SOCKET4677_AZIFS054P001C01   I9
  U2     BF83  VSS457  SOCKET4677_AZIFS054P001C01   I9
  U2     BG1  VSS458  SOCKET4677_AZIFS054P001C01   I9
  U2     BG5  VSS464  SOCKET4677_AZIFS054P001C01   I9
  U2     BG9  VSS466  SOCKET4677_AZIFS054P001C01   I9
  U2     BG13  VSS459  SOCKET4677_AZIFS054P001C01   I9
  U2     BG17  VSS460  SOCKET4677_AZIFS054P001C01   I9
  U2     BG21  VSS461  SOCKET4677_AZIFS054P001C01   I9
  U2     BG23  VSS462  SOCKET4677_AZIFS054P001C01   I9
  U2     BG25  VSS463  SOCKET4677_AZIFS054P001C01   I9
  U2     BG70  VSS465  SOCKET4677_AZIFS054P001C01   I9
  U2     BH4  VSS470  SOCKET4677_AZIFS054P001C01   I9
  U2     BH8  VSS475  SOCKET4677_AZIFS054P001C01   I9
  U2     BH12  VSS467  SOCKET4677_AZIFS054P001C01   I9
  U2     BH16  VSS468  SOCKET4677_AZIFS054P001C01   I9
  U2     BH20  VSS469  SOCKET4677_AZIFS054P001C01   I9
  U2     BH67  VSS472  SOCKET4677_AZIFS054P001C01   I9
  U2     BH73  VSS473  SOCKET4677_AZIFS054P001C01   I9
  U2     BH77  VSS474  SOCKET4677_AZIFS054P001C01   I9
  U2     BH81  VSS476  SOCKET4677_AZIFS054P001C01   I9
  U2     BH83  VSS477  SOCKET4677_AZIFS054P001C01   I9
  U2     BJ62  VSS479  SOCKET4677_AZIFS054P001C01   I9
  U2     BJ68  VSS480  SOCKET4677_AZIFS054P001C01   I9
  U2     BJ80  VSS481  SOCKET4677_AZIFS054P001C01   I9
  U2     BJ82  VSS482  SOCKET4677_AZIFS054P001C01   I9
  U2     BJ84  VSS483  SOCKET4677_AZIFS054P001C01   I9
  U2     BJ86  VSS484  SOCKET4677_AZIFS054P001C01   I9
  U2     BJ88  VSS485  SOCKET4677_AZIFS054P001C01   I9
  U2     BJ90  VSS486  SOCKET4677_AZIFS054P001C01   I9
  U2     BK4  VSS490  SOCKET4677_AZIFS054P001C01   I9
  U2     BK8  VSS496  SOCKET4677_AZIFS054P001C01   I9
  U2     BK12  VSS487  SOCKET4677_AZIFS054P001C01   I9
  U2     BK16  VSS488  SOCKET4677_AZIFS054P001C01   I9
  U2     BK20  VSS489  SOCKET4677_AZIFS054P001C01   I9
  U2     BK65  VSS491  SOCKET4677_AZIFS054P001C01   I9
  U2     BK71  VSS492  SOCKET4677_AZIFS054P001C01   I9
  U2     BK75  VSS494  SOCKET4677_AZIFS054P001C01   I9
  U2     BK79  VSS495  SOCKET4677_AZIFS054P001C01   I9
  U2     BL1  VSS497  SOCKET4677_AZIFS054P001C01   I9
  U2     BL5  VSS500  SOCKET4677_AZIFS054P001C01   I9
  U2     BL9  VSS505  SOCKET4677_AZIFS054P001C01   I9
  U2     BL13  VSS498  SOCKET4677_AZIFS054P001C01   I9
  U2     BL17  VSS499  SOCKET4677_AZIFS054P001C01   I9
  U2     BL68  VSS501  SOCKET4677_AZIFS054P001C01   I9
  U2     BL70  VSS502  SOCKET4677_AZIFS054P001C01   I9
  U2     BL72  VSS503  SOCKET4677_AZIFS054P001C01   I9
  U2     BL78  VSS504  SOCKET4677_AZIFS054P001C01   I9
  U2     BM4  VSS512  SOCKET4677_AZIFS054P001C01   I9
  U2     BM8  VSS517  SOCKET4677_AZIFS054P001C01   I9
  U2     BM12  VSS506  SOCKET4677_AZIFS054P001C01   I9
  U2     BM16  VSS507  SOCKET4677_AZIFS054P001C01   I9
  U2     BM20  VSS508  SOCKET4677_AZIFS054P001C01   I9
  U2     BM22  VSS509  SOCKET4677_AZIFS054P001C01   I9
  U2     BM24  VSS510  SOCKET4677_AZIFS054P001C01   I9
  U2     BM26  VSS511  SOCKET4677_AZIFS054P001C01   I9
  U2     BM61  VSS513  SOCKET4677_AZIFS054P001C01   I9
  U2     BM73  VSS515  SOCKET4677_AZIFS054P001C01   I9
  U2     BM77  VSS516  SOCKET4677_AZIFS054P001C01   I9
  U2     BN31  VSS518  SOCKET4677_AZIFS054P001C01   I9
  U2     BN62  VSS519  SOCKET4677_AZIFS054P001C01   I9
  U2     BN70  VSS520  SOCKET4677_AZIFS054P001C01   I9
  U2     BP2  VSS524  SOCKET4677_AZIFS054P001C01   I9
  U2     BP4  VSS527  SOCKET4677_AZIFS054P001C01   I9
  U2     BP8  VSS533  SOCKET4677_AZIFS054P001C01   I9
  U2     BP12  VSS522  SOCKET4677_AZIFS054P001C01   I9
  U2     BP16  VSS523  SOCKET4677_AZIFS054P001C01   I9
  U2     BP20  VSS525  SOCKET4677_AZIFS054P001C01   I9
  U2     BP63  VSS528  SOCKET4677_AZIFS054P001C01   I9
  U2     BP71  VSS529  SOCKET4677_AZIFS054P001C01   I9
  U2     BP73  VSS530  SOCKET4677_AZIFS054P001C01   I9
  U2     BP75  VSS531  SOCKET4677_AZIFS054P001C01   I9
  U2     BP77  VSS532  SOCKET4677_AZIFS054P001C01   I9
  U2     BR5   VSS0  SOCKET4677_AZIFS054P001C01   I9
  U2     BR9  VSS572  SOCKET4677_AZIFS054P001C01   I9
  U2     BR13  VSS535  SOCKET4677_AZIFS054P001C01   I9
  U2     BR17  VSS536  SOCKET4677_AZIFS054P001C01   I9
  U2     BR27  VSS538  SOCKET4677_AZIFS054P001C01   I9
  U2     BR29  VSS539  SOCKET4677_AZIFS054P001C01   I9
  U2     BR31  VSS540  SOCKET4677_AZIFS054P001C01   I9
  U2     BR33  VSS541  SOCKET4677_AZIFS054P001C01   I9
  U2     BR35  VSS542  SOCKET4677_AZIFS054P001C01  I12
  U2     BR37  VSS543  SOCKET4677_AZIFS054P001C01  I12
  U2     BR39  VSS545  SOCKET4677_AZIFS054P001C01  I12
  U2     BR41  VSS546  SOCKET4677_AZIFS054P001C01  I12
  U2     BR43  VSS547  SOCKET4677_AZIFS054P001C01  I12
  U2     BR45  VSS548  SOCKET4677_AZIFS054P001C01  I12
  U2     BR48  VSS549  SOCKET4677_AZIFS054P001C01  I12
  U2     BR50  VSS550  SOCKET4677_AZIFS054P001C01  I12
  U2     BR52  VSS551  SOCKET4677_AZIFS054P001C01  I12
  U2     BR54  VSS552  SOCKET4677_AZIFS054P001C01  I12
  U2     BR56  VSS555  SOCKET4677_AZIFS054P001C01  I12
  U2     BR58  VSS556  SOCKET4677_AZIFS054P001C01  I12
  U2     BR64  VSS557  SOCKET4677_AZIFS054P001C01  I12
  U2     BR66  VSS559  SOCKET4677_AZIFS054P001C01  I12
  U2     BR68  VSS560  SOCKET4677_AZIFS054P001C01  I12
  U2     BR70  VSS561  SOCKET4677_AZIFS054P001C01  I12
  U2     BR72  VSS563  SOCKET4677_AZIFS054P001C01  I12
  U2     BR74  VSS564  SOCKET4677_AZIFS054P001C01  I12
  U2     BR76  VSS565  SOCKET4677_AZIFS054P001C01  I12
  U2     BR80  VSS566  SOCKET4677_AZIFS054P001C01  I12
  U2     BR82  VSS567  SOCKET4677_AZIFS054P001C01  I12
  U2     BR84  VSS568  SOCKET4677_AZIFS054P001C01  I12
  U2     BR86  VSS569  SOCKET4677_AZIFS054P001C01  I12
  U2     BR88  VSS570  SOCKET4677_AZIFS054P001C01  I12
  U2     BR90  VSS573  SOCKET4677_AZIFS054P001C01  I12
  U2     BT4  VSS577  SOCKET4677_AZIFS054P001C01  I12
  U2     BT8  VSS578  SOCKET4677_AZIFS054P001C01  I12
  U2     BT12  VSS574  SOCKET4677_AZIFS054P001C01  I12
  U2     BT16  VSS575  SOCKET4677_AZIFS054P001C01  I12
  U2     BT20  VSS576  SOCKET4677_AZIFS054P001C01  I12
  U2     BU7  VSS586  SOCKET4677_AZIFS054P001C01  I12
  U2     BU15  VSS579  SOCKET4677_AZIFS054P001C01  I12
  U2     BU19  VSS580  SOCKET4677_AZIFS054P001C01  I12
  U2     BU21  VSS581  SOCKET4677_AZIFS054P001C01  I12
  U2     BU23  VSS582  SOCKET4677_AZIFS054P001C01  I12
  U2     BU25  VSS584  SOCKET4677_AZIFS054P001C01  I12
  U2     BU31  VSS585  SOCKET4677_AZIFS054P001C01  I12
  U2     BV2  VSS590  SOCKET4677_AZIFS054P001C01  I12
  U2     BV4  VSS592  SOCKET4677_AZIFS054P001C01  I12
  U2     BV6  VSS593  SOCKET4677_AZIFS054P001C01  I12
  U2     BV8  VSS594  SOCKET4677_AZIFS054P001C01  I12
  U2     BV12  VSS587  SOCKET4677_AZIFS054P001C01  I12
  U2     BV16  VSS588  SOCKET4677_AZIFS054P001C01  I12
  U2     BV18  VSS589  SOCKET4677_AZIFS054P001C01  I12
  U2     BV20  VSS591  SOCKET4677_AZIFS054P001C01  I12
  U2     BW3  VSS600  SOCKET4677_AZIFS054P001C01  I12
  U2     BW5  VSS602  SOCKET4677_AZIFS054P001C01  I12
  U2     BW9  VSS603  SOCKET4677_AZIFS054P001C01  I12
  U2     BW13  VSS596  SOCKET4677_AZIFS054P001C01  I12
  U2     BW17  VSS597  SOCKET4677_AZIFS054P001C01  I12
  U2     BW27  VSS598  SOCKET4677_AZIFS054P001C01  I12
  U2     BW29  VSS599  SOCKET4677_AZIFS054P001C01  I12
  U2     BW31  VSS601  SOCKET4677_AZIFS054P001C01  I12
  U2     BY4  VSS607  SOCKET4677_AZIFS054P001C01  I12
  U2     BY8  VSS608  SOCKET4677_AZIFS054P001C01  I12
  U2     BY12  VSS604  SOCKET4677_AZIFS054P001C01  I12
  U2     BY16  VSS605  SOCKET4677_AZIFS054P001C01  I12
  U2     BY20  VSS606  SOCKET4677_AZIFS054P001C01  I12
  U2      C5  VSS612  SOCKET4677_AZIFS054P001C01  I12
  U2     C39  VSS609  SOCKET4677_AZIFS054P001C01  I12
  U2     C45  VSS610  SOCKET4677_AZIFS054P001C01  I12
  U2     C52  VSS613  SOCKET4677_AZIFS054P001C01  I12
  U2     C72  VSS614  SOCKET4677_AZIFS054P001C01  I12
  U2     C74  VSS615  SOCKET4677_AZIFS054P001C01  I12
  U2     C78  VSS616  SOCKET4677_AZIFS054P001C01  I12
  U2     C80  VSS617  SOCKET4677_AZIFS054P001C01  I12
  U2     C82  VSS618  SOCKET4677_AZIFS054P001C01  I12
  U2     C86  VSS619  SOCKET4677_AZIFS054P001C01  I12
  U2     CA3  VSS620  SOCKET4677_AZIFS054P001C01  I12
  U2     CA31  VSS621  SOCKET4677_AZIFS054P001C01  I12
  U2     CB4  VSS633  SOCKET4677_AZIFS054P001C01  I12
  U2     CB8  VSS651  SOCKET4677_AZIFS054P001C01  I12
  U2     CB12  VSS622  SOCKET4677_AZIFS054P001C01  I12
  U2     CB16  VSS623  SOCKET4677_AZIFS054P001C01  I12
  U2     CB20  VSS624  SOCKET4677_AZIFS054P001C01  I12
  U2     CB22  VSS625  SOCKET4677_AZIFS054P001C01  I12
  U2     CB24  VSS626  SOCKET4677_AZIFS054P001C01  I12
  U2     CB26  VSS627  SOCKET4677_AZIFS054P001C01  I12
  U2     CB28  VSS628  SOCKET4677_AZIFS054P001C01  I12
  U2     CB32  VSS629  SOCKET4677_AZIFS054P001C01  I12
  U2     CB34  VSS630  SOCKET4677_AZIFS054P001C01  I12
  U2     CB36  VSS631  SOCKET4677_AZIFS054P001C01  I12
  U2     CB38  VSS632  SOCKET4677_AZIFS054P001C01  I12
  U2     CB40  VSS634  SOCKET4677_AZIFS054P001C01  I12
  U2     CB42  VSS635  SOCKET4677_AZIFS054P001C01  I12
  U2     CB44  VSS636  SOCKET4677_AZIFS054P001C01  I12
  U2     CB47  VSS637  SOCKET4677_AZIFS054P001C01  I12
  U2     CB49  VSS638  SOCKET4677_AZIFS054P001C01  I12
  U2     CB51  VSS639  SOCKET4677_AZIFS054P001C01  I12
  U2     CB53  VSS640  SOCKET4677_AZIFS054P001C01  I12
  U2     CB55  VSS641  SOCKET4677_AZIFS054P001C01  I12
  U2     CB57  VSS642  SOCKET4677_AZIFS054P001C01  I12
  U2     CB59  VSS643  SOCKET4677_AZIFS054P001C01  I12
  U2     CB63  VSS644  SOCKET4677_AZIFS054P001C01  I12
  U2     CB65  VSS645  SOCKET4677_AZIFS054P001C01  I12
  U2     CB67  VSS646  SOCKET4677_AZIFS054P001C01  I12
  U2     CB69  VSS647  SOCKET4677_AZIFS054P001C01  I12
  U2     CB71  VSS648  SOCKET4677_AZIFS054P001C01  I12
  U2     CB73  VSS649  SOCKET4677_AZIFS054P001C01  I12
  U2     CB79  VSS650  SOCKET4677_AZIFS054P001C01  I12
  U2     CB81  VSS652  SOCKET4677_AZIFS054P001C01  I12
  U2     CB83  VSS653  SOCKET4677_AZIFS054P001C01  I12
  U2     CB85  VSS654  SOCKET4677_AZIFS054P001C01  I12
  U2     CB87  VSS655  SOCKET4677_AZIFS054P001C01  I12
  U2     CB89  VSS656  SOCKET4677_AZIFS054P001C01  I12
  U2     CC5  VSS665  SOCKET4677_AZIFS054P001C01  I12
  U2     CC9  VSS670  SOCKET4677_AZIFS054P001C01  I12
  U2     CC13  VSS660  SOCKET4677_AZIFS054P001C01  I12
  U2     CC17  VSS661  SOCKET4677_AZIFS054P001C01  I12
  U2     CC31  VSS664  SOCKET4677_AZIFS054P001C01  I12
  U2     CC62  VSS666  SOCKET4677_AZIFS054P001C01  I12
  U2     CC70  VSS667  SOCKET4677_AZIFS054P001C01  I12
  U2     CC72  VSS668  SOCKET4677_AZIFS054P001C01  I12
  U2     CC74  VSS669  SOCKET4677_AZIFS054P001C01  I12
  U2     CD4  VSS674  SOCKET4677_AZIFS054P001C01  I12
  U2     CD8  VSS678  SOCKET4677_AZIFS054P001C01  I12
  U2     CD12  VSS671  SOCKET4677_AZIFS054P001C01  I12
  U2     CD16  VSS672  SOCKET4677_AZIFS054P001C01  I12
  U2     CD20  VSS673  SOCKET4677_AZIFS054P001C01  I12
  U2     CD61  VSS675  SOCKET4677_AZIFS054P001C01  I12
  U2     CD75  VSS676  SOCKET4677_AZIFS054P001C01  I12
  U2     CD77  VSS677  SOCKET4677_AZIFS054P001C01  I12
  U2     CE3  VSS680  SOCKET4677_AZIFS054P001C01  I12
  U2     CE60  VSS681  SOCKET4677_AZIFS054P001C01  I12
  U2     CE66  VSS682  SOCKET4677_AZIFS054P001C01  I12
  U2     CE72  VSS683  SOCKET4677_AZIFS054P001C01  I12
  U2     CE76  VSS684  SOCKET4677_AZIFS054P001C01  I12
  U2     CE78  VSS685  SOCKET4677_AZIFS054P001C01  I12
  U2     CF4  VSS689  SOCKET4677_AZIFS054P001C01  I12
  U2     CF8  VSS693  SOCKET4677_AZIFS054P001C01  I12
  U2     CF12  VSS686  SOCKET4677_AZIFS054P001C01  I12
  U2     CF16  VSS687  SOCKET4677_AZIFS054P001C01  I12
  U2     CF20  VSS688  SOCKET4677_AZIFS054P001C01  I12
  U2     CF69  VSS691  SOCKET4677_AZIFS054P001C01  I12
  U2     CF71  VSS692  SOCKET4677_AZIFS054P001C01  I12
  U2     CG1  VSS694  SOCKET4677_AZIFS054P001C01  I12
  U2     CG5  VSS703  SOCKET4677_AZIFS054P001C01  I12
  U2     CG9  VSS716  SOCKET4677_AZIFS054P001C01  I12
  U2     CG13  VSS695  SOCKET4677_AZIFS054P001C01  I12
  U2     CG17  VSS696  SOCKET4677_AZIFS054P001C01  I12
  U2     CG21  VSS697  SOCKET4677_AZIFS054P001C01  I12
  U2     CG23  VSS698  SOCKET4677_AZIFS054P001C01  I12
  U2     CG25  VSS701  SOCKET4677_AZIFS054P001C01  I12
  U2     CG62  VSS704  SOCKET4677_AZIFS054P001C01  I12
  U2     CG64  VSS706  SOCKET4677_AZIFS054P001C01  I12
  U2     CG70  VSS707  SOCKET4677_AZIFS054P001C01  I12
  U2     CG72  VSS708  SOCKET4677_AZIFS054P001C01  I12
  U2     CG74  VSS710  SOCKET4677_AZIFS054P001C01  I12
  U2     CG78  VSS713  SOCKET4677_AZIFS054P001C01  I12
  U2     CH4  VSS722  SOCKET4677_AZIFS054P001C01  I12
  U2     CH8  VSS730  SOCKET4677_AZIFS054P001C01  I12
  U2     CH12  VSS718  SOCKET4677_AZIFS054P001C01  I12
  U2     CH16  VSS720  SOCKET4677_AZIFS054P001C01  I12
  U2     CH20  VSS721  SOCKET4677_AZIFS054P001C01  I12
  U2     CH67  VSS727  SOCKET4677_AZIFS054P001C01  I12
  U2     CH73  VSS728  SOCKET4677_AZIFS054P001C01  I12
  U2     CH79  VSS729  SOCKET4677_AZIFS054P001C01  I12
  U2     CH83  VSS731  SOCKET4677_AZIFS054P001C01  I12
  U2     CH85  VSS732  SOCKET4677_AZIFS054P001C01  I12
  U2     CH87  VSS733  SOCKET4677_AZIFS054P001C01  I12
  U2     CH89  VSS734  SOCKET4677_AZIFS054P001C01  I12
  U2     CJ60  VSS736  SOCKET4677_AZIFS054P001C01  I12
  U2     CJ76  VSS383  SOCKET4677_AZIFS054P001C01  I12
  U2     CJ80  VSS737  SOCKET4677_AZIFS054P001C01  I12
  U2     CK4  VSS396  SOCKET4677_AZIFS054P001C01  I12
  U2     CK8  VSS746  SOCKET4677_AZIFS054P001C01  I12
  U2     CK12  VSS740  SOCKET4677_AZIFS054P001C01  I12
  U2     CK16  VSS741  SOCKET4677_AZIFS054P001C01  I12
  U2     CK20  VSS742  SOCKET4677_AZIFS054P001C01  I12
  U2     CK26  VSS743  SOCKET4677_AZIFS054P001C01  I12
  U2     CK63  VSS744  SOCKET4677_AZIFS054P001C01  I11
  U2     CK69  VSS745  SOCKET4677_AZIFS054P001C01  I11
  U2     CK81  VSS749  SOCKET4677_AZIFS054P001C01  I11
  U2     CL1  VSS750  SOCKET4677_AZIFS054P001C01  I11
  U2     CL5  VSS754  SOCKET4677_AZIFS054P001C01  I11
  U2     CL9  VSS760  SOCKET4677_AZIFS054P001C01  I11
  U2     CL13  VSS751  SOCKET4677_AZIFS054P001C01  I11
  U2     CL17  VSS752  SOCKET4677_AZIFS054P001C01  I11
  U2     CL62  VSS755  SOCKET4677_AZIFS054P001C01  I11
  U2     CL74  VSS756  SOCKET4677_AZIFS054P001C01  I11
  U2     CL78  VSS757  SOCKET4677_AZIFS054P001C01  I11
  U2     CL80  VSS758  SOCKET4677_AZIFS054P001C01  I11
  U2     CL82  VSS759  SOCKET4677_AZIFS054P001C01  I11
  U2     CM4  VSS764  SOCKET4677_AZIFS054P001C01  I11
  U2     CM8  VSS769  SOCKET4677_AZIFS054P001C01  I11
  U2     CM12  VSS761  SOCKET4677_AZIFS054P001C01  I11
  U2     CM16  VSS436  SOCKET4677_AZIFS054P001C01  I11
  U2     CM20  VSS762  SOCKET4677_AZIFS054P001C01  I11
  U2     CM22  VSS438  SOCKET4677_AZIFS054P001C01  I11
  U2     CM24  VSS763  SOCKET4677_AZIFS054P001C01  I11
  U2     CM61  VSS765  SOCKET4677_AZIFS054P001C01  I11
  U2     CM65  VSS766  SOCKET4677_AZIFS054P001C01  I11
  U2     CM67  VSS767  SOCKET4677_AZIFS054P001C01  I11
  U2     CM79  VSS768  SOCKET4677_AZIFS054P001C01  I11
  U2     CM81  VSS770  SOCKET4677_AZIFS054P001C01  I11
  U2     CM83  VSS771  SOCKET4677_AZIFS054P001C01  I11
  U2     CM85  VSS772  SOCKET4677_AZIFS054P001C01  I11
  U2     CN68  VSS773  SOCKET4677_AZIFS054P001C01  I11
  U2     CN70  VSS774  SOCKET4677_AZIFS054P001C01  I11
  U2     CN72  VSS775  SOCKET4677_AZIFS054P001C01  I11
  U2     CN74  VSS777  SOCKET4677_AZIFS054P001C01  I11
  U2     CN76  VSS471  SOCKET4677_AZIFS054P001C01  I11
  U2     CN84  VSS778  SOCKET4677_AZIFS054P001C01  I11
  U2     CN86  VSS779  SOCKET4677_AZIFS054P001C01  I11
  U2     CP4  VSS782  SOCKET4677_AZIFS054P001C01  I11
  U2     CP8  VSS785  SOCKET4677_AZIFS054P001C01  I11
  U2     CP12  VSS780  SOCKET4677_AZIFS054P001C01  I11
  U2     CP16  VSS478  SOCKET4677_AZIFS054P001C01  I11
  U2     CP18  VSS781  SOCKET4677_AZIFS054P001C01  I11
  U2     CP75  VSS783  SOCKET4677_AZIFS054P001C01  I11
  U2     CP77  VSS784  SOCKET4677_AZIFS054P001C01  I11
  U2     CP79  VSS493  SOCKET4677_AZIFS054P001C01  I11
  U2     CP83  VSS786  SOCKET4677_AZIFS054P001C01  I11
  U2     CP87  VSS787  SOCKET4677_AZIFS054P001C01  I11
  U2     CP91  VSS788  SOCKET4677_AZIFS054P001C01  I11
  U2     CR1  VSS789  SOCKET4677_AZIFS054P001C01  I11
  U2     CR5  VSS794  SOCKET4677_AZIFS054P001C01  I11
  U2     CR9  VSS801  SOCKET4677_AZIFS054P001C01  I11
  U2     CR11  VSS790  SOCKET4677_AZIFS054P001C01  I11
  U2     CR13  VSS792  SOCKET4677_AZIFS054P001C01  I11
  U2     CR17  VSS793  SOCKET4677_AZIFS054P001C01  I11
  U2     CR62  VSS795  SOCKET4677_AZIFS054P001C01  I11
  U2     CR64  VSS796  SOCKET4677_AZIFS054P001C01  I11
  U2     CR78  VSS514  SOCKET4677_AZIFS054P001C01  I11
  U2     CR84  VSS797  SOCKET4677_AZIFS054P001C01  I11
  U2     CR88  VSS800  SOCKET4677_AZIFS054P001C01  I11
  U2     CR90  VSS803  SOCKET4677_AZIFS054P001C01  I11
  U2     CT4  VSS526  SOCKET4677_AZIFS054P001C01  I11
  U2     CT8  VSS534  SOCKET4677_AZIFS054P001C01  I11
  U2     CT10  VSS804  SOCKET4677_AZIFS054P001C01  I11
  U2     CT12  VSS805  SOCKET4677_AZIFS054P001C01  I11
  U2     CT16  VSS521  SOCKET4677_AZIFS054P001C01  I11
  U2     CT69  VSS810  SOCKET4677_AZIFS054P001C01  I11
  U2     CT73  VSS811  SOCKET4677_AZIFS054P001C01  I11
  U2     CT81  VSS812  SOCKET4677_AZIFS054P001C01  I11
  U2     CT89  VSS537  SOCKET4677_AZIFS054P001C01  I11
  U2     CU19  VSS813  SOCKET4677_AZIFS054P001C01  I11
  U2     CU21  VSS814  SOCKET4677_AZIFS054P001C01  I11
  U2     CU23  VSS815  SOCKET4677_AZIFS054P001C01  I11
  U2     CU25  VSS544  SOCKET4677_AZIFS054P001C01  I11
  U2     CU60  VSS816  SOCKET4677_AZIFS054P001C01  I11
  U2     CU66  VSS818  SOCKET4677_AZIFS054P001C01  I11
  U2     CU68  VSS819  SOCKET4677_AZIFS054P001C01  I11
  U2     CU72  VSS553  SOCKET4677_AZIFS054P001C01  I11
  U2     CU78  VSS554  SOCKET4677_AZIFS054P001C01  I11
  U2     CU84  VSS822  SOCKET4677_AZIFS054P001C01  I11
  U2     CU88  VSS823  SOCKET4677_AZIFS054P001C01  I11
  U2     CV4  VSS825  SOCKET4677_AZIFS054P001C01  I11
  U2     CV8  VSS827  SOCKET4677_AZIFS054P001C01  I11
  U2     CV12  VSS824  SOCKET4677_AZIFS054P001C01  I11
  U2     CV16  VSS558  SOCKET4677_AZIFS054P001C01  I11
  U2     CV26  VSS562  SOCKET4677_AZIFS054P001C01  I11
  U2     CV75  VSS826  SOCKET4677_AZIFS054P001C01  I11
  U2     CV79  VSS571  SOCKET4677_AZIFS054P001C01  I11
  U2     CV83  VSS828  SOCKET4677_AZIFS054P001C01  I11
  U2     CV87  VSS831  SOCKET4677_AZIFS054P001C01  I11
  U2     CV91  VSS833  SOCKET4677_AZIFS054P001C01  I11
  U2     CW1  VSS834  SOCKET4677_AZIFS054P001C01  I11
  U2     CW5  VSS838  SOCKET4677_AZIFS054P001C01  I11
  U2     CW9  VSS850  SOCKET4677_AZIFS054P001C01  I11
  U2     CW13  VSS836  SOCKET4677_AZIFS054P001C01  I11
  U2     CW17  VSS837  SOCKET4677_AZIFS054P001C01  I11
  U2     CW33  VSS583  SOCKET4677_AZIFS054P001C01  I11
  U2     CW70  VSS595  SOCKET4677_AZIFS054P001C01  I11
  U2     CW72  VSS840  SOCKET4677_AZIFS054P001C01  I11
  U2     CW78  VSS843  SOCKET4677_AZIFS054P001C01  I11
  U2     CW84  VSS846  SOCKET4677_AZIFS054P001C01  I11
  U2     CW88  VSS848  SOCKET4677_AZIFS054P001C01  I11
  U2     CY4  VSS611  SOCKET4677_AZIFS054P001C01  I11
  U2     CY8  VSS860  SOCKET4677_AZIFS054P001C01  I11
  U2     CY12  VSS851  SOCKET4677_AZIFS054P001C01  I11
  U2     CY16  VSS852  SOCKET4677_AZIFS054P001C01  I11
  U2     CY18  VSS853  SOCKET4677_AZIFS054P001C01  I11
  U2     CY26  VSS854  SOCKET4677_AZIFS054P001C01  I11
  U2     CY30  VSS855  SOCKET4677_AZIFS054P001C01  I11
  U2     CY63  VSS856  SOCKET4677_AZIFS054P001C01  I11
  U2     CY73  VSS858  SOCKET4677_AZIFS054P001C01  I11
  U2     CY77  VSS859  SOCKET4677_AZIFS054P001C01  I11
  U2     CY81  VSS862  SOCKET4677_AZIFS054P001C01  I11
  U2     CY83  VSS863  SOCKET4677_AZIFS054P001C01  I11
  U2      D6  VSS899  SOCKET4677_AZIFS054P001C01  I12
  U2      D8  VSS663  SOCKET4677_AZIFS054P001C01  I12
  U2     D10  VSS864  SOCKET4677_AZIFS054P001C01  I12
  U2     D12  VSS865  SOCKET4677_AZIFS054P001C01  I12
  U2     D14  VSS866  SOCKET4677_AZIFS054P001C01  I12
  U2     D16  VSS868  SOCKET4677_AZIFS054P001C01  I12
  U2     D18  VSS869  SOCKET4677_AZIFS054P001C01  I12
  U2     D20  VSS871  SOCKET4677_AZIFS054P001C01  I12
  U2     D22  VSS873  SOCKET4677_AZIFS054P001C01  I12
  U2     D24  VSS874  SOCKET4677_AZIFS054P001C01  I12
  U2     D26  VSS875  SOCKET4677_AZIFS054P001C01  I12
  U2     D28  VSS876  SOCKET4677_AZIFS054P001C01  I12
  U2     D30  VSS877  SOCKET4677_AZIFS054P001C01  I12
  U2     D32  VSS878  SOCKET4677_AZIFS054P001C01  I12
  U2     D34  VSS879  SOCKET4677_AZIFS054P001C01  I12
  U2     D36  VSS881  SOCKET4677_AZIFS054P001C01  I12
  U2     D38  VSS884  SOCKET4677_AZIFS054P001C01  I12
  U2     D40  VSS885  SOCKET4677_AZIFS054P001C01  I12
  U2     D42  VSS886  SOCKET4677_AZIFS054P001C01  I12
  U2     D44  VSS888  SOCKET4677_AZIFS054P001C01  I12
  U2     D47  VSS889  SOCKET4677_AZIFS054P001C01  I12
  U2     D49  VSS891  SOCKET4677_AZIFS054P001C01  I12
  U2     D51  VSS892  SOCKET4677_AZIFS054P001C01  I12
  U2     D53  VSS895  SOCKET4677_AZIFS054P001C01  I12
  U2     D55  VSS896  SOCKET4677_AZIFS054P001C01  I12
  U2     D57  VSS897  SOCKET4677_AZIFS054P001C01  I12
  U2     D59  VSS898  SOCKET4677_AZIFS054P001C01  I12
  U2     D61  VSS900  SOCKET4677_AZIFS054P001C01  I12
  U2     D63  VSS657  SOCKET4677_AZIFS054P001C01  I12
  U2     D65  VSS658  SOCKET4677_AZIFS054P001C01  I12
  U2     D67  VSS659  SOCKET4677_AZIFS054P001C01  I12
  U2     D69  VSS901  SOCKET4677_AZIFS054P001C01  I12
  U2     D71  VSS902  SOCKET4677_AZIFS054P001C01  I12
  U2     D79  VSS662  SOCKET4677_AZIFS054P001C01  I12
  U2     D81  VSS906  SOCKET4677_AZIFS054P001C01  I12
  U2     D83  VSS907  SOCKET4677_AZIFS054P001C01  I12
  U2     DA19  VSS910  SOCKET4677_AZIFS054P001C01  I11
  U2     DA23  VSS911  SOCKET4677_AZIFS054P001C01  I11
  U2     DA25  VSS912  SOCKET4677_AZIFS054P001C01  I11
  U2     DA29  VSS913  SOCKET4677_AZIFS054P001C01  I11
  U2     DA31  VSS914  SOCKET4677_AZIFS054P001C01  I11
  U2     DA33  VSS915  SOCKET4677_AZIFS054P001C01  I11
  U2     DA35  VSS916  SOCKET4677_AZIFS054P001C01  I11
  U2     DA37  VSS917  SOCKET4677_AZIFS054P001C01  I11
  U2     DA41  VSS918  SOCKET4677_AZIFS054P001C01  I11
  U2     DA43  VSS679  SOCKET4677_AZIFS054P001C01  I11
  U2     DA48  VSS919  SOCKET4677_AZIFS054P001C01  I11
  U2     DA50  VSS920  SOCKET4677_AZIFS054P001C01  I11
  U2     DA54  VSS921  SOCKET4677_AZIFS054P001C01  I11
  U2     DA56  VSS922  SOCKET4677_AZIFS054P001C01  I11
  U2     DA58  VSS923  SOCKET4677_AZIFS054P001C01  I11
  U2     DA60  VSS924  SOCKET4677_AZIFS054P001C01  I11
  U2     DA62  VSS925  SOCKET4677_AZIFS054P001C01  I11
  U2     DA66  VSS926  SOCKET4677_AZIFS054P001C01  I11
  U2     DA68  VSS690  SOCKET4677_AZIFS054P001C01  I11
  U2     DA72  VSS927  SOCKET4677_AZIFS054P001C01  I11
  U2     DA74  VSS928  SOCKET4677_AZIFS054P001C01  I11
  U2     DA80  VSS929  SOCKET4677_AZIFS054P001C01  I11
  U2     DA82  VSS930  SOCKET4677_AZIFS054P001C01  I11
  U2     DA84  VSS931  SOCKET4677_AZIFS054P001C01  I11
  U2     DA88  VSS932  SOCKET4677_AZIFS054P001C01  I11
  U2     DB4  VSS939  SOCKET4677_AZIFS054P001C01  I11
  U2     DB8  VSS947  SOCKET4677_AZIFS054P001C01  I11
  U2     DB12  VSS933  SOCKET4677_AZIFS054P001C01  I11
  U2     DB16  VSS699  SOCKET4677_AZIFS054P001C01  I11
  U2     DB20  VSS700  SOCKET4677_AZIFS054P001C01  I11
  U2     DB22  VSS935  SOCKET4677_AZIFS054P001C01  I11
  U2     DB26  VSS702  SOCKET4677_AZIFS054P001C01  I11
  U2     DB28  VSS936  SOCKET4677_AZIFS054P001C01  I11
  U2     DB32  VSS937  SOCKET4677_AZIFS054P001C01  I11
  U2     DB34  VSS705  SOCKET4677_AZIFS054P001C01  I11
  U2     DB38  VSS938  SOCKET4677_AZIFS054P001C01  I11
  U2     DB40  VSS940  SOCKET4677_AZIFS054P001C01  I11
  U2     DB44  VSS709  SOCKET4677_AZIFS054P001C01  I11
  U2     DB47  VSS941  SOCKET4677_AZIFS054P001C01  I11
  U2     DB51  VSS711  SOCKET4677_AZIFS054P001C01  I11
  U2     DB53  VSS712  SOCKET4677_AZIFS054P001C01  I11
  U2     DB57  VSS942  SOCKET4677_AZIFS054P001C01  I11
  U2     DB59  VSS714  SOCKET4677_AZIFS054P001C01  I11
  U2     DB63  VSS715  SOCKET4677_AZIFS054P001C01  I11
  U2     DB65  VSS943  SOCKET4677_AZIFS054P001C01  I11
  U2     DB69  VSS717  SOCKET4677_AZIFS054P001C01  I11
  U2     DB71  VSS944  SOCKET4677_AZIFS054P001C01  I11
  U2     DB75  VSS719  SOCKET4677_AZIFS054P001C01  I11
  U2     DB77  VSS946  SOCKET4677_AZIFS054P001C01  I11
  U2     DB87  VSS948  SOCKET4677_AZIFS054P001C01  I11
  U2     DB91  VSS723  SOCKET4677_AZIFS054P001C01  I10
  U2     DC1  VSS724  SOCKET4677_AZIFS054P001C01  I10
  U2     DC5  VSS953  SOCKET4677_AZIFS054P001C01  I10
  U2     DC9  VSS963  SOCKET4677_AZIFS054P001C01  I10
  U2     DC13  VSS725  SOCKET4677_AZIFS054P001C01  I10
  U2     DC21  VSS726  SOCKET4677_AZIFS054P001C01  I10
  U2     DC27  VSS949  SOCKET4677_AZIFS054P001C01  I10
  U2     DC33  VSS950  SOCKET4677_AZIFS054P001C01  I10
  U2     DC39  VSS951  SOCKET4677_AZIFS054P001C01  I10
  U2     DC45  VSS952  SOCKET4677_AZIFS054P001C01  I10
  U2     DC52  VSS735  SOCKET4677_AZIFS054P001C01  I10
  U2     DC58  VSS738  SOCKET4677_AZIFS054P001C01  I10
  U2     DC64  VSS739  SOCKET4677_AZIFS054P001C01  I10
  U2     DC70  VSS954  SOCKET4677_AZIFS054P001C01  I10
  U2     DC76  VSS956  SOCKET4677_AZIFS054P001C01  I10
  U2     DC78  VSS958  SOCKET4677_AZIFS054P001C01  I10
  U2     DC80  VSS960  SOCKET4677_AZIFS054P001C01  I10
  U2     DC84  VSS961  SOCKET4677_AZIFS054P001C01  I10
  U2     DC88  VSS962  SOCKET4677_AZIFS054P001C01  I10
  U2     DD4  VSS964  SOCKET4677_AZIFS054P001C01  I10
  U2     DD8  VSS967  SOCKET4677_AZIFS054P001C01  I10
  U2     DD12  VSS747  SOCKET4677_AZIFS054P001C01  I10
  U2     DD16  VSS748  SOCKET4677_AZIFS054P001C01  I10
  U2     DD49  VSS753  SOCKET4677_AZIFS054P001C01  I10
  U2     DD79  VSS965  SOCKET4677_AZIFS054P001C01  I10
  U2     DE17  VSS970  SOCKET4677_AZIFS054P001C01  I10
  U2     DE19  VSS971  SOCKET4677_AZIFS054P001C01  I10
  U2     DE21  VSS972  SOCKET4677_AZIFS054P001C01  I10
  U2     DE23  VSS974  SOCKET4677_AZIFS054P001C01  I10
  U2     DE25  VSS975  SOCKET4677_AZIFS054P001C01  I10
  U2     DE27  VSS977  SOCKET4677_AZIFS054P001C01  I10
  U2     DE29  VSS978  SOCKET4677_AZIFS054P001C01  I10
  U2     DE31  VSS981  SOCKET4677_AZIFS054P001C01  I10
  U2     DE33  VSS982  SOCKET4677_AZIFS054P001C01  I10
  U2     DE35  VSS983  SOCKET4677_AZIFS054P001C01  I10
  U2     DE37  VSS984  SOCKET4677_AZIFS054P001C01  I10
  U2     DE39  VSS776  SOCKET4677_AZIFS054P001C01  I10
  U2     DE41  VSS986  SOCKET4677_AZIFS054P001C01  I10
  U2     DE43  VSS987  SOCKET4677_AZIFS054P001C01  I10
  U2     DE45  VSS988  SOCKET4677_AZIFS054P001C01  I10
  U2     DE48  VSS989  SOCKET4677_AZIFS054P001C01  I10
  U2     DE50  VSS991  SOCKET4677_AZIFS054P001C01  I10
  U2     DE52  VSS992  SOCKET4677_AZIFS054P001C01  I10
  U2     DE54  VSS994  SOCKET4677_AZIFS054P001C01  I10
  U2     DE56  VSS995  SOCKET4677_AZIFS054P001C01  I10
  U2     DE58  VSS996  SOCKET4677_AZIFS054P001C01  I10
  U2     DE60  VSS997  SOCKET4677_AZIFS054P001C01  I10
  U2     DE62  VSS999  SOCKET4677_AZIFS054P001C01  I10
  U2     DE64  VSS1001  SOCKET4677_AZIFS054P001C01  I10
  U2     DE66  VSS1004  SOCKET4677_AZIFS054P001C01  I10
  U2     DE68  VSS1007  SOCKET4677_AZIFS054P001C01  I10
  U2     DE70  VSS791  SOCKET4677_AZIFS054P001C01  I10
  U2     DE72  VSS1008  SOCKET4677_AZIFS054P001C01  I10
  U2     DE74  VSS1009  SOCKET4677_AZIFS054P001C01  I10
  U2     DE76  VSS1010  SOCKET4677_AZIFS054P001C01  I10
  U2     DE82  VSS1011  SOCKET4677_AZIFS054P001C01  I10
  U2     DE84  VSS1012  SOCKET4677_AZIFS054P001C01  I10
  U2     DE88  VSS1015  SOCKET4677_AZIFS054P001C01  I10
  U2     DF4  VSS1017  SOCKET4677_AZIFS054P001C01  I10
  U2     DF8  VSS1019  SOCKET4677_AZIFS054P001C01  I10
  U2     DF12  VSS798  SOCKET4677_AZIFS054P001C01  I10
  U2     DF16  VSS799  SOCKET4677_AZIFS054P001C01  I10
  U2     DF49  VSS802  SOCKET4677_AZIFS054P001C01  I10
  U2     DF79  VSS1018  SOCKET4677_AZIFS054P001C01  I10
  U2     DF87  VSS1020  SOCKET4677_AZIFS054P001C01  I10
  U2     DF91  VSS806  SOCKET4677_AZIFS054P001C01  I10
  U2     DG1  VSS807  SOCKET4677_AZIFS054P001C01  I10
  U2     DG5  VSS1031  SOCKET4677_AZIFS054P001C01  I10
  U2     DG9  VSS1038  SOCKET4677_AZIFS054P001C01  I10
  U2     DG13  VSS808  SOCKET4677_AZIFS054P001C01  I10
  U2     DG21  VSS809  SOCKET4677_AZIFS054P001C01  I10
  U2     DG27  VSS1022  SOCKET4677_AZIFS054P001C01  I10
  U2     DG33  VSS1024  SOCKET4677_AZIFS054P001C01  I10
  U2     DG39  VSS1027  SOCKET4677_AZIFS054P001C01  I10
  U2     DG45  VSS1030  SOCKET4677_AZIFS054P001C01  I10
  U2     DG52  VSS817  SOCKET4677_AZIFS054P001C01  I10
  U2     DG58  VSS820  SOCKET4677_AZIFS054P001C01  I10
  U2     DG64  VSS821  SOCKET4677_AZIFS054P001C01  I10
  U2     DG70  VSS1032  SOCKET4677_AZIFS054P001C01  I10
  U2     DG76  VSS1033  SOCKET4677_AZIFS054P001C01  I10
  U2     DG80  VSS1034  SOCKET4677_AZIFS054P001C01  I10
  U2     DG84  VSS1035  SOCKET4677_AZIFS054P001C01  I10
  U2     DG88  VSS1037  SOCKET4677_AZIFS054P001C01  I10
  U2     DH4  VSS1044  SOCKET4677_AZIFS054P001C01  I10
  U2     DH8  VSS1057  SOCKET4677_AZIFS054P001C01  I10
  U2     DH12  VSS1039  SOCKET4677_AZIFS054P001C01  I10
  U2     DH16  VSS829  SOCKET4677_AZIFS054P001C01  I10
  U2     DH20  VSS830  SOCKET4677_AZIFS054P001C01  I10
  U2     DH22  VSS1040  SOCKET4677_AZIFS054P001C01  I10
  U2     DH26  VSS832  SOCKET4677_AZIFS054P001C01  I10
  U2     DH28  VSS1041  SOCKET4677_AZIFS054P001C01  I10
  U2     DH32  VSS1042  SOCKET4677_AZIFS054P001C01  I10
  U2     DH34  VSS835  SOCKET4677_AZIFS054P001C01  I10
  U2     DH38  VSS1043  SOCKET4677_AZIFS054P001C01  I10
  U2     DH40  VSS1045  SOCKET4677_AZIFS054P001C01  I10
  U2     DH44  VSS839  SOCKET4677_AZIFS054P001C01  I10
  U2     DH47  VSS1046  SOCKET4677_AZIFS054P001C01  I10
  U2     DH51  VSS841  SOCKET4677_AZIFS054P001C01  I10
  U2     DH53  VSS842  SOCKET4677_AZIFS054P001C01  I10
  U2     DH57  VSS1049  SOCKET4677_AZIFS054P001C01  I10
  U2     DH59  VSS844  SOCKET4677_AZIFS054P001C01  I10
  U2     DH63  VSS845  SOCKET4677_AZIFS054P001C01  I10
  U2     DH65  VSS1053  SOCKET4677_AZIFS054P001C01  I10
  U2     DH69  VSS847  SOCKET4677_AZIFS054P001C01  I10
  U2     DH71  VSS1055  SOCKET4677_AZIFS054P001C01  I10
  U2     DH75  VSS849  SOCKET4677_AZIFS054P001C01  I10
  U2     DH77  VSS1056  SOCKET4677_AZIFS054P001C01  I10
  U2     DH85  VSS1058  SOCKET4677_AZIFS054P001C01  I10
  U2     DJ19  VSS1061  SOCKET4677_AZIFS054P001C01  I10
  U2     DJ23  VSS1062  SOCKET4677_AZIFS054P001C01  I10
  U2     DJ25  VSS857  SOCKET4677_AZIFS054P001C01  I10
  U2     DJ29  VSS1065  SOCKET4677_AZIFS054P001C01  I10
  U2     DJ31  VSS1066  SOCKET4677_AZIFS054P001C01  I10
  U2     DJ35  VSS861  SOCKET4677_AZIFS054P001C01  I10
  U2     DJ37  VSS1067  SOCKET4677_AZIFS054P001C01  I10
  U2     DJ41  VSS1068  SOCKET4677_AZIFS054P001C01  I10
  U2     DJ43  VSS1069  SOCKET4677_AZIFS054P001C01  I10
  U2     DJ48  VSS1070  SOCKET4677_AZIFS054P001C01  I10
  U2     DJ50  VSS1071  SOCKET4677_AZIFS054P001C01  I10
  U2     DJ54  VSS867  SOCKET4677_AZIFS054P001C01  I10
  U2     DJ56  VSS1072  SOCKET4677_AZIFS054P001C01  I10
  U2     DJ60  VSS1073  SOCKET4677_AZIFS054P001C01  I10
  U2     DJ62  VSS870  SOCKET4677_AZIFS054P001C01  I10
  U2     DJ66  VSS1074  SOCKET4677_AZIFS054P001C01  I10
  U2     DJ68  VSS872  SOCKET4677_AZIFS054P001C01  I10
  U2     DJ72  VSS1075  SOCKET4677_AZIFS054P001C01  I10
  U2     DJ74  VSS1076  SOCKET4677_AZIFS054P001C01  I10
  U2     DJ80  VSS1078  SOCKET4677_AZIFS054P001C01  I10
  U2     DJ82  VSS1079  SOCKET4677_AZIFS054P001C01  I10
  U2     DJ84  VSS1080  SOCKET4677_AZIFS054P001C01  I10
  U2     DJ88  VSS1081  SOCKET4677_AZIFS054P001C01  I10
  U2     DK4  VSS1085  SOCKET4677_AZIFS054P001C01  I10
  U2     DK8  VSS1090  SOCKET4677_AZIFS054P001C01  I10
  U2     DK12  VSS880  SOCKET4677_AZIFS054P001C01  I10
  U2     DK16  VSS1082  SOCKET4677_AZIFS054P001C01  I10
  U2     DK18  VSS882  SOCKET4677_AZIFS054P001C01  I10
  U2     DK24  VSS883  SOCKET4677_AZIFS054P001C01  I10
  U2     DK30  VSS1083  SOCKET4677_AZIFS054P001C01  I10
  U2     DK36  VSS1084  SOCKET4677_AZIFS054P001C01  I10
  U2     DK42  VSS887  SOCKET4677_AZIFS054P001C01  I10
  U2     DK49  VSS1086  SOCKET4677_AZIFS054P001C01  I10
  U2     DK55  VSS890  SOCKET4677_AZIFS054P001C01  I10
  U2     DK61  VSS893  SOCKET4677_AZIFS054P001C01  I10
  U2     DK67  VSS894  SOCKET4677_AZIFS054P001C01  I10
  U2     DK73  VSS1087  SOCKET4677_AZIFS054P001C01  I10
  U2     DK77  VSS1088  SOCKET4677_AZIFS054P001C01  I10
  U2     DK79  VSS1089  SOCKET4677_AZIFS054P001C01  I10
  U2     DK81  VSS1091  SOCKET4677_AZIFS054P001C01  I10
  U2     DK83  VSS1092  SOCKET4677_AZIFS054P001C01  I10
  U2     DK87  VSS1093  SOCKET4677_AZIFS054P001C01  I10
  U2     DK91  VSS1094  SOCKET4677_AZIFS054P001C01  I10
  U2     DL1  VSS903  SOCKET4677_AZIFS054P001C01  I10
  U2     DL5  VSS908  SOCKET4677_AZIFS054P001C01  I10
  U2     DL9  VSS1099  SOCKET4677_AZIFS054P001C01  I10
  U2     DL13  VSS904  SOCKET4677_AZIFS054P001C01  I10
  U2     DL17  VSS905  SOCKET4677_AZIFS054P001C01  I10
  U2     DL39  VSS1095  SOCKET4677_AZIFS054P001C01  I10
  U2     DL52  VSS909  SOCKET4677_AZIFS054P001C01  I10
  U2     DL84  VSS1096  SOCKET4677_AZIFS054P001C01  I10
  U2     DL88  VSS1098  SOCKET4677_AZIFS054P001C01  I10
  U2     DM4  VSS1117  SOCKET4677_AZIFS054P001C01  I10
  U2     DM8  VSS1140  SOCKET4677_AZIFS054P001C01  I10
  U2     DM12  VSS1100  SOCKET4677_AZIFS054P001C01  I10
  U2     DM16  VSS1101  SOCKET4677_AZIFS054P001C01  I10
  U2     DM18  VSS1102  SOCKET4677_AZIFS054P001C01  I10
  U2     DM20  VSS1103  SOCKET4677_AZIFS054P001C01  I10
  U2     DM22  VSS1104  SOCKET4677_AZIFS054P001C01  I10
  U2     DM24  VSS1105  SOCKET4677_AZIFS054P001C01  I10
  U2     DM26  VSS1106  SOCKET4677_AZIFS054P001C01  I10
  U2     DM28  VSS1107  SOCKET4677_AZIFS054P001C01  I10
  U2     DM30  VSS1108  SOCKET4677_AZIFS054P001C01  I10
  U2     DM32  VSS1109  SOCKET4677_AZIFS054P001C01  I10
  U2     DM34  VSS1110  SOCKET4677_AZIFS054P001C01  I10
  U2     DM36  VSS1113  SOCKET4677_AZIFS054P001C01  I10
  U2     DM38  VSS1114  SOCKET4677_AZIFS054P001C01  I10
  U2     DM40  VSS1118  SOCKET4677_AZIFS054P001C01  I10
  U2     DM42  VSS1119  SOCKET4677_AZIFS054P001C01  I10
  U2     DM44  VSS1120  SOCKET4677_AZIFS054P001C01  I10
  U2     DM47  VSS1121  SOCKET4677_AZIFS054P001C01  I10
  U2     DM49  VSS1122  SOCKET4677_AZIFS054P001C01  I10
  U2     DM51  VSS934  SOCKET4677_AZIFS054P001C01  I10
  U2     DM53  VSS1123  SOCKET4677_AZIFS054P001C01  I10
  U2     DM55  VSS1124  SOCKET4677_AZIFS054P001C01  I10
  U2     DM57  VSS1127  SOCKET4677_AZIFS054P001C01  I10
  U2     DM59  VSS1128  SOCKET4677_AZIFS054P001C01  I10
  U2     DM61  VSS1130  SOCKET4677_AZIFS054P001C01  I10
  U2     DM63  VSS1132  SOCKET4677_AZIFS054P001C01  I10
  U2     DM65  VSS1133  SOCKET4677_AZIFS054P001C01  I10
  U2     DM67  VSS1134  SOCKET4677_AZIFS054P001C01  I10
  U2     DM69  VSS1135  SOCKET4677_AZIFS054P001C01  I10
  U2     DM71  VSS1136  SOCKET4677_AZIFS054P001C01  I10
  U2     DM73  VSS945  SOCKET4677_AZIFS054P001C01  I10
  U2     DM75  VSS1137  SOCKET4677_AZIFS054P001C01  I10
  U2     DM77  VSS1138  SOCKET4677_AZIFS054P001C01  I10
  U2     DM79  VSS1139  SOCKET4677_AZIFS054P001C01  I10
  U2     DN17  VSS955  SOCKET4677_AZIFS054P001C01  I10
  U2     DN39  VSS957  SOCKET4677_AZIFS054P001C01  I10
  U2     DN52  VSS959  SOCKET4677_AZIFS054P001C01  I10
  U2     DN78  VSS1143  SOCKET4677_AZIFS054P001C01  I10
  U2     DN84  VSS1147  SOCKET4677_AZIFS054P001C01  I10
  U2     DN88  VSS1148  SOCKET4677_AZIFS054P001C01  I10
  U2     DP4  VSS1152  SOCKET4677_AZIFS054P001C01  I10
  U2     DP8  VSS1157  SOCKET4677_AZIFS054P001C01  I10
  U2     DP12  VSS966  SOCKET4677_AZIFS054P001C01  I10
  U2     DP16  VSS1149  SOCKET4677_AZIFS054P001C01  I10
  U2     DP18  VSS968  SOCKET4677_AZIFS054P001C01  I10
  U2     DP24  VSS969  SOCKET4677_AZIFS054P001C01  I10
  U2     DP30  VSS1150  SOCKET4677_AZIFS054P001C01  I10
  U2     DP36  VSS1151  SOCKET4677_AZIFS054P001C01  I10
  U2     DP42  VSS973  SOCKET4677_AZIFS054P001C01  I10
  U2     DP49  VSS1153  SOCKET4677_AZIFS054P001C01  I10
  U2     DP55  VSS976  SOCKET4677_AZIFS054P001C01  I10
  U2     DP61  VSS979  SOCKET4677_AZIFS054P001C01  I10
  U2     DP67  VSS980  SOCKET4677_AZIFS054P001C01  I10
  U2     DP73  VSS1154  SOCKET4677_AZIFS054P001C01  I10
  U2     DP81  VSS1159  SOCKET4677_AZIFS054P001C01  I10
  U2     DP87  VSS1160  SOCKET4677_AZIFS054P001C01  I10
  U2     DP91  VSS985  SOCKET4677_AZIFS054P001C01  I10
  U2     DR1  VSS1162  SOCKET4677_AZIFS054P001C01  I10
  U2     DR5  VSS998  SOCKET4677_AZIFS054P001C01  I10
  U2     DR9  VSS1187  SOCKET4677_AZIFS054P001C01  I10
  U2     DR13  VSS1164  SOCKET4677_AZIFS054P001C01  I10
  U2     DR19  VSS1166  SOCKET4677_AZIFS054P001C01  I10
  U2     DR23  VSS1169  SOCKET4677_AZIFS054P001C01  I10
  U2     DR25  VSS990  SOCKET4677_AZIFS054P001C01  I10
  U2     DR29  VSS1172  SOCKET4677_AZIFS054P001C01  I10
  U2     DR31  VSS1173  SOCKET4677_AZIFS054P001C01  I10
  U2     DR35  VSS993  SOCKET4677_AZIFS054P001C01  I10
  U2     DR37  VSS1174  SOCKET4677_AZIFS054P001C01  I10
  U2     DR41  VSS1175  SOCKET4677_AZIFS054P001C01  I10
  U2     DR43  VSS1176  SOCKET4677_AZIFS054P001C01  I10
  U2     DR48  VSS1177  SOCKET4677_AZIFS054P001C01  I10
  U2     DR50  VSS1178  SOCKET4677_AZIFS054P001C01  I10
  U2     DR54  VSS1000  SOCKET4677_AZIFS054P001C01  I10
  U2     DR56  VSS1179  SOCKET4677_AZIFS054P001C01  I10
  U2     DR60  VSS1002  SOCKET4677_AZIFS054P001C01  I10
  U2     DR62  VSS1003  SOCKET4677_AZIFS054P001C01  I10
  U2     DR66  VSS1181  SOCKET4677_AZIFS054P001C01  I10
  U2     DR68  VSS1005  SOCKET4677_AZIFS054P001C01  I10
  U2     DR72  VSS1006  SOCKET4677_AZIFS054P001C01  I10
  U2     DR74  VSS1182  SOCKET4677_AZIFS054P001C01  I10
  U2     DR78  VSS1183  SOCKET4677_AZIFS054P001C01  I10
  U2     DR84  VSS1184  SOCKET4677_AZIFS054P001C01  I10
  U2     DR88  VSS1186  SOCKET4677_AZIFS054P001C01  I10
  U2     DT4  VSS1021  SOCKET4677_AZIFS054P001C01  I10
  U2     DT8  VSS1207  SOCKET4677_AZIFS054P001C01  I10
  U2     DT12  VSS1189  SOCKET4677_AZIFS054P001C01  I10
  U2     DT16  VSS1013  SOCKET4677_AZIFS054P001C01  I10
  U2     DT20  VSS1014  SOCKET4677_AZIFS054P001C01  I10
  U2     DT22  VSS1190  SOCKET4677_AZIFS054P001C01  I10
  U2     DT26  VSS1016  SOCKET4677_AZIFS054P001C01  I10
  U2     DT28  VSS1191  SOCKET4677_AZIFS054P001C01  I10
  U2     DT32  VSS1192  SOCKET4677_AZIFS054P001C01  I10
  U2     DT34  VSS1194  SOCKET4677_AZIFS054P001C01  I10
  U2     DT38  VSS1196  SOCKET4677_AZIFS054P001C01  I10
  U2     DT40  VSS1199  SOCKET4677_AZIFS054P001C01  I10
  U2     DT44  VSS1023  SOCKET4677_AZIFS054P001C01  I10
  U2     DT47  VSS1201  SOCKET4677_AZIFS054P001C01  I10
  U2     DT51  VSS1025  SOCKET4677_AZIFS054P001C01  I10
  U2     DT53  VSS1026  SOCKET4677_AZIFS054P001C01  I10
  U2     DT57  VSS1202  SOCKET4677_AZIFS054P001C01  I10
  U2     DT59  VSS1028  SOCKET4677_AZIFS054P001C01  I10
  U2     DT63  VSS1029  SOCKET4677_AZIFS054P001C01  I10
  U2     DT65  VSS1203  SOCKET4677_AZIFS054P001C01  I10
  U2     DT69  VSS1204  SOCKET4677_AZIFS054P001C01  I10
  U2     DT71  VSS1205  SOCKET4677_AZIFS054P001C01  I10
  U2     DT75  VSS1206  SOCKET4677_AZIFS054P001C01  I10
  U2     DT83  VSS1036  SOCKET4677_AZIFS054P001C01  I10
  U2     DU21  VSS1209  SOCKET4677_AZIFS054P001C01  I10
  U2     DU27  VSS1211  SOCKET4677_AZIFS054P001C01  I10
  U2     DU33  VSS1212  SOCKET4677_AZIFS054P001C01  I10
  U2     DU39  VSS1047  SOCKET4677_AZIFS054P001C01  I10
  U2     DU45  VSS1048  SOCKET4677_AZIFS054P001C01  I10
  U2     DU52  VSS1050  SOCKET4677_AZIFS054P001C01  I10
  U2     DU58  VSS1051  SOCKET4677_AZIFS054P001C01  I10
  U2     DU64  VSS1052  SOCKET4677_AZIFS054P001C01  I10
  U2     DU70  VSS1054  SOCKET4677_AZIFS054P001C01  I10
  U2     DU76  VSS1213  SOCKET4677_AZIFS054P001C01  I10
  U2     DU78  VSS1214  SOCKET4677_AZIFS054P001C01  I10
  U2     DU84  VSS1215  SOCKET4677_AZIFS054P001C01  I10
  U2     DU88  VSS1216  SOCKET4677_AZIFS054P001C01  I10
  U2     DV4  VSS1063  SOCKET4677_AZIFS054P001C01  I10
  U2     DV8  VSS1221  SOCKET4677_AZIFS054P001C01  I10
  U2     DV12  VSS1059  SOCKET4677_AZIFS054P001C01  I10
  U2     DV16  VSS1060  SOCKET4677_AZIFS054P001C01  I10
  U2     DV42  VSS1064  SOCKET4677_AZIFS054P001C01  I10
  U2     DV77  VSS1218  SOCKET4677_AZIFS054P001C01  I10
  U2     DV79  VSS1219  SOCKET4677_AZIFS054P001C01  I10
  U2     DV81  VSS1222  SOCKET4677_AZIFS054P001C01  I10
  U2     DV83  VSS1226  SOCKET4677_AZIFS054P001C01  I10
  U2     DV87  VSS1227  SOCKET4677_AZIFS054P001C01  I10
  U2     DV91  VSS1228  SOCKET4677_AZIFS054P001C01  I10
  U2     DW1  VSS1229  SOCKET4677_AZIFS054P001C01  I10
  U2     DW5  VSS1249  SOCKET4677_AZIFS054P001C01  I10
  U2     DW9  VSS1268  SOCKET4677_AZIFS054P001C01  I10
  U2     DW13  VSS1230  SOCKET4677_AZIFS054P001C01  I10
  U2     DW17  VSS1231  SOCKET4677_AZIFS054P001C01  I10
  U2     DW19  VSS1233  SOCKET4677_AZIFS054P001C01  I10
  U2     DW21  VSS1077  SOCKET4677_AZIFS054P001C01  I10
  U2     DW23  VSS1234  SOCKET4677_AZIFS054P001C01  I10
  U2     DW25  VSS1236  SOCKET4677_AZIFS054P001C01  I10
  U2     DW27  VSS1238  SOCKET4677_AZIFS054P001C01  I10
  U2     DW29  VSS1239  SOCKET4677_AZIFS054P001C01  I10
  U2     DW31  VSS1240  SOCKET4677_AZIFS054P001C01  I10
  U2     DW33  VSS1241  SOCKET4677_AZIFS054P001C01  I10
  U2     DW35  VSS1242  SOCKET4677_AZIFS054P001C01  I10
  U2     DW37  VSS1243  SOCKET4677_AZIFS054P001C01  I10
  U2     DW39  VSS1244  SOCKET4677_AZIFS054P001C01  I10
  U2     DW41  VSS1245  SOCKET4677_AZIFS054P001C01  I10
  U2     DW43  VSS1246  SOCKET4677_AZIFS054P001C01  I10
  U2     DW45  VSS1247  SOCKET4677_AZIFS054P001C01  I10
  U2     DW48  VSS1248  SOCKET4677_AZIFS054P001C01  I10
  U2     DW50  VSS1250  SOCKET4677_AZIFS054P001C01  I10
  U2     DW52  VSS1251  SOCKET4677_AZIFS054P001C01  I10
  U2     DW54  VSS1252  SOCKET4677_AZIFS054P001C01  I10
  U2     DW56  VSS1253  SOCKET4677_AZIFS054P001C01  I10
  U2     DW58  VSS1254  SOCKET4677_AZIFS054P001C01  I10
  U2     DW60  VSS1097  SOCKET4677_AZIFS054P001C01  I10
  U2     DW62  VSS1255  SOCKET4677_AZIFS054P001C01  I10
  U2     DW64  VSS1256  SOCKET4677_AZIFS054P001C01  I10
  U2     DW66  VSS1257  SOCKET4677_AZIFS054P001C01   I9
  U2     DW68  VSS1258  SOCKET4677_AZIFS054P001C01   I9
  U2     DW70  VSS1259  SOCKET4677_AZIFS054P001C01   I9
  U2     DW72  VSS1260  SOCKET4677_AZIFS054P001C01   I9
  U2     DW74  VSS1261  SOCKET4677_AZIFS054P001C01   I9
  U2     DW76  VSS1262  SOCKET4677_AZIFS054P001C01   I9
  U2     DW80  VSS1263  SOCKET4677_AZIFS054P001C01   I9
  U2     DW82  VSS1264  SOCKET4677_AZIFS054P001C01   I9
  U2     DW84  VSS1266  SOCKET4677_AZIFS054P001C01   I9
  U2     DW88  VSS1267  SOCKET4677_AZIFS054P001C01   I9
  U2     DY4  VSS1115  SOCKET4677_AZIFS054P001C01   I9
  U2     DY8  VSS1270  SOCKET4677_AZIFS054P001C01   I9
  U2     DY12  VSS1111  SOCKET4677_AZIFS054P001C01   I9
  U2     DY16  VSS1112  SOCKET4677_AZIFS054P001C01   I9
  U2     DY42  VSS1116  SOCKET4677_AZIFS054P001C01   I9
  U2     DY77  VSS1269  SOCKET4677_AZIFS054P001C01   I9
  U2      E5  VSS1125  SOCKET4677_AZIFS054P001C01  I12
  U2     E39  VSS1271  SOCKET4677_AZIFS054P001C01  I12
  U2     E52  VSS1126  SOCKET4677_AZIFS054P001C01  I11
  U2     E74  VSS1129  SOCKET4677_AZIFS054P001C01  I11
  U2     E76  VSS1272  SOCKET4677_AZIFS054P001C01  I11
  U2     E78  VSS1131  SOCKET4677_AZIFS054P001C01  I11
  U2     E86  VSS1273  SOCKET4677_AZIFS054P001C01  I11
  U2     EA21  VSS1274  SOCKET4677_AZIFS054P001C01   I9
  U2     EA27  VSS1275  SOCKET4677_AZIFS054P001C01   I9
  U2     EA33  VSS1278  SOCKET4677_AZIFS054P001C01   I9
  U2     EA39  VSS1141  SOCKET4677_AZIFS054P001C01   I9
  U2     EA45  VSS1142  SOCKET4677_AZIFS054P001C01   I9
  U2     EA52  VSS1144  SOCKET4677_AZIFS054P001C01   I9
  U2     EA58  VSS1145  SOCKET4677_AZIFS054P001C01   I9
  U2     EA64  VSS1146  SOCKET4677_AZIFS054P001C01   I9
  U2     EA70  VSS1279  SOCKET4677_AZIFS054P001C01   I9
  U2     EA76  VSS1280  SOCKET4677_AZIFS054P001C01   I9
  U2     EA78  VSS1281  SOCKET4677_AZIFS054P001C01   I9
  U2     EA80  VSS1282  SOCKET4677_AZIFS054P001C01   I9
  U2     EA84  VSS1285  SOCKET4677_AZIFS054P001C01   I9
  U2     EA88  VSS1286  SOCKET4677_AZIFS054P001C01   I9
  U2     EB4  VSS1163  SOCKET4677_AZIFS054P001C01   I9
  U2     EB8  VSS1306  SOCKET4677_AZIFS054P001C01   I9
  U2     EB12  VSS1287  SOCKET4677_AZIFS054P001C01   I9
  U2     EB16  VSS1155  SOCKET4677_AZIFS054P001C01   I9
  U2     EB20  VSS1156  SOCKET4677_AZIFS054P001C01   I9
  U2     EB22  VSS1288  SOCKET4677_AZIFS054P001C01   I9
  U2     EB26  VSS1158  SOCKET4677_AZIFS054P001C01   I9
  U2     EB28  VSS1289  SOCKET4677_AZIFS054P001C01   I9
  U2     EB32  VSS1292  SOCKET4677_AZIFS054P001C01   I9
  U2     EB34  VSS1161  SOCKET4677_AZIFS054P001C01   I9
  U2     EB38  VSS1293  SOCKET4677_AZIFS054P001C01   I9
  U2     EB40  VSS1295  SOCKET4677_AZIFS054P001C01   I9
  U2     EB44  VSS1165  SOCKET4677_AZIFS054P001C01   I9
  U2     EB47  VSS1296  SOCKET4677_AZIFS054P001C01   I9
  U2     EB51  VSS1167  SOCKET4677_AZIFS054P001C01   I9
  U2     EB53  VSS1168  SOCKET4677_AZIFS054P001C01   I9
  U2     EB57  VSS1297  SOCKET4677_AZIFS054P001C01   I9
  U2     EB59  VSS1170  SOCKET4677_AZIFS054P001C01   I9
  U2     EB63  VSS1171  SOCKET4677_AZIFS054P001C01   I9
  U2     EB65  VSS1298  SOCKET4677_AZIFS054P001C01   I9
  U2     EB69  VSS1299  SOCKET4677_AZIFS054P001C01   I9
  U2     EB71  VSS1300  SOCKET4677_AZIFS054P001C01   I9
  U2     EB75  VSS1301  SOCKET4677_AZIFS054P001C01   I9
  U2     EB79  VSS1304  SOCKET4677_AZIFS054P001C01   I9
  U2     EB83  VSS1307  SOCKET4677_AZIFS054P001C01   I9
  U2     EB87  VSS1308  SOCKET4677_AZIFS054P001C01   I9
  U2     EB91  VSS1180  SOCKET4677_AZIFS054P001C01   I9
  U2     EC1  VSS1309  SOCKET4677_AZIFS054P001C01   I9
  U2     EC5  VSS1193  SOCKET4677_AZIFS054P001C01   I9
  U2     EC9  VSS1337  SOCKET4677_AZIFS054P001C01   I9
  U2     EC13  VSS1310  SOCKET4677_AZIFS054P001C01   I9
  U2     EC19  VSS1311  SOCKET4677_AZIFS054P001C01   I9
  U2     EC23  VSS1313  SOCKET4677_AZIFS054P001C01   I9
  U2     EC25  VSS1185  SOCKET4677_AZIFS054P001C01   I9
  U2     EC29  VSS1314  SOCKET4677_AZIFS054P001C01   I9
  U2     EC31  VSS1316  SOCKET4677_AZIFS054P001C01   I9
  U2     EC35  VSS1188  SOCKET4677_AZIFS054P001C01   I9
  U2     EC37  VSS1317  SOCKET4677_AZIFS054P001C01   I9
  U2     EC41  VSS1321  SOCKET4677_AZIFS054P001C01   I9
  U2     EC43  VSS1323  SOCKET4677_AZIFS054P001C01   I9
  U2     EC48  VSS1324  SOCKET4677_AZIFS054P001C01   I9
  U2     EC50  VSS1326  SOCKET4677_AZIFS054P001C01   I9
  U2     EC54  VSS1195  SOCKET4677_AZIFS054P001C01   I9
  U2     EC56  VSS1327  SOCKET4677_AZIFS054P001C01   I9
  U2     EC60  VSS1197  SOCKET4677_AZIFS054P001C01   I9
  U2     EC62  VSS1198  SOCKET4677_AZIFS054P001C01   I9
  U2     EC66  VSS1329  SOCKET4677_AZIFS054P001C01   I9
  U2     EC68  VSS1200  SOCKET4677_AZIFS054P001C01   I9
  U2     EC72  VSS1330  SOCKET4677_AZIFS054P001C01   I9
  U2     EC74  VSS1332  SOCKET4677_AZIFS054P001C01   I9
  U2     EC82  VSS1333  SOCKET4677_AZIFS054P001C01   I9
  U2     EC84  VSS1335  SOCKET4677_AZIFS054P001C01   I9
  U2     EC88  VSS1336  SOCKET4677_AZIFS054P001C01   I9
  U2     ED4  VSS1344  SOCKET4677_AZIFS054P001C01   I9
  U2     ED8  VSS1348  SOCKET4677_AZIFS054P001C01   I9
  U2     ED12  VSS1208  SOCKET4677_AZIFS054P001C01   I9
  U2     ED16  VSS1338  SOCKET4677_AZIFS054P001C01   I9
  U2     ED18  VSS1210  SOCKET4677_AZIFS054P001C01   I9
  U2     ED24  VSS1339  SOCKET4677_AZIFS054P001C01   I9
  U2     ED30  VSS1341  SOCKET4677_AZIFS054P001C01   I9
  U2     ED36  VSS1342  SOCKET4677_AZIFS054P001C01   I9
  U2     ED42  VSS1217  SOCKET4677_AZIFS054P001C01   I9
  U2     ED49  VSS1346  SOCKET4677_AZIFS054P001C01   I9
  U2     ED55  VSS1220  SOCKET4677_AZIFS054P001C01   I9
  U2     ED61  VSS1223  SOCKET4677_AZIFS054P001C01   I9
  U2     ED67  VSS1224  SOCKET4677_AZIFS054P001C01   I9
  U2     ED73  VSS1225  SOCKET4677_AZIFS054P001C01   I9
  U2     EE17  VSS1232  SOCKET4677_AZIFS054P001C01   I9
  U2     EE39  VSS1235  SOCKET4677_AZIFS054P001C01   I9
  U2     EE52  VSS1237  SOCKET4677_AZIFS054P001C01   I9
  U2     EE78  VSS1349  SOCKET4677_AZIFS054P001C01   I9
  U2     EE80  VSS1350  SOCKET4677_AZIFS054P001C01   I9
  U2     EE88  VSS1351  SOCKET4677_AZIFS054P001C01   I9
  U2     EF2  VSS1356  SOCKET4677_AZIFS054P001C01   I9
  U2     EF4  VSS1374  SOCKET4677_AZIFS054P001C01   I9
  U2     EF8  VSS1404  SOCKET4677_AZIFS054P001C01   I9
  U2     EF12  VSS1352  SOCKET4677_AZIFS054P001C01   I9
  U2     EF16  VSS1353  SOCKET4677_AZIFS054P001C01   I9
  U2     EF18  VSS1354  SOCKET4677_AZIFS054P001C01   I9
  U2     EF20  VSS1358  SOCKET4677_AZIFS054P001C01   I9
  U2     EF22  VSS1360  SOCKET4677_AZIFS054P001C01   I9
  U2     EF24  VSS1361  SOCKET4677_AZIFS054P001C01   I9
  U2     EF26  VSS1362  SOCKET4677_AZIFS054P001C01   I9
  U2     EF28  VSS1363  SOCKET4677_AZIFS054P001C01   I9
  U2     EF30  VSS1364  SOCKET4677_AZIFS054P001C01   I9
  U2     EF32  VSS1365  SOCKET4677_AZIFS054P001C01   I9
  U2     EF34  VSS1367  SOCKET4677_AZIFS054P001C01   I9
  U2     EF36  VSS1370  SOCKET4677_AZIFS054P001C01   I9
  U2     EF38  VSS1373  SOCKET4677_AZIFS054P001C01   I9
  U2     EF40  VSS1376  SOCKET4677_AZIFS054P001C01   I9
  U2     EF42  VSS1382  SOCKET4677_AZIFS054P001C01   I9
  U2     EF44  VSS1383  SOCKET4677_AZIFS054P001C01   I9
  U2     EF47  VSS1384  SOCKET4677_AZIFS054P001C01   I9
  U2     EF49  VSS1385  SOCKET4677_AZIFS054P001C01   I9
  U2     EF51  VSS1265  SOCKET4677_AZIFS054P001C01   I9
  U2     EF53  VSS1386  SOCKET4677_AZIFS054P001C01   I9
  U2     EF55  VSS1387  SOCKET4677_AZIFS054P001C01   I9
  U2     EF57  VSS1388  SOCKET4677_AZIFS054P001C01   I9
  U2     EF59  VSS1389  SOCKET4677_AZIFS054P001C01   I9
  U2     EF61  VSS1390  SOCKET4677_AZIFS054P001C01   I9
  U2     EF63  VSS1392  SOCKET4677_AZIFS054P001C01   I9
  U2     EF65  VSS1393  SOCKET4677_AZIFS054P001C01   I9
  U2     EF67  VSS1395  SOCKET4677_AZIFS054P001C01   I9
  U2     EF69  VSS1399  SOCKET4677_AZIFS054P001C01   I9
  U2     EF71  VSS1402  SOCKET4677_AZIFS054P001C01   I9
  U2     EF73  VSS1276  SOCKET4677_AZIFS054P001C01   I9
  U2     EF75  VSS1277  SOCKET4677_AZIFS054P001C01   I9
  U2     EF77  VSS1403  SOCKET4677_AZIFS054P001C01   I9
  U2     EF85  VSS1406  SOCKET4677_AZIFS054P001C01   I9
  U2     EF87  VSS1407  SOCKET4677_AZIFS054P001C01   I9
  U2     EF89  VSS1283  SOCKET4677_AZIFS054P001C01   I9
  U2     EG5  VSS1290  SOCKET4677_AZIFS054P001C01   I9
  U2     EG7  VSS1294  SOCKET4677_AZIFS054P001C01   I9
  U2     EG9  VSS1414  SOCKET4677_AZIFS054P001C01   I9
  U2     EG13  VSS1284  SOCKET4677_AZIFS054P001C01   I9
  U2     EG39  VSS1408  SOCKET4677_AZIFS054P001C01   I9
  U2     EG52  VSS1291  SOCKET4677_AZIFS054P001C01   I9
  U2     EG82  VSS1410  SOCKET4677_AZIFS054P001C01   I9
  U2     EG84  VSS1411  SOCKET4677_AZIFS054P001C01   I9
  U2     EG86  VSS1412  SOCKET4677_AZIFS054P001C01   I9
  U2     EG88  VSS1413  SOCKET4677_AZIFS054P001C01   I9
  U2     EG90  VSS1415  SOCKET4677_AZIFS054P001C01   I9
  U2     EH4  VSS1420  SOCKET4677_AZIFS054P001C01   I9
  U2     EH6  VSS1318  SOCKET4677_AZIFS054P001C01   I9
  U2     EH12  VSS1302  SOCKET4677_AZIFS054P001C01   I9
  U2     EH14  VSS1303  SOCKET4677_AZIFS054P001C01   I9
  U2     EH16  VSS1416  SOCKET4677_AZIFS054P001C01   I9
  U2     EH18  VSS1305  SOCKET4677_AZIFS054P001C01   I9
  U2     EH24  VSS1417  SOCKET4677_AZIFS054P001C01   I9
  U2     EH30  VSS1418  SOCKET4677_AZIFS054P001C01   I9
  U2     EH36  VSS1419  SOCKET4677_AZIFS054P001C01   I1
  U2     EH42  VSS1312  SOCKET4677_AZIFS054P001C01   I1
  U2     EH49  VSS1421  SOCKET4677_AZIFS054P001C01   I1
  U2     EH55  VSS1315  SOCKET4677_AZIFS054P001C01   I1
  U2     EH61  VSS1319  SOCKET4677_AZIFS054P001C01   I1
  U2     EH67  VSS1320  SOCKET4677_AZIFS054P001C01   I1
  U2     EH73  VSS1422  SOCKET4677_AZIFS054P001C01   I1
  U2     EH79  VSS1322  SOCKET4677_AZIFS054P001C01   I1
  U2     EH81  VSS1423  SOCKET4677_AZIFS054P001C01   I1
  U2     EH83  VSS1424  SOCKET4677_AZIFS054P001C01   I1
  U2     EJ7  VSS1444  SOCKET4677_AZIFS054P001C01   I1
  U2     EJ9  VSS1450  SOCKET4677_AZIFS054P001C01   I1
  U2     EJ11  VSS1325  SOCKET4677_AZIFS054P001C01   I1
  U2     EJ13  VSS1425  SOCKET4677_AZIFS054P001C01   I1
  U2     EJ17  VSS1328  SOCKET4677_AZIFS054P001C01   I1
  U2     EJ19  VSS1426  SOCKET4677_AZIFS054P001C01   I1
  U2     EJ23  VSS1428  SOCKET4677_AZIFS054P001C01   I1
  U2     EJ25  VSS1331  SOCKET4677_AZIFS054P001C01   I1
  U2     EJ29  VSS1429  SOCKET4677_AZIFS054P001C01   I1
  U2     EJ31  VSS1430  SOCKET4677_AZIFS054P001C01   I1
  U2     EJ35  VSS1334  SOCKET4677_AZIFS054P001C01   I1
  U2     EJ37  VSS1431  SOCKET4677_AZIFS054P001C01   I1
  U2     EJ41  VSS1432  SOCKET4677_AZIFS054P001C01   I1
  U2     EJ43  VSS1433  SOCKET4677_AZIFS054P001C01   I1
  U2     EJ48  VSS1434  SOCKET4677_AZIFS054P001C01   I1
  U2     EJ50  VSS1435  SOCKET4677_AZIFS054P001C01   I1
  U2     EJ54  VSS1340  SOCKET4677_AZIFS054P001C01   I1
  U2     EJ56  VSS1439  SOCKET4677_AZIFS054P001C01   I1
  U2     EJ60  VSS1442  SOCKET4677_AZIFS054P001C01   I1
  U2     EJ62  VSS1343  SOCKET4677_AZIFS054P001C01   I1
  U2     EJ66  VSS1443  SOCKET4677_AZIFS054P001C01   I1
  U2     EJ68  VSS1345  SOCKET4677_AZIFS054P001C01   I1
  U2     EJ72  VSS1347  SOCKET4677_AZIFS054P001C01   I1
  U2     EJ74  VSS1447  SOCKET4677_AZIFS054P001C01   I1
  U2     EJ78  VSS1448  SOCKET4677_AZIFS054P001C01   I1
  U2     EJ88  VSS1449  SOCKET4677_AZIFS054P001C01   I1
  U2     EK2  VSS1458  SOCKET4677_AZIFS054P001C01   I1
  U2     EK4  VSS1466  SOCKET4677_AZIFS054P001C01   I1
  U2     EK10  VSS1451  SOCKET4677_AZIFS054P001C01   I1
  U2     EK14  VSS1455  SOCKET4677_AZIFS054P001C01   I1
  U2     EK16  VSS1355  SOCKET4677_AZIFS054P001C01   I1
  U2     EK20  VSS1357  SOCKET4677_AZIFS054P001C01   I1
  U2     EK22  VSS1459  SOCKET4677_AZIFS054P001C01   I1
  U2     EK26  VSS1359  SOCKET4677_AZIFS054P001C01   I1
  U2     EK28  VSS1460  SOCKET4677_AZIFS054P001C01   I1
  U2     EK32  VSS1461  SOCKET4677_AZIFS054P001C01   I1
  U2     EK34  VSS1463  SOCKET4677_AZIFS054P001C01   I1
  U2     EK38  VSS1465  SOCKET4677_AZIFS054P001C01   I1
  U2     EK40  VSS1469  SOCKET4677_AZIFS054P001C01   I1
  U2     EK44  VSS1366  SOCKET4677_AZIFS054P001C01   I1
  U2     EK47  VSS1470  SOCKET4677_AZIFS054P001C01   I1
  U2     EK51  VSS1368  SOCKET4677_AZIFS054P001C01   I1
  U2     EK53  VSS1369  SOCKET4677_AZIFS054P001C01   I1
  U2     EK57  VSS1471  SOCKET4677_AZIFS054P001C01   I1
  U2     EK59  VSS1371  SOCKET4677_AZIFS054P001C01   I1
  U2     EK63  VSS1372  SOCKET4677_AZIFS054P001C01   I1
  U2     EK65  VSS1472  SOCKET4677_AZIFS054P001C01   I1
  U2     EK69  VSS1473  SOCKET4677_AZIFS054P001C01   I1
  U2     EK71  VSS1375  SOCKET4677_AZIFS054P001C01   I1
  U2     EK75  VSS1474  SOCKET4677_AZIFS054P001C01   I1
  U2     EK77  VSS1377  SOCKET4677_AZIFS054P001C01   I1
  U2     EK79  VSS1378  SOCKET4677_AZIFS054P001C01   I1
  U2     EK83  VSS1379  SOCKET4677_AZIFS054P001C01   I1
  U2     EK89  VSS1380  SOCKET4677_AZIFS054P001C01   I1
  U2     EL3  VSS1479  SOCKET4677_AZIFS054P001C01   I1
  U2     EL5  VSS1486  SOCKET4677_AZIFS054P001C01   I1
  U2     EL7  VSS1396  SOCKET4677_AZIFS054P001C01   I1
  U2     EL9  VSS1401  SOCKET4677_AZIFS054P001C01   I1
  U2     EL15  VSS1381  SOCKET4677_AZIFS054P001C01   I1
  U2     EL21  VSS1475  SOCKET4677_AZIFS054P001C01   I1
  U2     EL27  VSS1477  SOCKET4677_AZIFS054P001C01   I1
  U2     EL33  VSS1481  SOCKET4677_AZIFS054P001C01   I1
  U2     EL39  VSS1483  SOCKET4677_AZIFS054P001C01   I1
  U2     EL45  VSS1485  SOCKET4677_AZIFS054P001C01   I1
  U2     EL52  VSS1391  SOCKET4677_AZIFS054P001C01   I1
  U2     EL58  VSS1394  SOCKET4677_AZIFS054P001C01   I1
  U2     EL64  VSS1488  SOCKET4677_AZIFS054P001C01   I1
  U2     EL70  VSS1397  SOCKET4677_AZIFS054P001C01   I1
  U2     EL72  VSS1398  SOCKET4677_AZIFS054P001C01   I1
  U2     EL76  VSS1489  SOCKET4677_AZIFS054P001C01   I1
  U2     EL86  VSS1400  SOCKET4677_AZIFS054P001C01   I1
  U2     EM8  VSS1497  SOCKET4677_AZIFS054P001C01   I1
  U2     EM42  VSS1492  SOCKET4677_AZIFS054P001C01   I1
  U2     EM49  VSS1405  SOCKET4677_AZIFS054P001C01   I1
  U2     EM73  VSS1496  SOCKET4677_AZIFS054P001C01   I1
  U2     EM79  VSS1409  SOCKET4677_AZIFS054P001C01   I1
  U2     EM81  VSS1498  SOCKET4677_AZIFS054P001C01   I1
  U2     EM83  VSS1499  SOCKET4677_AZIFS054P001C01   I1
  U2     EN9  VSS1446  SOCKET4677_AZIFS054P001C01   I1
  U2     EN11  VSS1500  SOCKET4677_AZIFS054P001C01   I1
  U2     EN13  VSS1501  SOCKET4677_AZIFS054P001C01   I1
  U2     EN15  VSS1503  SOCKET4677_AZIFS054P001C01   I1
  U2     EN17  VSS1505  SOCKET4677_AZIFS054P001C01   I1
  U2     EN19  VSS1506  SOCKET4677_AZIFS054P001C01   I1
  U2     EN21  VSS1512  SOCKET4677_AZIFS054P001C01   I1
  U2     EN23  VSS1513  SOCKET4677_AZIFS054P001C01   I1
  U2     EN25  VSS1515  SOCKET4677_AZIFS054P001C01   I1
  U2     EN27  VSS1517  SOCKET4677_AZIFS054P001C01   I1
  U2     EN29  VSS1518  SOCKET4677_AZIFS054P001C01   I1
  U2     EN31  VSS1520  SOCKET4677_AZIFS054P001C01   I1
  U2     EN33  VSS1522  SOCKET4677_AZIFS054P001C01   I1
  U2     EN35  VSS1524  SOCKET4677_AZIFS054P001C01   I1
  U2     EN37  VSS1525  SOCKET4677_AZIFS054P001C01   I1
  U2     EN39  VSS1427  SOCKET4677_AZIFS054P001C01   I1
  U2     EN41  VSS1526  SOCKET4677_AZIFS054P001C01   I1
  U2     EN43  VSS1528  SOCKET4677_AZIFS054P001C01   I1
  U2     EN45  VSS1529  SOCKET4677_AZIFS054P001C01   I1
  U2     EN48  VSS1530  SOCKET4677_AZIFS054P001C01   I1
  U2     EN50  VSS1531  SOCKET4677_AZIFS054P001C01   I1
  U2     EN52  VSS1533  SOCKET4677_AZIFS054P001C01   I1
  U2     EN54  VSS1537  SOCKET4677_AZIFS054P001C01   I1
  U2     EN56  VSS1539  SOCKET4677_AZIFS054P001C01   I1
  U2     EN58  VSS1436  SOCKET4677_AZIFS054P001C01   I1
  U2     EN60  VSS1437  SOCKET4677_AZIFS054P001C01   I1
  U2     EN62  VSS1438  SOCKET4677_AZIFS054P001C01   I1
  U2     EN64  VSS1540  SOCKET4677_AZIFS054P001C01   I1
  U2     EN66  VSS1440  SOCKET4677_AZIFS054P001C01   I1
  U2     EN72  VSS1441  SOCKET4677_AZIFS054P001C01   I1
  U2     EN78  VSS1541  SOCKET4677_AZIFS054P001C01   I1
  U2     EN80  VSS1542  SOCKET4677_AZIFS054P001C01   I1
  U2     EN88  VSS1445  SOCKET4677_AZIFS054P001C01   I1
  U2     EP67  VSS1543  SOCKET4677_AZIFS054P001C01   I1
  U2     EP69  VSS1452  SOCKET4677_AZIFS054P001C01   I1
  U2     EP71  VSS1453  SOCKET4677_AZIFS054P001C01   I1
  U2     EP77  VSS1454  SOCKET4677_AZIFS054P001C01   I1
  U2     EP83  VSS1545  SOCKET4677_AZIFS054P001C01   I1
  U2     ER5  VSS1549  SOCKET4677_AZIFS054P001C01   I1
  U2     ER7  VSS1550  SOCKET4677_AZIFS054P001C01   I1
  U2     ER9  VSS1476  SOCKET4677_AZIFS054P001C01   I1
  U2     ER15  VSS1456  SOCKET4677_AZIFS054P001C01   I1
  U2     ER21  VSS1457  SOCKET4677_AZIFS054P001C01   I1
  U2     ER27  VSS1547  SOCKET4677_AZIFS054P001C01   I1
  U2     ER33  VSS1548  SOCKET4677_AZIFS054P001C01   I1
  U2     ER39  VSS1462  SOCKET4677_AZIFS054P001C01   I1
  U2     ER41  GND_ER41  SOCKET4677_AZIFS054P001C01   I1
  U2     ER43  GND_ER43  SOCKET4677_AZIFS054P001C01   I1
  U2     ER48  GND_ER48  SOCKET4677_AZIFS054P001C01   I1
  U2     ER50  GND_ER50  SOCKET4677_AZIFS054P001C01   I1
  U2     ER52  VSS1464  SOCKET4677_AZIFS054P001C01   I1
  U2     ER58  VSS1467  SOCKET4677_AZIFS054P001C01   I1
  U2     ER64  VSS1468  SOCKET4677_AZIFS054P001C01   I1
  U2     ER70  VSS1551  SOCKET4677_AZIFS054P001C01   I1
  U2     ER74  VSS1552  SOCKET4677_AZIFS054P001C01   I1
  U2     ER78  VSS1553  SOCKET4677_AZIFS054P001C01   I1
  U2     ER80  VSS1554  SOCKET4677_AZIFS054P001C01   I1
  U2     ER84  VSS1555  SOCKET4677_AZIFS054P001C01   I1
  U2     ER86  VSS1556  SOCKET4677_AZIFS054P001C01   I1
  U2     ET10  VSS1557  SOCKET4677_AZIFS054P001C01   I1
  U2     ET14  VSS1478  SOCKET4677_AZIFS054P001C01   I1
  U2     ET16  VSS1559  SOCKET4677_AZIFS054P001C01   I1
  U2     ET20  VSS1480  SOCKET4677_AZIFS054P001C01   I1
  U2     ET22  VSS1561  SOCKET4677_AZIFS054P001C01   I1
  U2     ET26  VSS1482  SOCKET4677_AZIFS054P001C01   I1
  U2     ET28  VSS1562  SOCKET4677_AZIFS054P001C01   I1
  U2     ET32  VSS1484  SOCKET4677_AZIFS054P001C01   I1
  U2     ET34  VSS1563  SOCKET4677_AZIFS054P001C01   I1
  U2     ET38  VSS1565  SOCKET4677_AZIFS054P001C01   I1
  U2     ET53  VSS1491  SOCKET4677_AZIFS054P001C01   I1
  U2     ET57  VSS1569  SOCKET4677_AZIFS054P001C01   I1
  U2     ET59  VSS1493  SOCKET4677_AZIFS054P001C01   I1
  U2      F4  VSS1573  SOCKET4677_AZIFS054P001C01  I11
  U2      F6  VSS1507  SOCKET4677_AZIFS054P001C01  I11
  U2     F12  VSS1494  SOCKET4677_AZIFS054P001C01  I11
  U2     F18  VSS1495  SOCKET4677_AZIFS054P001C01  I11
  U2     F24  VSS1570  SOCKET4677_AZIFS054P001C01  I11
  U2     F30  VSS1571  SOCKET4677_AZIFS054P001C01  I11
  U2     F36  VSS1572  SOCKET4677_AZIFS054P001C01  I11
  U2     F42  VSS1502  SOCKET4677_AZIFS054P001C01  I11
  U2     F49  VSS1574  SOCKET4677_AZIFS054P001C01  I11
  U2     F55  VSS1504  SOCKET4677_AZIFS054P001C01  I11
  U2     F61  VSS1508  SOCKET4677_AZIFS054P001C01  I11
  U2     F67  VSS1509  SOCKET4677_AZIFS054P001C01  I11
  U2     F73  VSS1510  SOCKET4677_AZIFS054P001C01  I11
  U2     F79  VSS1511  SOCKET4677_AZIFS054P001C01  I11
  U2     F83  VSS1576  SOCKET4677_AZIFS054P001C01  I11
  U2     F89  VSS1577  SOCKET4677_AZIFS054P001C01  I11
  U2      G3  VSS1521  SOCKET4677_AZIFS054P001C01  I11
  U2      G7  VSS1536  SOCKET4677_AZIFS054P001C01  I11
  U2     G11  VSS1514  SOCKET4677_AZIFS054P001C01  I11
  U2     G13  VSS1578  SOCKET4677_AZIFS054P001C01  I11
  U2     G17  VSS1516  SOCKET4677_AZIFS054P001C01  I11
  U2     G19  VSS1579  SOCKET4677_AZIFS054P001C01  I11
  U2     G23  VSS1581  SOCKET4677_AZIFS054P001C01  I11
  U2     G25  VSS1519  SOCKET4677_AZIFS054P001C01  I11
  U2     G29  VSS1583  SOCKET4677_AZIFS054P001C01  I11
  U2     G31  VSS1584  SOCKET4677_AZIFS054P001C01  I11
  U2     G35  VSS1523  SOCKET4677_AZIFS054P001C01  I11
  U2     G37  VSS1585  SOCKET4677_AZIFS054P001C01  I11
  U2     G41  VSS1586  SOCKET4677_AZIFS054P001C01  I11
  U2     G43  VSS1588  SOCKET4677_AZIFS054P001C01  I11
  U2     G48  VSS1527  SOCKET4677_AZIFS054P001C01  I11
  U2     G50  VSS1590  SOCKET4677_AZIFS054P001C01  I11
  U2     G54  VSS1591  SOCKET4677_AZIFS054P001C01  I11
  U2     G56  VSS1592  SOCKET4677_AZIFS054P001C01  I11
  U2     G60  VSS1532  SOCKET4677_AZIFS054P001C01  I11
  U2     G62  VSS1593  SOCKET4677_AZIFS054P001C01  I11
  U2     G66  VSS1534  SOCKET4677_AZIFS054P001C01  I11
  U2     G68  VSS1535  SOCKET4677_AZIFS054P001C01  I11
  U2     G72  VSS1594  SOCKET4677_AZIFS054P001C01  I11
  U2     G74  VSS1538  SOCKET4677_AZIFS054P001C01  I11
  U2     G84  VSS1600  SOCKET4677_AZIFS054P001C01  I11
  U2     G88  VSS1601  SOCKET4677_AZIFS054P001C01  I11
  U2     G90  VSS1604  SOCKET4677_AZIFS054P001C01  I11
  U2      H2  VSS1546  SOCKET4677_AZIFS054P001C01  I11
  U2      H4  VSS1615  SOCKET4677_AZIFS054P001C01  I11
  U2      H6  VSS1621  SOCKET4677_AZIFS054P001C01  I11
  U2      H8  VSS1626  SOCKET4677_AZIFS054P001C01  I11
  U2     H10  VSS1605  SOCKET4677_AZIFS054P001C01  I11
  U2     H14  VSS1544  SOCKET4677_AZIFS054P001C01  I11
  U2     H16  VSS1606  SOCKET4677_AZIFS054P001C01  I11
  U2     H20  VSS1607  SOCKET4677_AZIFS054P001C01  I11
  U2     H22  VSS1608  SOCKET4677_AZIFS054P001C01  I11
  U2     H26  VSS1609  SOCKET4677_AZIFS054P001C01  I11
  U2     H28  VSS1610  SOCKET4677_AZIFS054P001C01  I11
  U2     H32  VSS1611  SOCKET4677_AZIFS054P001C01  I11
  U2     H34  VSS1612  SOCKET4677_AZIFS054P001C01  I11
  U2     H38  VSS1613  SOCKET4677_AZIFS054P001C01  I11
  U2     H40  VSS1616  SOCKET4677_AZIFS054P001C01  I11
  U2     H44  VSS1617  SOCKET4677_AZIFS054P001C01  I11
  U2     H47  VSS1618  SOCKET4677_AZIFS054P001C01  I11
  U2     H51  VSS1558  SOCKET4677_AZIFS054P001C01  I11
  U2     H53  VSS1619  SOCKET4677_AZIFS054P001C01  I11
  U2     H57  VSS1560  SOCKET4677_AZIFS054P001C01  I11
  U2     H59  VSS1620  SOCKET4677_AZIFS054P001C01  I11
  U2     H63  VSS1622  SOCKET4677_AZIFS054P001C01  I11
  U2     H65  VSS1564  SOCKET4677_AZIFS054P001C01  I11
  U2     H69  VSS1623  SOCKET4677_AZIFS054P001C01  I11
  U2     H71  VSS1624  SOCKET4677_AZIFS054P001C01  I11
  U2     H75  VSS1567  SOCKET4677_AZIFS054P001C01  I11
  U2     H79  VSS1625  SOCKET4677_AZIFS054P001C01  I11
  U2     H81  VSS1627  SOCKET4677_AZIFS054P001C01  I11
  U2      J5  VSS1582  SOCKET4677_AZIFS054P001C01  I11
  U2      J9  VSS1596  SOCKET4677_AZIFS054P001C01  I11
  U2     J15  VSS1628  SOCKET4677_AZIFS054P001C01  I11
  U2     J21  VSS1575  SOCKET4677_AZIFS054P001C01  I11
  U2     J27  VSS1629  SOCKET4677_AZIFS054P001C01  I11
  U2     J33  VSS1630  SOCKET4677_AZIFS054P001C01  I11
  U2     J39  VSS1580  SOCKET4677_AZIFS054P001C01  I11
  U2     J45  VSS1631  SOCKET4677_AZIFS054P001C01  I11
  U2     J52  VSS1632  SOCKET4677_AZIFS054P001C01  I11
  U2     J58  VSS1633  SOCKET4677_AZIFS054P001C01  I11
  U2     J64  VSS1587  SOCKET4677_AZIFS054P001C01  I11
  U2     J70  VSS1589  SOCKET4677_AZIFS054P001C01  I11
  U2     J76  VSS1635  SOCKET4677_AZIFS054P001C01  I11
  U2     J78  VSS1636  SOCKET4677_AZIFS054P001C01  I11
  U2     J84  VSS1637  SOCKET4677_AZIFS054P001C01  I11
  U2     J86  VSS1638  SOCKET4677_AZIFS054P001C01  I11
  U2     J88  VSS1595  SOCKET4677_AZIFS054P001C01  I11
  U2      K2  VSS1599  SOCKET4677_AZIFS054P001C01  I11
  U2      K8  VSS1641  SOCKET4677_AZIFS054P001C01  I11
  U2     K12  VSS1597  SOCKET4677_AZIFS054P001C01  I11
  U2     K14  VSS1598  SOCKET4677_AZIFS054P001C01  I11
  U2     K42  VSS1602  SOCKET4677_AZIFS054P001C01  I11
  U2     K49  VSS1603  SOCKET4677_AZIFS054P001C01  I11
  U2     K77  VSS1639  SOCKET4677_AZIFS054P001C01  I11
  U2     K83  VSS1642  SOCKET4677_AZIFS054P001C01  I11
  U2     K85  VSS1643  SOCKET4677_AZIFS054P001C01  I11
  U2      L5  VSS1671  SOCKET4677_AZIFS054P001C01  I11
  U2      L9  VSS1647  SOCKET4677_AZIFS054P001C01  I11
  U2     L13  VSS1644  SOCKET4677_AZIFS054P001C01  I11
  U2     L15  VSS1645  SOCKET4677_AZIFS054P001C01  I11
  U2     L17  VSS1650  SOCKET4677_AZIFS054P001C01  I11
  U2     L19  VSS1614  SOCKET4677_AZIFS054P001C01  I11
  U2     L21  VSS1651  SOCKET4677_AZIFS054P001C01  I11
  U2     L23  VSS1655  SOCKET4677_AZIFS054P001C01  I11
  U2     L25  VSS1656  SOCKET4677_AZIFS054P001C01  I11
  U2     L27  VSS1658  SOCKET4677_AZIFS054P001C01  I11
  U2     L29  VSS1659  SOCKET4677_AZIFS054P001C01  I11
  U2     L31  VSS1660  SOCKET4677_AZIFS054P001C01  I11
  U2     L33  VSS1661  SOCKET4677_AZIFS054P001C01  I11
  U2     L35  VSS1662  SOCKET4677_AZIFS054P001C01  I11
  U2     L37  VSS1663  SOCKET4677_AZIFS054P001C01  I11
  U2     L39  VSS1665  SOCKET4677_AZIFS054P001C01  I11
  U2     L41  VSS1666  SOCKET4677_AZIFS054P001C01  I11
  U2     L43  VSS1667  SOCKET4677_AZIFS054P001C01  I11
  U2     L45  VSS1668  SOCKET4677_AZIFS054P001C01  I11
  U2     L48  VSS1670  SOCKET4677_AZIFS054P001C01  I11
  U2     L50  VSS1672  SOCKET4677_AZIFS054P001C01  I11
  U2     L52  VSS1673  SOCKET4677_AZIFS054P001C01  I11
  U2     L54  VSS1674  SOCKET4677_AZIFS054P001C01  I11
  U2     L56  VSS1676  SOCKET4677_AZIFS054P001C01  I11
  U2     L58  VSS1634  SOCKET4677_AZIFS054P001C01  I11
  U2     L60  VSS1677  SOCKET4677_AZIFS054P001C01  I11
  U2     L62  VSS1678  SOCKET4677_AZIFS054P001C01  I11
  U2     L64  VSS1679  SOCKET4677_AZIFS054P001C01  I11
  U2     L66  VSS1680  SOCKET4677_AZIFS054P001C01  I11
  U2     L68  VSS1681  SOCKET4677_AZIFS054P001C01  I11
  U2     L70  VSS1640  SOCKET4677_AZIFS054P001C01  I11
  U2     L72  VSS1682  SOCKET4677_AZIFS054P001C01  I11
  U2     L74  VSS1683  SOCKET4677_AZIFS054P001C01  I11
  U2     L76  VSS1684  SOCKET4677_AZIFS054P001C01  I11
  U2     L78  VSS1685  SOCKET4677_AZIFS054P001C01  I11
  U2     L88  VSS1646  SOCKET4677_AZIFS054P001C01  I11
  U2     L90  VSS1648  SOCKET4677_AZIFS054P001C01  I11
  U2      M4  VSS1652  SOCKET4677_AZIFS054P001C01  I11
  U2      M8  VSS1657  SOCKET4677_AZIFS054P001C01  I11
  U2     M12  VSS1649  SOCKET4677_AZIFS054P001C01  I11
  U2     M42  VSS1653  SOCKET4677_AZIFS054P001C01  I11
  U2     M49  VSS1654  SOCKET4677_AZIFS054P001C01  I11
  U2     M81  VSS1686  SOCKET4677_AZIFS054P001C01  I11
  U2     M83  VSS1687  SOCKET4677_AZIFS054P001C01  I11
  U2     N15  VSS1688  SOCKET4677_AZIFS054P001C01  I11
  U2     N21  VSS1664  SOCKET4677_AZIFS054P001C01  I11
  U2     N27  VSS1689  SOCKET4677_AZIFS054P001C01  I11
  U2     N33  VSS1691  SOCKET4677_AZIFS054P001C01  I11
  U2     N39  VSS1669  SOCKET4677_AZIFS054P001C01  I11
  U2     N45  VSS1692  SOCKET4677_AZIFS054P001C01  I11
  U2     N52  VSS1693  SOCKET4677_AZIFS054P001C01  I11
  U2     N58  VSS1694  SOCKET4677_AZIFS054P001C01  I11
  U2     N64  VSS1675  SOCKET4677_AZIFS054P001C01  I11
  U2     N70  VSS1695  SOCKET4677_AZIFS054P001C01  I11
  U2     N76  VSS1696  SOCKET4677_AZIFS054P001C01  I10
  U2     N78  VSS1698  SOCKET4677_AZIFS054P001C01  I10
  U2     N80  VSS1700  SOCKET4677_AZIFS054P001C01  I10
  U2     N82  VSS1701  SOCKET4677_AZIFS054P001C01  I10
  U2     N84  VSS1702  SOCKET4677_AZIFS054P001C01  I10
  U2     N88  VSS1703  SOCKET4677_AZIFS054P001C01  I10
  U2      P4  VSS1716  SOCKET4677_AZIFS054P001C01  I10
  U2      P8  VSS1729  SOCKET4677_AZIFS054P001C01  I10
  U2     P12  VSS1705  SOCKET4677_AZIFS054P001C01  I10
  U2     P16  VSS1706  SOCKET4677_AZIFS054P001C01  I10
  U2     P20  VSS1707  SOCKET4677_AZIFS054P001C01  I10
  U2     P22  VSS1708  SOCKET4677_AZIFS054P001C01  I10
  U2     P26  VSS1709  SOCKET4677_AZIFS054P001C01  I10
  U2     P28  VSS1710  SOCKET4677_AZIFS054P001C01  I10
  U2     P32  VSS1690  SOCKET4677_AZIFS054P001C01  I10
  U2     P34  VSS1712  SOCKET4677_AZIFS054P001C01  I10
  U2     P38  VSS1713  SOCKET4677_AZIFS054P001C01  I10
  U2     P40  VSS1717  SOCKET4677_AZIFS054P001C01  I10
  U2     P44  VSS1718  SOCKET4677_AZIFS054P001C01  I10
  U2     P47  VSS1719  SOCKET4677_AZIFS054P001C01  I10
  U2     P51  VSS1697  SOCKET4677_AZIFS054P001C01  I10
  U2     P53  VSS1720  SOCKET4677_AZIFS054P001C01  I10
  U2     P57  VSS1699  SOCKET4677_AZIFS054P001C01  I10
  U2     P59  VSS1721  SOCKET4677_AZIFS054P001C01  I10
  U2     P63  VSS1722  SOCKET4677_AZIFS054P001C01  I10
  U2     P65  VSS1724  SOCKET4677_AZIFS054P001C01  I10
  U2     P69  VSS1725  SOCKET4677_AZIFS054P001C01  I10
  U2     P71  VSS1704  SOCKET4677_AZIFS054P001C01  I10
  U2     P75  VSS1726  SOCKET4677_AZIFS054P001C01  I10
  U2     P77  VSS1727  SOCKET4677_AZIFS054P001C01  I10
  U2     P87  VSS1731  SOCKET4677_AZIFS054P001C01  I10
  U2     P91  VSS1732  SOCKET4677_AZIFS054P001C01  I10
  U2      R1  VSS1711  SOCKET4677_AZIFS054P001C01  I10
  U2      R5  VSS1745  SOCKET4677_AZIFS054P001C01  I10
  U2      R9  VSS1759  SOCKET4677_AZIFS054P001C01  I10
  U2     R13  VSS1733  SOCKET4677_AZIFS054P001C01  I10
  U2     R17  VSS1734  SOCKET4677_AZIFS054P001C01  I10
  U2     R19  VSS1714  SOCKET4677_AZIFS054P001C01  I10
  U2     R23  VSS1715  SOCKET4677_AZIFS054P001C01  I10
  U2     R25  VSS1735  SOCKET4677_AZIFS054P001C01  I10
  U2     R29  VSS1736  SOCKET4677_AZIFS054P001C01  I10
  U2     R31  VSS1737  SOCKET4677_AZIFS054P001C01  I10
  U2     R35  VSS1738  SOCKET4677_AZIFS054P001C01  I10
  U2     R37  VSS1742  SOCKET4677_AZIFS054P001C01  I10
  U2     R41  VSS1743  SOCKET4677_AZIFS054P001C01  I10
  U2     R43  VSS1744  SOCKET4677_AZIFS054P001C01  I10
  U2     R48  VSS1723  SOCKET4677_AZIFS054P001C01  I10
  U2     R50  VSS1747  SOCKET4677_AZIFS054P001C01  I10
  U2     R54  VSS1748  SOCKET4677_AZIFS054P001C01  I10
  U2     R56  VSS1751  SOCKET4677_AZIFS054P001C01  I10
  U2     R60  VSS1728  SOCKET4677_AZIFS054P001C01  I10
  U2     R62  VSS1752  SOCKET4677_AZIFS054P001C01  I10
  U2     R66  VSS1730  SOCKET4677_AZIFS054P001C01  I10
  U2     R68  VSS1753  SOCKET4677_AZIFS054P001C01  I10
  U2     R72  VSS1754  SOCKET4677_AZIFS054P001C01  I10
  U2     R74  VSS1755  SOCKET4677_AZIFS054P001C01  I10
  U2     R78  VSS1756  SOCKET4677_AZIFS054P001C01  I10
  U2     R84  VSS1757  SOCKET4677_AZIFS054P001C01  I10
  U2     R88  VSS1758  SOCKET4677_AZIFS054P001C01  I10
  U2      T4  VSS1762  SOCKET4677_AZIFS054P001C01  I10
  U2      T8  VSS1769  SOCKET4677_AZIFS054P001C01  I10
  U2     T12  VSS1739  SOCKET4677_AZIFS054P001C01  I10
  U2     T16  VSS1740  SOCKET4677_AZIFS054P001C01  I10
  U2     T18  VSS1741  SOCKET4677_AZIFS054P001C01  I10
  U2     T24  VSS1760  SOCKET4677_AZIFS054P001C01  I10
  U2     T30  VSS1761  SOCKET4677_AZIFS054P001C01  I10
  U2     T36  VSS1746  SOCKET4677_AZIFS054P001C01  I10
  U2     T42  VSS1763  SOCKET4677_AZIFS054P001C01  I10
  U2     T49  VSS1749  SOCKET4677_AZIFS054P001C01  I10
  U2     T55  VSS1750  SOCKET4677_AZIFS054P001C01  I10
  U2     T61  VSS1764  SOCKET4677_AZIFS054P001C01  I10
  U2     T67  VSS1765  SOCKET4677_AZIFS054P001C01  I10
  U2     T73  VSS1767  SOCKET4677_AZIFS054P001C01  I10
  U2     T79  VSS1768  SOCKET4677_AZIFS054P001C01  I10
  U2     T83  VSS1770  SOCKET4677_AZIFS054P001C01  I10
  U2     U39  VSS1771  SOCKET4677_AZIFS054P001C01  I10
  U2     U52  VSS1766  SOCKET4677_AZIFS054P001C01  I10
  U2     U82  VSS1772  SOCKET4677_AZIFS054P001C01  I10
  U2     U84  VSS1773  SOCKET4677_AZIFS054P001C01  I10
  U2     U88  VSS1774  SOCKET4677_AZIFS054P001C01  I10
  U2      V4  VSS1788  SOCKET4677_AZIFS054P001C01  I10
  U2      V8  VSS1812  SOCKET4677_AZIFS054P001C01  I10
  U2     V12  VSS1775  SOCKET4677_AZIFS054P001C01  I10
  U2     V16  VSS1776  SOCKET4677_AZIFS054P001C01  I10
  U2     V18  VSS1777  SOCKET4677_AZIFS054P001C01  I10
  U2     V20  VSS1778  SOCKET4677_AZIFS054P001C01  I10
  U2     V22  VSS1779  SOCKET4677_AZIFS054P001C01  I10
  U2     V24  VSS1780  SOCKET4677_AZIFS054P001C01  I10
  U2     V26  VSS1781  SOCKET4677_AZIFS054P001C01  I10
  U2     V28  VSS1782  SOCKET4677_AZIFS054P001C01  I10
  U2     V30  VSS1783  SOCKET4677_AZIFS054P001C01  I10
  U2     V32  VSS1784  SOCKET4677_AZIFS054P001C01  I10
  U2     V34  VSS1785  SOCKET4677_AZIFS054P001C01  I10
  U2     V36  VSS1786  SOCKET4677_AZIFS054P001C01  I10
  U2     V38  VSS1787  SOCKET4677_AZIFS054P001C01  I10
  U2     V40  VSS1790  SOCKET4677_AZIFS054P001C01  I10
  U2     V42  VSS1791  SOCKET4677_AZIFS054P001C01  I10
  U2     V44  VSS1792  SOCKET4677_AZIFS054P001C01  I10
  U2     V47  VSS1793  SOCKET4677_AZIFS054P001C01  I10
  U2     V49  VSS1789  SOCKET4677_AZIFS054P001C01  I10
  U2     V51  VSS1794  SOCKET4677_AZIFS054P001C01  I10
  U2     V53  VSS1795  SOCKET4677_AZIFS054P001C01  I10
  U2     V55  VSS1796  SOCKET4677_AZIFS054P001C01  I10
  U2     V57  VSS1797  SOCKET4677_AZIFS054P001C01  I10
  U2     V59  VSS1798  SOCKET4677_AZIFS054P001C01  I10
  U2     V61  VSS1799  SOCKET4677_AZIFS054P001C01  I10
  U2     V63  VSS1802  SOCKET4677_AZIFS054P001C01  I10
  U2     V65  VSS1803  SOCKET4677_AZIFS054P001C01  I10
  U2     V67  VSS1804  SOCKET4677_AZIFS054P001C01  I10
  U2     V69  VSS1805  SOCKET4677_AZIFS054P001C01  I10
  U2     V71  VSS1800  SOCKET4677_AZIFS054P001C01  I10
  U2     V73  VSS1801  SOCKET4677_AZIFS054P001C01  I10
  U2     V75  VSS1806  SOCKET4677_AZIFS054P001C01  I10
  U2     V77  VSS1810  SOCKET4677_AZIFS054P001C01  I10
  U2     V79  VSS1811  SOCKET4677_AZIFS054P001C01  I10
  U2     V87  VSS1813  SOCKET4677_AZIFS054P001C01  I10
  U2     V91  VSS1807  SOCKET4677_AZIFS054P001C01  I10
  U2      W1  VSS1808  SOCKET4677_AZIFS054P001C01  I10
  U2      W5  VSS1814  SOCKET4677_AZIFS054P001C01  I10
  U2      W9  VSS1819  SOCKET4677_AZIFS054P001C01  I10
  U2     W13  VSS1809  SOCKET4677_AZIFS054P001C01  I10
  U2     W39  VSS1816  SOCKET4677_AZIFS054P001C01  I10
  U2     W52  VSS1815  SOCKET4677_AZIFS054P001C01  I10
  U2     W84  VSS1817  SOCKET4677_AZIFS054P001C01  I10
  U2     W88  VSS1818  SOCKET4677_AZIFS054P001C01  I10
  U2      Y4  VSS1826  SOCKET4677_AZIFS054P001C01  I10
  U2      Y8  VSS1832  SOCKET4677_AZIFS054P001C01  I10
  U2     Y12  VSS1820  SOCKET4677_AZIFS054P001C01  I10
  U2     Y16  VSS1821  SOCKET4677_AZIFS054P001C01  I10
  U2     Y18  VSS1822  SOCKET4677_AZIFS054P001C01  I10
  U2     Y24  VSS1823  SOCKET4677_AZIFS054P001C01  I10
  U2     Y30  VSS1824  SOCKET4677_AZIFS054P001C01  I10
  U2     Y36  VSS1825  SOCKET4677_AZIFS054P001C01  I10
  U2     Y42  VSS1827  SOCKET4677_AZIFS054P001C01  I10
  U2     Y49  VSS1830  SOCKET4677_AZIFS054P001C01  I10
  U2     Y55  VSS1831  SOCKET4677_AZIFS054P001C01  I10
  U2     Y61  VSS1828  SOCKET4677_AZIFS054P001C01  I10
  U2     Y67  VSS1829  SOCKET4677_AZIFS054P001C01  I10
  U2     Y73  VSS1833  SOCKET4677_AZIFS054P001C01  I10
  U4      A6  VSS_A6  EMMITSBURG_REV0P9   I9
  U4     A20  VSS_A20  EMMITSBURG_REV0P9   I9
  U4     A22  VSS_A22  EMMITSBURG_REV0P9   I9
  U4     A24  VSS_A24  EMMITSBURG_REV0P9   I9
  U4     A26  VSS_A26  EMMITSBURG_REV0P9   I9
  U4     A38  VSS_A38  EMMITSBURG_REV0P9   I9
  U4     A40  VSS_A40  EMMITSBURG_REV0P9   I9
  U4     AA5  VSS_AA5  EMMITSBURG_REV0P9   I9
  U4     AA17  VSS_AA17  EMMITSBURG_REV0P9   I9
  U4     AA19  VSS_AA19  EMMITSBURG_REV0P9   I9
  U4     AA20  VSS_AA20  EMMITSBURG_REV0P9   I9
  U4     AA22  VSS_AA22  EMMITSBURG_REV0P9   I9
  U4     AA24  VSS_AA24  EMMITSBURG_REV0P9   I9
  U4     AA25  VSS_AA25  EMMITSBURG_REV0P9   I9
  U4     AA27  VSS_AA27  EMMITSBURG_REV0P9   I9
  U4     AA32  VSS_AA32  EMMITSBURG_REV0P9   I9
  U4     AA36  VSS_AA36  EMMITSBURG_REV0P9   I9
  U4     AA39  VSS_AA39  EMMITSBURG_REV0P9   I9
  U4     AB15  VSS_AB15  EMMITSBURG_REV0P9   I9
  U4     AB17  VSS_AB17  EMMITSBURG_REV0P9   I9
  U4     AB25  VSS_AB25  EMMITSBURG_REV0P9   I9
  U4     AB37  VSS_AB37  EMMITSBURG_REV0P9   I9
  U4     AC5  VSS_AC5  EMMITSBURG_REV0P9   I9
  U4     AC29  VSS_AC29  EMMITSBURG_REV0P9   I9
  U4     AC32  VSS_AC32  EMMITSBURG_REV0P9   I9
  U4     AC36  VSS_AC36  EMMITSBURG_REV0P9   I9
  U4     AC39  VSS_AC39  EMMITSBURG_REV0P9   I9
  U4     AD8  VSS_AD8  EMMITSBURG_REV0P9   I9
  U4     AD11  VSS_AD11  EMMITSBURG_REV0P9   I9
  U4     AD19  VSS_AD19  EMMITSBURG_REV0P9   I9
  U4     AD20  VSS_AD20  EMMITSBURG_REV0P9   I9
  U4     AD22  VSS_AD22  EMMITSBURG_REV0P9   I9
  U4     AD24  VSS_AD24  EMMITSBURG_REV0P9   I9
  U4     AD31  VSS_AD31  EMMITSBURG_REV0P9   I9
  U4     AD34  VSS_AD34  EMMITSBURG_REV0P9   I9
  U4     AE5  VSS_AE5  EMMITSBURG_REV0P9   I9
  U4     AE13  VSS_AE13  EMMITSBURG_REV0P9   I9
  U4     AE39  VSS_AE39  EMMITSBURG_REV0P9   I9
  U4     AF19  VSS_AF19  EMMITSBURG_REV0P9   I9
  U4     AF24  VSS_AF24  EMMITSBURG_REV0P9   I9
  U4     AF31  VSS_AF31  EMMITSBURG_REV0P9   I9
  U4     AF40  VSS_AF40  EMMITSBURG_REV0P9   I9
  U4     AF42  VSS_AF42  EMMITSBURG_REV0P9   I9
  U4     AG5  VSS_AG5  EMMITSBURG_REV0P9   I9
  U4     AG13  VSS_AG13  EMMITSBURG_REV0P9   I9
  U4     AG19  VSS_AG19  EMMITSBURG_REV0P9   I9
  U4     AG24  VSS_AG24  EMMITSBURG_REV0P9   I9
  U4     AG39  VSS_AG39  EMMITSBURG_REV0P9   I9
  U4     AH8  VSS_AH8  EMMITSBURG_REV0P9   I9
  U4     AH31  VSS_AH31  EMMITSBURG_REV0P9   I9
  U4     AJ5  VSS_AJ5  EMMITSBURG_REV0P9   I9
  U4     AJ19  VSS_AJ19  EMMITSBURG_REV0P9   I9
  U4     AJ24  VSS_AJ24  EMMITSBURG_REV0P9   I9
  U4     AJ29  VSS_AJ29  EMMITSBURG_REV0P9   I9
  U4     AJ36  VSS_AJ36  EMMITSBURG_REV0P9   I9
  U4     AJ39  VSS_AJ39  EMMITSBURG_REV0P9   I9
  U4     AK2  VSS_AK2  EMMITSBURG_REV0P9   I9
  U4     AK4  VSS_AK4  EMMITSBURG_REV0P9   I9
  U4     AK11  VSS_AK11  EMMITSBURG_REV0P9   I9
  U4     AK37  VSS_AK37  EMMITSBURG_REV0P9   I9
  U4     AL19  VSS_AL19  EMMITSBURG_REV0P9   I9
  U4     AL24  VSS_AL24  EMMITSBURG_REV0P9   I9
  U4     AL27  VSS_AL27  EMMITSBURG_REV0P9   I9
  U4     AL29  VSS_AL29  EMMITSBURG_REV0P9   I9
  U4     AL39  VSS_AL39  EMMITSBURG_REV0P9   I9
  U4     AM8  VSS_AM8  EMMITSBURG_REV0P9   I9
  U4     AM15  VSS_AM15  EMMITSBURG_REV0P9   I9
  U4     AM31  VSS_AM31  EMMITSBURG_REV0P9   I9
  U4     AN13  VSS_AN13  EMMITSBURG_REV0P9   I9
  U4     AN16  VSS_AN16  EMMITSBURG_REV0P9   I9
  U4     AN29  VSS_AN29  EMMITSBURG_REV0P9   I9
  U4     AN32  VSS_AN32  EMMITSBURG_REV0P9   I9
  U4     AP5  VSS_AP5  EMMITSBURG_REV0P9   I9
  U4     AP11  VSS_AP11  EMMITSBURG_REV0P9   I9
  U4     AP18  VSS_AP18  EMMITSBURG_REV0P9   I9
  U4     AP24  VSS_AP24  EMMITSBURG_REV0P9   I9
  U4     AP28  VSS_AP28  EMMITSBURG_REV0P9   I9
  U4     AP37  VSS_AP37  EMMITSBURG_REV0P9   I9
  U4     AP39  VSS_AP39  EMMITSBURG_REV0P9   I9
  U4     AR20  VSS_AR20  EMMITSBURG_REV0P9   I9
  U4     AR32  VSS_AR32  EMMITSBURG_REV0P9   I9
  U4     AT5  VSS_AT5  EMMITSBURG_REV0P9   I9
  U4     AT8  VSS_AT8  EMMITSBURG_REV0P9   I9
  U4     AT11  VSS_AT11  EMMITSBURG_REV0P9   I9
  U4     AT15  VSS_AT15  EMMITSBURG_REV0P9   I9
  U4     AT21  VSS_AT21  EMMITSBURG_REV0P9   I9
  U4     AT24  VSS_AT24  EMMITSBURG_REV0P9   I9
  U4     AT28  VSS_AT28  EMMITSBURG_REV0P9   I9
  U4     AT31  VSS_AT31  EMMITSBURG_REV0P9   I9
  U4     AT34  VSS_AT34  EMMITSBURG_REV0P9   I9
  U4     AT39  VSS_AT39  EMMITSBURG_REV0P9   I9
  U4     AU20  VSS_AU20  EMMITSBURG_REV0P9   I9
  U4     AU23  VSS_AU23  EMMITSBURG_REV0P9   I9
  U4     AU26  VSS_AU26  EMMITSBURG_REV0P9   I9
  U4     AU29  VSS_AU29  EMMITSBURG_REV0P9   I9
  U4     AU32  VSS_AU32  EMMITSBURG_REV0P9   I9
  U4     AU36  VSS_AU36  EMMITSBURG_REV0P9   I9
  U4     AV5  VSS_AV5  EMMITSBURG_REV0P9   I9
  U4     AV8  VSS_AV8  EMMITSBURG_REV0P9   I9
  U4     AV37  VSS_AV37  EMMITSBURG_REV0P9   I9
  U4     AV39  VSS_AV39  EMMITSBURG_REV0P9   I9
  U4     AW7  VSS_AW7  EMMITSBURG_REV0P9   I9
  U4     AY3  VSS_AY3  EMMITSBURG_REV0P9   I7
  U4     AY5  VSS_AY5  EMMITSBURG_REV0P9   I7
  U4     AY8  VSS_AY8  EMMITSBURG_REV0P9   I7
  U4     AY11  VSS_AY11  EMMITSBURG_REV0P9   I9
  U4     AY15  VSS_AY15  EMMITSBURG_REV0P9   I9
  U4     AY18  VSS_AY18  EMMITSBURG_REV0P9   I9
  U4     AY21  VSS_AY21  EMMITSBURG_REV0P9   I9
  U4     AY24  VSS_AY24  EMMITSBURG_REV0P9   I9
  U4     AY28  VSS_AY28  EMMITSBURG_REV0P9   I7
  U4     AY31  VSS_AY31  EMMITSBURG_REV0P9   I7
  U4     AY34  VSS_AY34  EMMITSBURG_REV0P9   I7
  U4     AY37  VSS_AY37  EMMITSBURG_REV0P9   I7
  U4     AY39  VSS_AY39  EMMITSBURG_REV0P9   I7
  U4      B9  VSS_B9  EMMITSBURG_REV0P9   I7
  U4     B13  VSS_B13  EMMITSBURG_REV0P9   I7
  U4     B29  VSS_B29  EMMITSBURG_REV0P9   I7
  U4     B39  VSS_B39  EMMITSBURG_REV0P9   I7
  U4     BB1  VSS_BB1  EMMITSBURG_REV0P9   I9
  U4     BB5  VSS_BB5  EMMITSBURG_REV0P9   I7
  U4     BB39  VSS_BB39  EMMITSBURG_REV0P9   I7
  U4     BC2  VSS_BC2  EMMITSBURG_REV0P9   I9
  U4     BC6  VSS_BC6  EMMITSBURG_REV0P9   I7
  U4     BC8  VSS_BC8  EMMITSBURG_REV0P9   I7
  U4     BC10  VSS_BC10  EMMITSBURG_REV0P9   I7
  U4     BC12  VSS_BC12  EMMITSBURG_REV0P9   I7
  U4     BC14  VSS_BC14  EMMITSBURG_REV0P9   I7
  U4     BC16  VSS_BC16  EMMITSBURG_REV0P9   I7
  U4     BC18  VSS_BC18  EMMITSBURG_REV0P9   I7
  U4     BC20  VSS_BC20  EMMITSBURG_REV0P9   I7
  U4     BC22  VSS_BC22  EMMITSBURG_REV0P9   I7
  U4     BC24  VSS_BC24  EMMITSBURG_REV0P9   I7
  U4     BC26  VSS_BC26  EMMITSBURG_REV0P9   I7
  U4     BC28  VSS_BC28  EMMITSBURG_REV0P9   I7
  U4     BC30  VSS_BC30  EMMITSBURG_REV0P9   I7
  U4     BC32  VSS_BC32  EMMITSBURG_REV0P9   I7
  U4     BC34  VSS_BC34  EMMITSBURG_REV0P9   I7
  U4     BC36  VSS_BC36  EMMITSBURG_REV0P9   I7
  U4     BC38  VSS_BC38  EMMITSBURG_REV0P9   I7
  U4     BC42  VSS_BC42  EMMITSBURG_REV0P9   I9
  U4     BD1  VSS_BD1  EMMITSBURG_REV0P9   I9
  U4     BD3  VSS_BD3  EMMITSBURG_REV0P9   I9
  U4     BD5  VSS_BD5  EMMITSBURG_REV0P9   I7
  U4     BD21  VSS_BD21  EMMITSBURG_REV0P9   I7
  U4     BD39  VSS_BD39  EMMITSBURG_REV0P9   I7
  U4     BD41  VSS_BD41  EMMITSBURG_REV0P9   I9
  U4     BD43  VSS_BD43  EMMITSBURG_REV0P9   I9
  U4     BE1  VSS_BE1  EMMITSBURG_REV0P9   I9
  U4     BE3  VSS_BE3  EMMITSBURG_REV0P9   I9
  U4     BE10  VSS_BE10  EMMITSBURG_REV0P9   I7
  U4     BE34  VSS_BE34  EMMITSBURG_REV0P9   I7
  U4     BE41  VSS_BE41  EMMITSBURG_REV0P9   I9
  U4     BE43  VSS_BE43  EMMITSBURG_REV0P9   I9
  U4     BF21  VSS_BF21  EMMITSBURG_REV0P9   I7
  U4     BG4  VSS_BG4  EMMITSBURG_REV0P9   I9
  U4     BG6  VSS_BG6  EMMITSBURG_REV0P9   I9
  U4     BG10  VSS_BG10  EMMITSBURG_REV0P9   I7
  U4     BG34  VSS_BG34  EMMITSBURG_REV0P9   I7
  U4     BG38  VSS_BG38  EMMITSBURG_REV0P9   I9
  U4     BG40  VSS_BG40  EMMITSBURG_REV0P9  I11
  U4     BG41  VSS_BG41  EMMITSBURG_REV0P9   I9
  U4      C3  VSS_C3  EMMITSBURG_REV0P9   I9
  U4      C4  VSS_C4  EMMITSBURG_REV0P9   I7
  U4     C20  VSS_C20  EMMITSBURG_REV0P9   I7
  U4     C22  VSS_C22  EMMITSBURG_REV0P9   I7
  U4     C24  VSS_C24  EMMITSBURG_REV0P9   I7
  U4     C26  VSS_C26  EMMITSBURG_REV0P9   I7
  U4     C38  VSS_C38  EMMITSBURG_REV0P9   I7
  U4     C41  VSS_C41  EMMITSBURG_REV0P9   I9
  U4     C43  VSS_C43  EMMITSBURG_REV0P9   I9
  U4      D1  VSS_D1  EMMITSBURG_REV0P9   I9
  U4      D3  VSS_D3  EMMITSBURG_REV0P9   I9
  U4      D5  VSS_D5  EMMITSBURG_REV0P9   I7
  U4      D9  VSS_D9  EMMITSBURG_REV0P9   I7
  U4     D13  VSS_D13  EMMITSBURG_REV0P9   I7
  U4     D29  VSS_D29  EMMITSBURG_REV0P9   I7
  U4     D41  VSS_D41  EMMITSBURG_REV0P9   I9
  U4     D43  VSS_D43  EMMITSBURG_REV0P9   I9
  U4      E2  VSS_E2  EMMITSBURG_REV0P9   I9
  U4      E6  VSS_E6  EMMITSBURG_REV0P9   I7
  U4      E8  VSS_E8  EMMITSBURG_REV0P9   I7
  U4     E10  VSS_E10  EMMITSBURG_REV0P9   I7
  U4     E12  VSS_E12  EMMITSBURG_REV0P9   I7
  U4     E14  VSS_E14  EMMITSBURG_REV0P9   I7
  U4     E16  VSS_E16  EMMITSBURG_REV0P9   I7
  U4     E18  VSS_E18  EMMITSBURG_REV0P9   I7
  U4     E20  VSS_E20  EMMITSBURG_REV0P9   I7
  U4     E22  VSS_E22  EMMITSBURG_REV0P9   I7
  U4     E24  VSS_E24  EMMITSBURG_REV0P9   I7
  U4     E26  VSS_E26  EMMITSBURG_REV0P9   I7
  U4     E28  VSS_E28  EMMITSBURG_REV0P9   I7
  U4     E30  VSS_E30  EMMITSBURG_REV0P9   I7
  U4     E32  VSS_E32  EMMITSBURG_REV0P9   I7
  U4     E34  VSS_E34  EMMITSBURG_REV0P9   I7
  U4     E36  VSS_E36  EMMITSBURG_REV0P9   I7
  U4     E38  VSS_E38  EMMITSBURG_REV0P9   I7
  U4     E40  VSS_E40  EMMITSBURG_REV0P9   I7
  U4     E42  VSS_E42  EMMITSBURG_REV0P9   I9
  U4     F15  VSS_F15  EMMITSBURG_REV0P9   I7
  U4     F24  VSS_F24  EMMITSBURG_REV0P9   I7
  U4     F31  VSS_F31  EMMITSBURG_REV0P9   I7
  U4     F34  VSS_F34  EMMITSBURG_REV0P9   I7
  U4     F39  VSS_F39  EMMITSBURG_REV0P9   I7
  U4     F41  VSS_F41  EMMITSBURG_REV0P9   I7
  U4     F43  VSS_F43  EMMITSBURG_REV0P9   I9
  U4     G13  VSS_G13  EMMITSBURG_REV0P9   I7
  U4     G20  VSS_G20  EMMITSBURG_REV0P9   I7
  U4     G26  VSS_G26  EMMITSBURG_REV0P9   I7
  U4      H5  VSS_H5  EMMITSBURG_REV0P9   I7
  U4      H8  VSS_H8  EMMITSBURG_REV0P9   I7
  U4     H39  VSS_H39  EMMITSBURG_REV0P9   I7
  U4     J13  VSS_J13  EMMITSBURG_REV0P9   I7
  U4     J20  VSS_J20  EMMITSBURG_REV0P9   I7
  U4     J26  VSS_J26  EMMITSBURG_REV0P9   I7
  U4      K5  VSS_K5  EMMITSBURG_REV0P9   I7
  U4     K11  VSS_K11  EMMITSBURG_REV0P9   I7
  U4     K15  VSS_K15  EMMITSBURG_REV0P9   I7
  U4     K24  VSS_K24  EMMITSBURG_REV0P9   I7
  U4     K34  VSS_K34  EMMITSBURG_REV0P9   I7
  U4     K39  VSS_K39  EMMITSBURG_REV0P9   I7
  U4     L10  VSS_L10  EMMITSBURG_REV0P9   I7
  U4     L16  VSS_L16  EMMITSBURG_REV0P9   I7
  U4     L20  VSS_L20  EMMITSBURG_REV0P9   I7
  U4     L23  VSS_L23  EMMITSBURG_REV0P9   I7
  U4     L26  VSS_L26  EMMITSBURG_REV0P9   I7
  U4     L29  VSS_L29  EMMITSBURG_REV0P9   I7
  U4     L36  VSS_L36  EMMITSBURG_REV0P9   I7
  U4      M1  VSS_M1  EMMITSBURG_REV0P9   I7
  U4      M3  VSS_M3  EMMITSBURG_REV0P9   I7
  U4      M5  VSS_M5  EMMITSBURG_REV0P9   I7
  U4     M11  VSS_M11  EMMITSBURG_REV0P9   I7
  U4     M15  VSS_M15  EMMITSBURG_REV0P9   I7
  U4     M18  VSS_M18  EMMITSBURG_REV0P9   I7
  U4     M21  VSS_M21  EMMITSBURG_REV0P9   I7
  U4     M28  VSS_M28  EMMITSBURG_REV0P9   I7
  U4     M31  VSS_M31  EMMITSBURG_REV0P9   I7
  U4     M34  VSS_M34  EMMITSBURG_REV0P9   I7
  U4     M37  VSS_M37  EMMITSBURG_REV0P9   I7
  U4     M39  VSS_M39  EMMITSBURG_REV0P9   I7
  U4     N16  VSS_N16  EMMITSBURG_REV0P9   I7
  U4     N32  VSS_N32  EMMITSBURG_REV0P9   I7
  U4      P5  VSS_P5  EMMITSBURG_REV0P9   I7
  U4      P8  VSS_P8  EMMITSBURG_REV0P9   I7
  U4     P11  VSS_P11  EMMITSBURG_REV0P9   I7
  U4     P24  VSS_P24  EMMITSBURG_REV0P9   I7
  U4     P28  VSS_P28  EMMITSBURG_REV0P9   I7
  U4     P31  VSS_P31  EMMITSBURG_REV0P9   I7
  U4     P37  VSS_P37  EMMITSBURG_REV0P9   I7
  U4     P39  VSS_P39  EMMITSBURG_REV0P9   I7
  U4     P41  VSS_P41  EMMITSBURG_REV0P9   I7
  U4     P43  VSS_P43  EMMITSBURG_REV0P9   I7
  U4     R13  VSS_R13  EMMITSBURG_REV0P9   I7
  U4     R16  VSS_R16  EMMITSBURG_REV0P9   I7
  U4     R20  VSS_R20  EMMITSBURG_REV0P9   I7
  U4     R36  VSS_R36  EMMITSBURG_REV0P9   I7
  U4     T31  VSS_T31  EMMITSBURG_REV0P9   I7
  U4      U5  VSS_U5  EMMITSBURG_REV0P9   I7
  U4     U10  VSS_U10  EMMITSBURG_REV0P9   I7
  U4     U13  VSS_U13  EMMITSBURG_REV0P9   I7
  U4     U25  VSS_U25  EMMITSBURG_REV0P9   I7
  U4     U39  VSS_U39  EMMITSBURG_REV0P9   I7
  U4      V2  VSS_V2  EMMITSBURG_REV0P9   I7
  U4     V31  VSS_V31  EMMITSBURG_REV0P9   I7
  U4      W3  VSS_W3  EMMITSBURG_REV0P9   I7
  U4      W5  VSS_W5  EMMITSBURG_REV0P9   I7
  U4     W25  VSS_W25  EMMITSBURG_REV0P9   I7
  U4     W39  VSS_W39  EMMITSBURG_REV0P9   I7
  U4      Y8  VSS_Y8  EMMITSBURG_REV0P9   I7
  U4     Y11  VSS_Y11  EMMITSBURG_REV0P9   I7
  U4     Y15  VSS_Y15  EMMITSBURG_REV0P9   I7
  U4     Y31  VSS_Y31  EMMITSBURG_REV0P9   I7
  U4     Y34  VSS_Y34  EMMITSBURG_REV0P9   I7
  U10      8    GND  PCA9546APWR  I194
  U13    A14  GNDXTAL  9SQ440NQQI8  I180
  U13    B10   GNDS  9SQ440NQQI8  I180
  U13    B12  NVGND  9SQ440NQQI8  I180
  U13     C1   EPAD  9SQ440NQQI8  I180
  U14      8    GND  IDTQS3VH257QG  I17
  U15      8    GND  IDTQS3VH257QG  I25
  U16      3    GND  NC7SZ66M5X  I88
  U17      7    GND  74CBTLV3126PW  I80
  U18      7    GND  74CBTLV3126PW  I129
  U19      S  SOURCE  MOSFET_N    I34
  U21      2    GND  NC7SB3157   I58
  U22      2    GND  NC7SB3157   I71
  U23      3    GND  74LVC1G02GW  I96
  U24     12    VSS  PCA9548APW  I60
  U27      2    GND  TPS2553DBVR1  I24
  U28      4    GND  PCA9617ADP  I39
  U29      4    GND  PCA9617ADP  I43
  U30      4    GND  PCA9617ADP  I28
  U31      4    GND  PCA9617ADP  I37
  U36      8    GND  PCA9546APWR  I179
  U38     TH   EPAD  9QXL2001BNHGI8  I119
  U40      8    GND  TPS259520DSGR  I42
  U40     TH  TH_GND  TPS259520DSGR  I42
  U49      S  SOURCE  MOSFET_N    I177
  U50      3    GND  SN74LVC1G08DBVR  I175
  U51     12    VSS  PCA9555PW   I125
  U52      1    GND  APX80929SAG7  I161
  U53      3    GND  SN74LVC1G08DBVR  I150
  U54      3    GND  74LVC1G07GV  I165
  U56      8    GND  TPS259520DSGR  I350
  U56     TH  TH_GND  TPS259520DSGR  I350
  U57      4  GND_1  TPS259824ONRGER  I377
  U57      5  GND_2  TPS259824ONRGER  I377
  U57     14  GND_3  TPS259824ONRGER  I377
  U57     26  GND_TH2  TPS259824ONRGER  I377
  U58      2    GND  SN74LVC2G07DCKR  I397
  U59      2    GND  SN74LVC2G07DCKR  I400
  U60      2    GND  NC7SB3157   I34
  U61      2    GND  NC7SB3157   I39
  U63      4    GND  TMP75AIDR    I1
  U64      4    VSS  M24128BWDW6TP  I35
  U65      4    GND  TMP75AIDR   I84
  U66      3    GND  74HC1G126GW  I53
  U67      7    GND  74CBTLV3126PW   I1
  U68      7    GND  74CBTLV3126PW   I2
  U70      S  SOURCE  MOSFET_N    I19
  U75      3    GND  SN74LVC1G17DCKR   I1
  U77      7    GND  74CBTLV3126PW  I105
  U79      4    GND  SLG55221120010VTR  I62
  U79     TH     TH  SLG55221120010VTR  I62
  U81      6    NC1  MP5981GLUZ  I66
  U81      7    NC2  MP5981GLUZ  I66
  U81     17    NC3  MP5981GLUZ  I66
  U81     20    GND  MP5981GLUZ  I66
  U81     TH  VIN_TH  MP5981GLUZ  I66
  U82      3    GND  74LVC1G126GW  I35
  U83      7  GND_0  GTL2014PW   I45
  U83      8  GND_1  GTL2014PW   I45
  U83     11  GND_2  GTL2014PW   I45
  U84      7  GND_0  GTL2014PW   I18
  U84      8  GND_1  GTL2014PW   I18
  U84     11  GND_2  GTL2014PW   I18
  U85      2    GND  NC7SB3157   I109
  U86      7    GND  74CBTLV3126PW  I84
  U89      S  SOURCE  MOSFET_N    I236
  U90      4    GND  PI6CV304LE  I46
  U94      2    GND  ADM1086AKSZREEL7   I1
  U95      3    GND  SN74LVC1G07DCKR  I41
  U96      5    GND  TS3A24157RSER  I68
  U97      5    GND  TS3A24157RSER  I38
  U98      1    GND  PCA9306DCTR  I27
  U99      2    GND  RT9818C44GV  I70
  U101     3    GND  SN74LVC1G17DCKR  I205
  U102     1   GND0  MAX9634FEUKT  I17
  U102     2   GND1  MAX9634FEUKT  I17
  U103     1   GND0  MAX9634FEUKT  I12
  U103     2   GND1  MAX9634FEUKT  I12
  U104     3    GND  74LVC1G07GV  I63
  U105     3    GND  ADS1015IDGSR   I1
  U107     6    NC1  MP5981GLUZ  I113
  U107     7    NC2  MP5981GLUZ  I113
  U107    17    NC3  MP5981GLUZ  I113
  U107    20    GND  MP5981GLUZ  I113
  U107    TH  VIN_TH  MP5981GLUZ  I113
  U117     2    GND  TPS3897PDRYR  I37
  U121     7    GND  MAX11607EUAT  I48
  U122    A1  GND_32  10M04SAU324I7G  I165
  U122   A18  GND_31  10M04SAU324I7G  I165
  U122    B6  GND_28  10M04SAU324I7G  I165
  U122   B10  GND_30  10M04SAU324I7G  I165
  U122   B15  GND_29  10M04SAU324I7G  I165
  U122    D3  GND_27  10M04SAU324I7G  I165
  U122    E3  REFGND  10M04SAU324I7G  I165
  U122    E6  GND_24  10M04SAU324I7G  I165
  U122   E10  GND_26  10M04SAU324I7G  I165
  U122   E13  GND_25  10M04SAU324I7G  I165
  U122    F8  GND_22  10M04SAU324I7G  I165
  U122   F17  GND_23  10M04SAU324I7G  I165
  U122    G2  GND_21  10M04SAU324I7G  I165
  U122    G4  GND_20  10M04SAU324I7G  I165
  U122   H14  GND_19  10M04SAU324I7G  I165
  U122   J10  GND_18  10M04SAU324I7G  I165
  U122   J17  GND_17  10M04SAU324I7G  I165
  U122    K6  GND_15  10M04SAU324I7G  I165
  U122    K9  GND_14  10M04SAU324I7G  I165
  U122   K13  GND_16  10M04SAU324I7G  I165
  U122    L4  GND_13  10M04SAU324I7G  I165
  U122   M14  GND_12  10M04SAU324I7G  I165
  U122    N2  GND_8  10M04SAU324I7G  I165
  U122    N5  GND_7  10M04SAU324I7G  I165
  U122   N10  GND_11  10M04SAU324I7G  I165
  U122   N12  GND_10  10M04SAU324I7G  I165
  U122   N17  GND_9  10M04SAU324I7G  I165
  U122    R7  GND_6  10M04SAU324I7G  I165
  U122    U4  GND_3  10M04SAU324I7G  I165
  U122   U10  GND_5  10M04SAU324I7G  I165
  U122   U14  GND_4  10M04SAU324I7G  I165
  U122    V1  GND_2  10M04SAU324I7G  I165
  U122   V18  GND_1  10M04SAU324I7G  I165
  U123     8    GND  TPS259520DSGR   I8
  U123    TH  TH_GND  TPS259520DSGR   I8
  U124     8    GND  TPS259520DSGR  I59
  U124    TH  TH_GND  TPS259520DSGR  I59
  U125     8    GND  TPS259520DSGR  I25
  U125    TH  TH_GND  TPS259520DSGR  I25
  U126     8    GND  TPS259540DSGR  I156
  U126    TH  TH_GND  TPS259540DSGR  I156
  U127     8    GND  TPS259540DSGR  I159
  U127    TH  TH_GND  TPS259540DSGR  I159
  U128     8    GND  TPS259540DSGR  I157
  U128    TH  TH_GND  TPS259540DSGR  I157
  U129     8    GND  TPS259540DSGR  I158
  U129    TH  TH_GND  TPS259540DSGR  I158
  U130    12    VSS  PCA9555PW    I1
  U131    12    VSS  PCA9555PW   I51
  U132     2    GND  SN74LVC2G17DCKR  I80
  U133     2    GND  SN74LVC2G17DCKR  I93
  U134     2    GND  SN74LVC2G07DCKR   I1
  U135     2    GND  SN74LVC2G07DCKR  I24
  U136     2    GND  SN74LVC2G07DCKR  I46
  U137     2    GND  SN74LVC2G07DCKR  I48
  U138     8    GND  TPS259540DSGR  I52
  U138    TH  TH_GND  TPS259540DSGR  I52
  U141     8    GND  PCA9546APWR  I91
  Y2       2      2  Q_XTAL_4P_13  I185
  Y2       4      4  Q_XTAL_4P_13  I185
  Y3       2     G1  Q_XTAL_4P_13BI_24GND  I75
  Y3       4     G2  Q_XTAL_4P_13BI_24GND  I75

HP_LVC3_OCP_V3_1_ATTN_OUT_SW_N   @S9S_MB_2U_LIB.S9S_MB_2U(SCH_1):HP_LVC3_OCP_V3_1_ATTN_OUT_SW_N
  R1147    2      B  Q_RES       I375
  R1149    2      B  Q_RES       I367
  U51      7    P03  PCA9555PW   I125

HP_LVC3_OCP_V3_1_EN   @S9S_MB_2U_LIB.S9S_MB_2U(SCH_1):HP_LVC3_OCP_V3_1_EN
  U50      4      Y  SN74LVC1G08DBVR  I175
  U56      2  EN||UVLO  TPS259520DSGR  I350
  U57      6  EN||UVLO  TPS259824ONRGER  I377

HP_LVC3_OCP_V3_1_FAULT_N   @S9S_MB_2U_LIB.S9S_MB_2U(SCH_1):HP_LVC3_OCP_V3_1_FAULT_N
  R1143    2      B  Q_RES       I343
  U51      9    P05  PCA9555PW   I125
  U56      6   FLT#  TPS259520DSGR  I350

HP_LVC3_OCP_V3_1_HSC_PWRGD   @S9S_MB_2U_LIB.S9S_MB_2U(SCH_1):HP_LVC3_OCP_V3_1_HSC_PWRGD
  Q45      2     G1  MOSFET_NCH_DUAL  I180
  R429     1      A  Q_RES       I344
  R1146    2      B  Q_RES       I358
  U57     13     PG  TPS259824ONRGER  I377

HP_LVC3_OCP_V3_1_PRSNT2   @S9S_MB_2U_LIB.S9S_MB_2U(SCH_1):HP_LVC3_OCP_V3_1_PRSNT2
  R1129    2      B  Q_RES       I172
  U49      D  DRAIN  MOSFET_N    I177
  U50      2      A  SN74LVC1G08DBVR  I175

HP_LVC3_OCP_V3_1_PRSNT2_N   @S9S_MB_2U_LIB.S9S_MB_2U(SCH_1):HP_LVC3_OCP_V3_1_PRSNT2_N
  R112     2      B  Q_RES       I413
  R1148    2      B  Q_RES       I376
  R1150    2      B  Q_RES       I368
  R1543    1      A  Q_RES       I411
  U49      G   GATE  MOSFET_N    I177
  U51      8    P04  PCA9555PW   I125

HP_LVC3_OCP_V3_1_PRSNT2_N_R   @S9S_MB_2U_LIB.S9S_MB_2U(SCH_1):HP_LVC3_OCP_V3_1_PRSNT2_N_R
  R1147    1      A  Q_RES       I375
  R1148    1      A  Q_RES       I376
  U58      4     2Y  SN74LVC2G07DCKR  I397
  U58      6     1Y  SN74LVC2G07DCKR  I397
  U59      4     2Y  SN74LVC2G07DCKR  I400
  U59      6     1Y  SN74LVC2G07DCKR  I400

HP_LVC3_OCP_V3_1_PWRGD   @S9S_MB_2U_LIB.S9S_MB_2U(SCH_1):HP_LVC3_OCP_V3_1_PWRGD
  Q45      3     D2  MOSFET_NCH_DUAL  I181
  R1132    2      B  Q_RES       I153
  U52      2  RESET_L  APX80929SAG7  I161
  U53      1      B  SN74LVC1G08DBVR  I150

HP_LVC3_OCP_V3_1_PWRGD_N   @S9S_MB_2U_LIB.S9S_MB_2U(SCH_1):HP_LVC3_OCP_V3_1_PWRGD_N
  Q45      5     G2  MOSFET_NCH_DUAL  I181
  Q45      6     D1  MOSFET_NCH_DUAL  I180
  R1133    2      B  Q_RES       I155

HP_OCP_V3_1_EN   @S9S_MB_2U_LIB.S9S_MB_2U(SCH_1):HP_OCP_V3_1_EN
  U50      1      B  SN74LVC1G08DBVR  I175
  U51      6    P02  PCA9555PW   I125

H_CPU0_BMCINIT_LVC1   @S9S_MB_2U_LIB.S9S_MB_2U(SCH_1):H_CPU0_BMCINIT_LVC1
  R278     2      B  Q_RES       I61
  U2     BN23  BMCINIT  SOCKET4677_AZIFS054P001C01  I57

H_CPU0_CATERR_LVC1_R_N   @S9S_MB_2U_LIB.S9S_MB_2U(SCH_1):H_CPU0_CATERR_LVC1_R_N
  R297     1      A  Q_RES       I23
  U2     BP24  CATERR_N  SOCKET4677_AZIFS054P001C01   I1

H_CPU0_ERR0_LVC1_R_N   @S9S_MB_2U_LIB.S9S_MB_2U(SCH_1):H_CPU0_ERR0_LVC1_R_N
  R336     1      A  Q_RES       I37
  U2     BF22  ERROR0_N  SOCKET4677_AZIFS054P001C01   I1

H_CPU0_ERR1_LVC1_R_N   @S9S_MB_2U_LIB.S9S_MB_2U(SCH_1):H_CPU0_ERR1_LVC1_R_N
  R340     1      A  Q_RES       I43
  U2     AY22  ERROR1_N  SOCKET4677_AZIFS054P001C01   I1

H_CPU0_ERR2_LVC1_R_N   @S9S_MB_2U_LIB.S9S_MB_2U(SCH_1):H_CPU0_ERR2_LVC1_R_N
  R344     1      A  Q_RES       I45
  U2     BD22  ERROR2_N  SOCKET4677_AZIFS054P001C01   I1

H_CPU0_MEMHOT_IN_LVC1_N   @S9S_MB_2U_LIB.S9S_MB_2U(SCH_1):H_CPU0_MEMHOT_IN_LVC1_N
  R208     2      B  Q_RES       I26
  R219     2      B  Q_RES       I54
  U2     AU21  MEMHOT_IN_N  SOCKET4677_AZIFS054P001C01   I1

H_CPU0_MEMHOT_IN_LVC1_R_N   @S9S_MB_2U_LIB.S9S_MB_2U(SCH_1):H_CPU0_MEMHOT_IN_LVC1_R_N
  R208     1      A  Q_RES       I26
  U122    T8  DIFFIO_RX_B8P  10M04SAU324I7G  I93

H_CPU0_MEMHOT_OUT_LVC1_N   @S9S_MB_2U_LIB.S9S_MB_2U(SCH_1):H_CPU0_MEMHOT_OUT_LVC1_N
  R203     2      B  Q_RES       I98
  R1425    1      A  Q_RES       I197
  U122    T9  DIFFIO_TX_RX_B16N  10M04SAU324I7G  I155

H_CPU0_MEMHOT_OUT_LVC1_R_N   @S9S_MB_2U_LIB.S9S_MB_2U(SCH_1):H_CPU0_MEMHOT_OUT_LVC1_R_N
  R199     2      B  Q_RES       I111
  R203     1      A  Q_RES       I98
  U2     CF26  MEMHOT_OUT_N  SOCKET4677_AZIFS054P001C01   I1

H_CPU0_MEMTRIP_LVC1_N   @S9S_MB_2U_LIB.S9S_MB_2U(SCH_1):H_CPU0_MEMTRIP_LVC1_N
  R205     2      B  Q_RES       I101
  R1429    1      A  Q_RES       I205
  U122    V4  DIFFIO_RX_B4P  10M04SAU324I7G  I93

H_CPU0_MEMTRIP_LVC1_R_N   @S9S_MB_2U_LIB.S9S_MB_2U(SCH_1):H_CPU0_MEMTRIP_LVC1_R_N
  R200     2      B  Q_RES       I102
  R205     1      A  Q_RES       I101
  U2     AV24  MEMTRIP_N  SOCKET4677_AZIFS054P001C01   I1

H_CPU0_MON_FAIL_LVC1_R_N   @S9S_MB_2U_LIB.S9S_MB_2U(SCH_1):H_CPU0_MON_FAIL_LVC1_R_N
  R100     1      A  Q_RES       I84
  R1956    1      A  Q_RES       I146
  U2     BR23  MON_FAIL_N  SOCKET4677_AZIFS054P001C01  I57

H_CPU0_MON_FAIL_PLD_LVC1_N   @S9S_MB_2U_LIB.S9S_MB_2U(SCH_1):H_CPU0_MON_FAIL_PLD_LVC1_N
  R100     2      B  Q_RES       I84
  U122    V5  DIFFIO_RX_B6P  10M04SAU324I7G  I93

H_CPU0_NMI_LVC1_N   @S9S_MB_2U_LIB.S9S_MB_2U(SCH_1):H_CPU0_NMI_LVC1_N
  R195     2      B  Q_RES       I49
  R197     2      B  Q_RES       I53
  U2     AV18    NMI  SOCKET4677_AZIFS054P001C01   I1

H_CPU0_PMDOWN_CPU1   @S9S_MB_2U_LIB.S9S_MB_2U(SCH_1):H_CPU0_PMDOWN_CPU1
  R11      1      A  Q_RES       I79
  U1     CN25  PMSYNC0  SOCKET4677_AZIFS054P001C01  I29

H_CPU0_PMDOWN_CPU1_R   @S9S_MB_2U_LIB.S9S_MB_2U(SCH_1):H_CPU0_PMDOWN_CPU1_R
  R11      2      B  Q_RES       I79
  U2     CW39  PMDOWN0  SOCKET4677_AZIFS054P001C01   I1

H_CPU0_PMDOWN_PCH   @S9S_MB_2U_LIB.S9S_MB_2U(SCH_1):H_CPU0_PMDOWN_PCH
  R7       2      B  Q_RES       I66
  U4     AE7  GPP_L_1_PM_DOWN_0  EMMITSBURG_REV0P9  I22

H_CPU0_PMDOWN_PCH_R   @S9S_MB_2U_LIB.S9S_MB_2U(SCH_1):H_CPU0_PMDOWN_PCH_R
  R7       1      A  Q_RES       I66
  R1959    2      B  Q_RES       I115

H_CPU0_PMDOWN_PCH_R2   @S9S_MB_2U_LIB.S9S_MB_2U(SCH_1):H_CPU0_PMDOWN_PCH_R2
  R1959    1      A  Q_RES       I115
  U2     CY40  PMDOWN_PCH  SOCKET4677_AZIFS054P001C01   I1

H_CPU0_PMSYNC_CPU1   @S9S_MB_2U_LIB.S9S_MB_2U(SCH_1):H_CPU0_PMSYNC_CPU1
  R322     2      B  Q_RES       I90
  U1     CW39  PMDOWN0  SOCKET4677_AZIFS054P001C01  I29

H_CPU0_PMSYNC_CPU1_R   @S9S_MB_2U_LIB.S9S_MB_2U(SCH_1):H_CPU0_PMSYNC_CPU1_R
  R322     1      A  Q_RES       I90
  U2     CN25  PMSYNC0  SOCKET4677_AZIFS054P001C01   I1

H_CPU0_PMSYNC_PCH   @S9S_MB_2U_LIB.S9S_MB_2U(SCH_1):H_CPU0_PMSYNC_PCH
  R10      2      B  Q_RES       I78
  U2     DA39  PMSYNC_PCH  SOCKET4677_AZIFS054P001C01   I1

H_CPU0_PMSYNC_PCH_R   @S9S_MB_2U_LIB.S9S_MB_2U(SCH_1):H_CPU0_PMSYNC_PCH_R
  R10      1      A  Q_RES       I78
  R1960    2      B  Q_RES       I117

H_CPU0_PMSYNC_PCH_R2   @S9S_MB_2U_LIB.S9S_MB_2U(SCH_1):H_CPU0_PMSYNC_PCH_R2
  R1960    1      A  Q_RES       I117
  U4     AF8  GPP_L_0_PM_SYNC_0  EMMITSBURG_REV0P9  I22

H_CPU0_PM_FAST_WAKE_N   @S9S_MB_2U_LIB.S9S_MB_2U(SCH_1):H_CPU0_PM_FAST_WAKE_N
  R1240    1      A  Q_RES        I9
  U2     CP20  PMFAST_WAKE_N  SOCKET4677_AZIFS054P001C01   I1

H_CPU0_PRDY_QS_GTL_R_N   @S9S_MB_2U_LIB.S9S_MB_2U(SCH_1):H_CPU0_PRDY_QS_GTL_R_N
  R1       2      B  Q_RES       I18
  U2     BP26  PRDY_N  SOCKET4677_AZIFS054P001C01  I57

H_CPU0_PREQ_QS_GTL_R_N   @S9S_MB_2U_LIB.S9S_MB_2U(SCH_1):H_CPU0_PREQ_QS_GTL_R_N
  R2       2      B  Q_RES       I16
  U2     AV22  PREQ_N  SOCKET4677_AZIFS054P001C01  I57

H_CPU0_PROCHOT_LVC1_N   @S9S_MB_2U_LIB.S9S_MB_2U(SCH_1):H_CPU0_PROCHOT_LVC1_N
  R239     2      B  Q_RES       I129
  R243     2      B  Q_RES       I171
  U2     AU19  PROCHOT_N  SOCKET4677_AZIFS054P001C01   I1

H_CPU0_PROCHOT_LVC1_R_N   @S9S_MB_2U_LIB.S9S_MB_2U(SCH_1):H_CPU0_PROCHOT_LVC1_R_N
  R239     1      A  Q_RES       I129
  U122    R6  DIFFIO_TX_RX_B5P  10M04SAU324I7G  I155

H_CPU0_RMCA_LVC1_R_N   @S9S_MB_2U_LIB.S9S_MB_2U(SCH_1):H_CPU0_RMCA_LVC1_R_N
  R302     1      A  Q_RES       I75
  U2     BH22  RMCA_N  SOCKET4677_AZIFS054P001C01   I1

H_CPU0_THERMTRIP_LVC1_N   @S9S_MB_2U_LIB.S9S_MB_2U(SCH_1):H_CPU0_THERMTRIP_LVC1_N
  R237     2      B  Q_RES       I69
  R241     2      B  Q_RES       I167
  R1427    1      A  Q_RES       I199
  U122   T10  DIFFIO_TX_RX_B16P  10M04SAU324I7G  I155

H_CPU0_THERMTRIP_LVC1_R_N   @S9S_MB_2U_LIB.S9S_MB_2U(SCH_1):H_CPU0_THERMTRIP_LVC1_R_N
  R237     1      A  Q_RES       I69
  U2     BL62  THERMTRIP_N  SOCKET4677_AZIFS054P001C01   I1

H_CPU1_BMCINIT_LVC1   @S9S_MB_2U_LIB.S9S_MB_2U(SCH_1):H_CPU1_BMCINIT_LVC1
  R264     2      B  Q_RES       I98
  U1     BN23  BMCINIT  SOCKET4677_AZIFS054P001C01  I51

H_CPU1_CATERR_LVC1_R_N   @S9S_MB_2U_LIB.S9S_MB_2U(SCH_1):H_CPU1_CATERR_LVC1_R_N
  R299     1      A  Q_RES       I63
  U1     BP24  CATERR_N  SOCKET4677_AZIFS054P001C01  I29

H_CPU1_ERR0_LVC1_R_N   @S9S_MB_2U_LIB.S9S_MB_2U(SCH_1):H_CPU1_ERR0_LVC1_R_N
  R337     1      A  Q_RES       I33
  U1     BF22  ERROR0_N  SOCKET4677_AZIFS054P001C01  I29

H_CPU1_ERR1_LVC1_R_N   @S9S_MB_2U_LIB.S9S_MB_2U(SCH_1):H_CPU1_ERR1_LVC1_R_N
  R341     1      A  Q_RES       I44
  U1     AY22  ERROR1_N  SOCKET4677_AZIFS054P001C01  I29

H_CPU1_ERR2_LVC1_R_N   @S9S_MB_2U_LIB.S9S_MB_2U(SCH_1):H_CPU1_ERR2_LVC1_R_N
  R345     1      A  Q_RES       I46
  U1     BD22  ERROR2_N  SOCKET4677_AZIFS054P001C01  I29

H_CPU1_MEMHOT_IN_LVC1_N   @S9S_MB_2U_LIB.S9S_MB_2U(SCH_1):H_CPU1_MEMHOT_IN_LVC1_N
  R210     2      B  Q_RES       I66
  R220     2      B  Q_RES       I63
  U1     AU21  MEMHOT_IN_N  SOCKET4677_AZIFS054P001C01  I29

H_CPU1_MEMHOT_IN_LVC1_R_N   @S9S_MB_2U_LIB.S9S_MB_2U(SCH_1):H_CPU1_MEMHOT_IN_LVC1_R_N
  R210     1      A  Q_RES       I66
  U122    V6   IO_3  10M04SAU324I7G  I155

H_CPU1_MEMHOT_OUT_LVC1_N   @S9S_MB_2U_LIB.S9S_MB_2U(SCH_1):H_CPU1_MEMHOT_OUT_LVC1_N
  R204     2      B  Q_RES       I100
  R1426    1      A  Q_RES       I198
  U122    V7  DIFFIO_RX_B11P  10M04SAU324I7G  I93

H_CPU1_MEMHOT_OUT_LVC1_R_N   @S9S_MB_2U_LIB.S9S_MB_2U(SCH_1):H_CPU1_MEMHOT_OUT_LVC1_R_N
  R201     2      B  Q_RES       I108
  R204     1      A  Q_RES       I100
  U1     CF26  MEMHOT_OUT_N  SOCKET4677_AZIFS054P001C01  I29

H_CPU1_MEMTRIP_LVC1_N   @S9S_MB_2U_LIB.S9S_MB_2U(SCH_1):H_CPU1_MEMTRIP_LVC1_N
  R206     2      B  Q_RES       I99
  R1430    1      A  Q_RES       I203
  U122    V8  DIFFIO_RX_B13P  10M04SAU324I7G  I93

H_CPU1_MEMTRIP_LVC1_R_N   @S9S_MB_2U_LIB.S9S_MB_2U(SCH_1):H_CPU1_MEMTRIP_LVC1_R_N
  R202     2      B  Q_RES       I110
  R206     1      A  Q_RES       I99
  U1     AV24  MEMTRIP_N  SOCKET4677_AZIFS054P001C01  I29

H_CPU1_MON_FAIL_LVC1_R_N   @S9S_MB_2U_LIB.S9S_MB_2U(SCH_1):H_CPU1_MON_FAIL_LVC1_R_N
  R104     1      A  Q_RES       I108
  R1957    1      A  Q_RES       I148
  U1     BR23  MON_FAIL_N  SOCKET4677_AZIFS054P001C01  I51

H_CPU1_MON_FAIL_PLD_LVC1_N   @S9S_MB_2U_LIB.S9S_MB_2U(SCH_1):H_CPU1_MON_FAIL_PLD_LVC1_N
  R104     2      B  Q_RES       I108
  U122    M8  DIFFIO_TX_RX_B14N  10M04SAU324I7G  I155

H_CPU1_NMI_LVC1_N   @S9S_MB_2U_LIB.S9S_MB_2U(SCH_1):H_CPU1_NMI_LVC1_N
  R196     2      B  Q_RES       I57
  R198     2      B  Q_RES       I54
  U1     AV18    NMI  SOCKET4677_AZIFS054P001C01  I29

H_CPU1_PM_FAST_WAKE_N   @S9S_MB_2U_LIB.S9S_MB_2U(SCH_1):H_CPU1_PM_FAST_WAKE_N
  R1245    2      B  Q_RES       I10
  U1     CP20  PMFAST_WAKE_N  SOCKET4677_AZIFS054P001C01  I29

H_CPU1_PRDY_QS_GTL_R_N   @S9S_MB_2U_LIB.S9S_MB_2U(SCH_1):H_CPU1_PRDY_QS_GTL_R_N
  R61      2      B  Q_RES       I16
  U1     BP26  PRDY_N  SOCKET4677_AZIFS054P001C01  I51

H_CPU1_PREQ_QS_GTL_R_N   @S9S_MB_2U_LIB.S9S_MB_2U(SCH_1):H_CPU1_PREQ_QS_GTL_R_N
  R62      2      B  Q_RES       I11
  U1     AV22  PREQ_N  SOCKET4677_AZIFS054P001C01  I51

H_CPU1_PROCHOT_LVC1_N   @S9S_MB_2U_LIB.S9S_MB_2U(SCH_1):H_CPU1_PROCHOT_LVC1_N
  R240     2      B  Q_RES       I151
  R244     2      B  Q_RES       I173
  U1     AU19  PROCHOT_N  SOCKET4677_AZIFS054P001C01  I29

H_CPU1_PROCHOT_LVC1_R_N   @S9S_MB_2U_LIB.S9S_MB_2U(SCH_1):H_CPU1_PROCHOT_LVC1_R_N
  R240     1      A  Q_RES       I151
  U122    P5  DIFFIO_TX_RX_B3P  10M04SAU324I7G  I155

H_CPU1_RMCA_LVC1_R_N   @S9S_MB_2U_LIB.S9S_MB_2U(SCH_1):H_CPU1_RMCA_LVC1_R_N
  R304     1      A  Q_RES       I72
  U1     BH22  RMCA_N  SOCKET4677_AZIFS054P001C01  I16

H_CPU1_THERMTRIP_LVC1_N   @S9S_MB_2U_LIB.S9S_MB_2U(SCH_1):H_CPU1_THERMTRIP_LVC1_N
  R238     2      B  Q_RES       I80
  R242     2      B  Q_RES       I169
  R1428    1      A  Q_RES       I202
  U122    P6  DIFFIO_TX_RX_B3N  10M04SAU324I7G  I155

H_CPU1_THERMTRIP_LVC1_R_N   @S9S_MB_2U_LIB.S9S_MB_2U(SCH_1):H_CPU1_THERMTRIP_LVC1_R_N
  R238     1      A  Q_RES       I80
  U1     BL62  THERMTRIP_N  SOCKET4677_AZIFS054P001C01  I29

H_CPU_CATERR_LVC1_R_N   @S9S_MB_2U_LIB.S9S_MB_2U(SCH_1):H_CPU_CATERR_LVC1_R_N
  R296     2      B  Q_RES       I65
  R297     2      B  Q_RES       I23
  R298     2      B  Q_RES       I67
  R299     2      B  Q_RES       I63
  U122    T5  DIFFIO_TX_RX_B7N  10M04SAU324I7G  I155

H_CPU_ERR0_LVC1_N   @S9S_MB_2U_LIB.S9S_MB_2U(SCH_1):H_CPU_ERR0_LVC1_N
  R338     2      B  Q_RES       I91
  R1431    1      A  Q_RES       I213
  U122    T6  DIFFIO_TX_RX_B7P  10M04SAU324I7G  I155

H_CPU_ERR0_LVC1_R_N   @S9S_MB_2U_LIB.S9S_MB_2U(SCH_1):H_CPU_ERR0_LVC1_R_N
  R336     2      B  Q_RES       I37
  R337     2      B  Q_RES       I33
  R338     1      A  Q_RES       I91
  R339     1      A  Q_RES       I94

H_CPU_ERR0_PCH_R_N   @S9S_MB_2U_LIB.S9S_MB_2U(SCH_1):H_CPU_ERR0_PCH_R_N
  R339     2      B  Q_RES       I94
  R1260    2      B  Q_RES       I17
  U4      J7  CPU_ERR0_N  EMMITSBURG_REV0P9  I36

H_CPU_ERR1_LVC1_N   @S9S_MB_2U_LIB.S9S_MB_2U(SCH_1):H_CPU_ERR1_LVC1_N
  R342     2      B  Q_RES       I96
  R1432    1      A  Q_RES       I214
  U122    V2  DIFFIO_RX_B2P  10M04SAU324I7G  I93

H_CPU_ERR1_LVC1_R_N   @S9S_MB_2U_LIB.S9S_MB_2U(SCH_1):H_CPU_ERR1_LVC1_R_N
  R340     2      B  Q_RES       I43
  R341     2      B  Q_RES       I44
  R342     1      A  Q_RES       I96
  R343     1      A  Q_RES       I95

H_CPU_ERR1_PCH_R_N   @S9S_MB_2U_LIB.S9S_MB_2U(SCH_1):H_CPU_ERR1_PCH_R_N
  R343     2      B  Q_RES       I95
  R1261    2      B  Q_RES       I18
  U4      G7  CPU_ERR1_N  EMMITSBURG_REV0P9  I36

H_CPU_ERR2_LVC1_N   @S9S_MB_2U_LIB.S9S_MB_2U(SCH_1):H_CPU_ERR2_LVC1_N
  R346     2      B  Q_RES       I100
  R1433    1      A  Q_RES       I215
  U122    V3  DIFFIO_RX_B4N  10M04SAU324I7G  I93

H_CPU_ERR2_LVC1_R_N   @S9S_MB_2U_LIB.S9S_MB_2U(SCH_1):H_CPU_ERR2_LVC1_R_N
  R344     2      B  Q_RES       I45
  R345     2      B  Q_RES       I46
  R346     1      A  Q_RES       I100
  R347     1      A  Q_RES       I99

H_CPU_ERR2_PCH_R_N   @S9S_MB_2U_LIB.S9S_MB_2U(SCH_1):H_CPU_ERR2_PCH_R_N
  R347     2      B  Q_RES       I99
  R1262    2      B  Q_RES       I11
  U4      L7  CPU_ERR2_N  EMMITSBURG_REV0P9  I36

H_CPU_NMI_LVC1_N   @S9S_MB_2U_LIB.S9S_MB_2U(SCH_1):H_CPU_NMI_LVC1_N
  R188     2      B  Q_RES        I8
  R195     1      A  Q_RES       I49
  R196     1      A  Q_RES       I57

H_CPU_NMI_LVC1_R_N   @S9S_MB_2U_LIB.S9S_MB_2U(SCH_1):H_CPU_NMI_LVC1_R_N
  R188     1      A  Q_RES        I8
  U122    R5  DIFFIO_TX_RX_B5N  10M04SAU324I7G  I155

H_CPU_PM_FAST_WAKE_N   @S9S_MB_2U_LIB.S9S_MB_2U(SCH_1):H_CPU_PM_FAST_WAKE_N
  R1240    2      B  Q_RES        I9
  R1242    2      B  Q_RES       I13
  R1244    2      B  Q_RES       I16
  R1245    1      A  Q_RES       I10

H_CPU_PRDY_QS_GTL_N   @S9S_MB_2U_LIB.S9S_MB_2U(SCH_1):H_CPU_PRDY_QS_GTL_N
  R1       1      A  Q_RES       I18
  R61      1      A  Q_RES       I16
  R759     2      B  Q_RES       I169
  U18      8     3B  74CBTLV3126PW  I129

H_CPU_PREQ_QS_GTL_N   @S9S_MB_2U_LIB.S9S_MB_2U(SCH_1):H_CPU_PREQ_QS_GTL_N
  R2       1      A  Q_RES       I16
  R62      1      A  Q_RES       I11
  R758     2      B  Q_RES       I168
  U18     11     4B  74CBTLV3126PW  I129

H_CPU_RMCA_LVC1_R_N   @S9S_MB_2U_LIB.S9S_MB_2U(SCH_1):H_CPU_RMCA_LVC1_R_N
  R301     2      B  Q_RES       I73
  R302     2      B  Q_RES       I75
  R303     2      B  Q_RES       I76
  R304     2      B  Q_RES       I72
  U122    T7  DIFFIO_RX_B8N  10M04SAU324I7G  I93

H_DBP_PRDY_N_PCH   @S9S_MB_2U_LIB.S9S_MB_2U(SCH_1):H_DBP_PRDY_N_PCH
  R751     2      B  Q_RES       I177
  R756     2      B  Q_RES       I148
  U4     BB37  PRDY_N  EMMITSBURG_REV0P9  I36

H_DBP_PREQ_N_PCH   @S9S_MB_2U_LIB.S9S_MB_2U(SCH_1):H_DBP_PREQ_N_PCH
  R750     2      B  Q_RES       I178
  R755     2      B  Q_RES       I147
  U4     BF37  PREQ_N  EMMITSBURG_REV0P9  I36

H_PMAX_TRIGGER_IO_CPU0   @S9S_MB_2U_LIB.S9S_MB_2U(SCH_1):H_PMAX_TRIGGER_IO_CPU0
  R1241    1      A  Q_RES       I17
  U2     BD24  PMAX_TRIGGER_IO  SOCKET4677_AZIFS054P001C01   I1

H_PMAX_TRIGGER_IO_CPU1   @S9S_MB_2U_LIB.S9S_MB_2U(SCH_1):H_PMAX_TRIGGER_IO_CPU1
  R1243    1      A  Q_RES       I19
  U1     BD24  PMAX_TRIGGER_IO  SOCKET4677_AZIFS054P001C01  I16

H_THERMTRIP_LVC1_N   @S9S_MB_2U_LIB.S9S_MB_2U(SCH_1):H_THERMTRIP_LVC1_N
  R1249    2      B  Q_RES        I2
  R1266    2      B  Q_RES       I36
  U4      F3  CPU_THRMTRIP_N  EMMITSBURG_REV0P9  I36

I3C_SPD_DDRABCD_CPU0_BMC_R_SCL   @S9S_MB_2U_LIB.S9S_MB_2U(SCH_1):I3C_SPD_DDRABCD_CPU0_BMC_R_SCL
  J41    OCP_A5  RBT_ARB_OUT  SCONN168_623403212  I115
  R593     1      A  Q_RES       I58

I3C_SPD_DDRABCD_CPU0_BMC_R_SDA   @S9S_MB_2U_LIB.S9S_MB_2U(SCH_1):I3C_SPD_DDRABCD_CPU0_BMC_R_SDA
  J41    OCP_A6  SLOT_ID1  SCONN168_623403212  I115
  R594     1      A  Q_RES       I59

I3C_SPD_DDRABCD_CPU0_BMC_SCL   @S9S_MB_2U_LIB.S9S_MB_2U(SCH_1):I3C_SPD_DDRABCD_CPU0_BMC_SCL
  R593     2      B  Q_RES       I58
  U15      3    I1A  IDTQS3VH257QG  I25

I3C_SPD_DDRABCD_CPU0_BMC_SDA   @S9S_MB_2U_LIB.S9S_MB_2U(SCH_1):I3C_SPD_DDRABCD_CPU0_BMC_SDA
  R594     2      B  Q_RES       I59
  U15      6    I1B  IDTQS3VH257QG  I25

I3C_SPD_DDRABCD_CPU0_LVC1_R_SCL   @S9S_MB_2U_LIB.S9S_MB_2U(SCH_1):I3C_SPD_DDRABCD_CPU0_LVC1_R_SCL
  R682     2      B  Q_RES       I65
  R691     1      A  Q_RES       I74
  U15      4     YA  IDTQS3VH257QG  I25

I3C_SPD_DDRABCD_CPU0_LVC1_R_SDA   @S9S_MB_2U_LIB.S9S_MB_2U(SCH_1):I3C_SPD_DDRABCD_CPU0_LVC1_R_SDA
  R683     2      B  Q_RES       I66
  R692     1      A  Q_RES       I73
  U15      7     YB  IDTQS3VH257QG  I25

I3C_SPD_DDRABCD_CPU0_LVC1_SCL   @S9S_MB_2U_LIB.S9S_MB_2U(SCH_1):I3C_SPD_DDRABCD_CPU0_LVC1_SCL
  J1       4   HSCL  SCONN288_ADR50001P013C01  I198
  J2       4   HSCL  SCONN288_ADR50001P003C01  I177
  J3       4   HSCL  SCONN288_ADR50001P013C01  I11
  J4       4   HSCL  SCONN288_ADR50001P003C01  I23
  J5       4   HSCL  SCONN288_ADR50001P013C01  I24
  J6       4   HSCL  SCONN288_ADR50001P003C01  I46
  J7       4   HSCL  SCONN288_ADR50001P013C01  I12
  J8       4   HSCL  SCONN288_ADR50001P003C01  I50
  R691     2      B  Q_RES       I74

I3C_SPD_DDRABCD_CPU0_LVC1_SDA   @S9S_MB_2U_LIB.S9S_MB_2U(SCH_1):I3C_SPD_DDRABCD_CPU0_LVC1_SDA
  J1       5   HSDA  SCONN288_ADR50001P013C01  I198
  J2       5   HSDA  SCONN288_ADR50001P003C01  I177
  J3       5   HSDA  SCONN288_ADR50001P013C01  I11
  J4       5   HSDA  SCONN288_ADR50001P003C01  I23
  J5       5   HSDA  SCONN288_ADR50001P013C01  I24
  J6       5   HSDA  SCONN288_ADR50001P003C01  I46
  J7       5   HSDA  SCONN288_ADR50001P013C01  I12
  J8       5   HSDA  SCONN288_ADR50001P003C01  I50
  R692     2      B  Q_RES       I73

I3C_SPD_DDRABCD_CPU0_R_SCL   @S9S_MB_2U_LIB.S9S_MB_2U(SCH_1):I3C_SPD_DDRABCD_CPU0_R_SCL
  R682     1      A  Q_RES       I65
  R687     2      B  Q_RES       I27
  U15      2    I0A  IDTQS3VH257QG  I25

I3C_SPD_DDRABCD_CPU0_R_SDA   @S9S_MB_2U_LIB.S9S_MB_2U(SCH_1):I3C_SPD_DDRABCD_CPU0_R_SDA
  R683     1      A  Q_RES       I66
  R688     2      B  Q_RES       I28
  U15      5    I0B  IDTQS3VH257QG  I25

I3C_SPD_DDRABCD_CPU0_SCL   @S9S_MB_2U_LIB.S9S_MB_2U(SCH_1):I3C_SPD_DDRABCD_CPU0_SCL
  R679     2      B  Q_RES       I85
  R687     1      A  Q_RES       I27
  U2     BT22  SPD_I2CBUS_SCL0  SOCKET4677_AZIFS054P001C01  I57

I3C_SPD_DDRABCD_CPU0_SDA   @S9S_MB_2U_LIB.S9S_MB_2U(SCH_1):I3C_SPD_DDRABCD_CPU0_SDA
  R680     2      B  Q_RES       I89
  R688     1      A  Q_RES       I28
  U2     BY22  SPD_I2CBUS_SDA0  SOCKET4677_AZIFS054P001C01  I57

I3C_SPD_DDRABCD_CPU1_BMC_R_SCL   @S9S_MB_2U_LIB.S9S_MB_2U(SCH_1):I3C_SPD_DDRABCD_CPU1_BMC_R_SCL
  J41    OCP_A9  RBT_TXD0  SCONN168_623403212  I115
  R597     1      A  Q_RES       I62

I3C_SPD_DDRABCD_CPU1_BMC_R_SDA   @S9S_MB_2U_LIB.S9S_MB_2U(SCH_1):I3C_SPD_DDRABCD_CPU1_BMC_R_SDA
  J41    OCP_A10  GND_OCP_A10  SCONN168_623403212  I115
  R598     1      A  Q_RES       I63

I3C_SPD_DDRABCD_CPU1_BMC_SCL   @S9S_MB_2U_LIB.S9S_MB_2U(SCH_1):I3C_SPD_DDRABCD_CPU1_BMC_SCL
  R597     2      B  Q_RES       I62
  U14      3    I1A  IDTQS3VH257QG  I17

I3C_SPD_DDRABCD_CPU1_BMC_SDA   @S9S_MB_2U_LIB.S9S_MB_2U(SCH_1):I3C_SPD_DDRABCD_CPU1_BMC_SDA
  R598     2      B  Q_RES       I63
  U14      6    I1B  IDTQS3VH257QG  I17

I3C_SPD_DDRABCD_CPU1_LVC1_R_SCL   @S9S_MB_2U_LIB.S9S_MB_2U(SCH_1):I3C_SPD_DDRABCD_CPU1_LVC1_R_SCL
  R665     2      B  Q_RES       I18
  R674     1      A  Q_RES       I31
  U14      4     YA  IDTQS3VH257QG  I17

I3C_SPD_DDRABCD_CPU1_LVC1_R_SDA   @S9S_MB_2U_LIB.S9S_MB_2U(SCH_1):I3C_SPD_DDRABCD_CPU1_LVC1_R_SDA
  R666     2      B  Q_RES       I16
  R675     1      A  Q_RES       I33
  U14      7     YB  IDTQS3VH257QG  I17

I3C_SPD_DDRABCD_CPU1_LVC1_SCL   @S9S_MB_2U_LIB.S9S_MB_2U(SCH_1):I3C_SPD_DDRABCD_CPU1_LVC1_SCL
  J17      4   HSCL  SCONN288_ADR50001P013C01  I12
  J18      4   HSCL  SCONN288_ADR50001P003C01  I24
  J19      4   HSCL  SCONN288_ADR50001P013C01  I25
  J20      4   HSCL  SCONN288_ADR50001P003C01  I47
  J21      4   HSCL  SCONN288_ADR50001P013C01  I13
  J22      4   HSCL  SCONN288_ADR50001P003C01  I51
  J23      4   HSCL  SCONN288_ADR50001P013C01  I25
  J24      4   HSCL  SCONN288_ADR50001P003C01  I178
  R674     2      B  Q_RES       I31

I3C_SPD_DDRABCD_CPU1_LVC1_SDA   @S9S_MB_2U_LIB.S9S_MB_2U(SCH_1):I3C_SPD_DDRABCD_CPU1_LVC1_SDA
  J17      5   HSDA  SCONN288_ADR50001P013C01  I12
  J18      5   HSDA  SCONN288_ADR50001P003C01  I24
  J19      5   HSDA  SCONN288_ADR50001P013C01  I25
  J20      5   HSDA  SCONN288_ADR50001P003C01  I47
  J21      5   HSDA  SCONN288_ADR50001P013C01  I13
  J22      5   HSDA  SCONN288_ADR50001P003C01  I51
  J23      5   HSDA  SCONN288_ADR50001P013C01  I25
  J24      5   HSDA  SCONN288_ADR50001P003C01  I178
  R675     2      B  Q_RES       I33

I3C_SPD_DDRABCD_CPU1_R_SCL   @S9S_MB_2U_LIB.S9S_MB_2U(SCH_1):I3C_SPD_DDRABCD_CPU1_R_SCL
  R665     1      A  Q_RES       I18
  R670     2      B  Q_RES       I27
  U14      2    I0A  IDTQS3VH257QG  I17

I3C_SPD_DDRABCD_CPU1_R_SDA   @S9S_MB_2U_LIB.S9S_MB_2U(SCH_1):I3C_SPD_DDRABCD_CPU1_R_SDA
  R666     1      A  Q_RES       I16
  R671     2      B  Q_RES       I28
  U14      5    I0B  IDTQS3VH257QG  I17

I3C_SPD_DDRABCD_CPU1_SCL   @S9S_MB_2U_LIB.S9S_MB_2U(SCH_1):I3C_SPD_DDRABCD_CPU1_SCL
  R662     2      B  Q_RES       I49
  R670     1      A  Q_RES       I27
  U1     BT22  SPD_I2CBUS_SCL0  SOCKET4677_AZIFS054P001C01  I51

I3C_SPD_DDRABCD_CPU1_SDA   @S9S_MB_2U_LIB.S9S_MB_2U(SCH_1):I3C_SPD_DDRABCD_CPU1_SDA
  R663     2      B  Q_RES       I48
  R671     1      A  Q_RES       I28
  U1     BY22  SPD_I2CBUS_SDA0  SOCKET4677_AZIFS054P001C01  I51

I3C_SPD_DDREFGH_CPU0_BMC_R_SCL   @S9S_MB_2U_LIB.S9S_MB_2U(SCH_1):I3C_SPD_DDREFGH_CPU0_BMC_R_SCL
  J41    OCP_A7  RBT_TX_EN  SCONN168_623403212  I115
  R595     1      A  Q_RES       I60

I3C_SPD_DDREFGH_CPU0_BMC_R_SDA   @S9S_MB_2U_LIB.S9S_MB_2U(SCH_1):I3C_SPD_DDREFGH_CPU0_BMC_R_SDA
  J41    OCP_A8  RBT_TXD1  SCONN168_623403212  I115
  R596     1      A  Q_RES       I61

I3C_SPD_DDREFGH_CPU0_BMC_SCL   @S9S_MB_2U_LIB.S9S_MB_2U(SCH_1):I3C_SPD_DDREFGH_CPU0_BMC_SCL
  R595     2      B  Q_RES       I60
  U15     10    I1C  IDTQS3VH257QG  I25

I3C_SPD_DDREFGH_CPU0_BMC_SDA   @S9S_MB_2U_LIB.S9S_MB_2U(SCH_1):I3C_SPD_DDREFGH_CPU0_BMC_SDA
  R596     2      B  Q_RES       I61
  U15     13    I1D  IDTQS3VH257QG  I25

I3C_SPD_DDREFGH_CPU0_LVC1_R_SCL   @S9S_MB_2U_LIB.S9S_MB_2U(SCH_1):I3C_SPD_DDREFGH_CPU0_LVC1_R_SCL
  R684     2      B  Q_RES       I67
  R693     1      A  Q_RES       I75
  U15      9     YC  IDTQS3VH257QG  I25

I3C_SPD_DDREFGH_CPU0_LVC1_R_SDA   @S9S_MB_2U_LIB.S9S_MB_2U(SCH_1):I3C_SPD_DDREFGH_CPU0_LVC1_R_SDA
  R685     2      B  Q_RES       I68
  R694     1      A  Q_RES       I76
  U15     12     YD  IDTQS3VH257QG  I25

I3C_SPD_DDREFGH_CPU0_LVC1_SCL   @S9S_MB_2U_LIB.S9S_MB_2U(SCH_1):I3C_SPD_DDREFGH_CPU0_LVC1_SCL
  J9       4   HSCL  SCONN288_ADR50001P013C01  I12
  J10      4   HSCL  SCONN288_ADR50001P003C01  I13
  J11      4   HSCL  SCONN288_ADR50001P013C01  I25
  J12      4   HSCL  SCONN288_ADR50001P003C01  I24
  J13      4   HSCL  SCONN288_ADR50001P013C01  I11
  J14      4   HSCL  SCONN288_ADR50001P003C01  I47
  J15      4   HSCL  SCONN288_ADR50001P013C01  I48
  J16      4   HSCL  SCONN288_ADR50001P003C01   I6
  R693     2      B  Q_RES       I75

I3C_SPD_DDREFGH_CPU0_LVC1_SDA   @S9S_MB_2U_LIB.S9S_MB_2U(SCH_1):I3C_SPD_DDREFGH_CPU0_LVC1_SDA
  J9       5   HSDA  SCONN288_ADR50001P013C01  I12
  J10      5   HSDA  SCONN288_ADR50001P003C01  I13
  J11      5   HSDA  SCONN288_ADR50001P013C01  I25
  J12      5   HSDA  SCONN288_ADR50001P003C01  I24
  J13      5   HSDA  SCONN288_ADR50001P013C01  I11
  J14      5   HSDA  SCONN288_ADR50001P003C01  I47
  J15      5   HSDA  SCONN288_ADR50001P013C01  I48
  J16      5   HSDA  SCONN288_ADR50001P003C01   I6
  R694     2      B  Q_RES       I76

I3C_SPD_DDREFGH_CPU0_R_SCL   @S9S_MB_2U_LIB.S9S_MB_2U(SCH_1):I3C_SPD_DDREFGH_CPU0_R_SCL
  R684     1      A  Q_RES       I67
  R689     2      B  Q_RES       I30
  U15     11    I0C  IDTQS3VH257QG  I25

I3C_SPD_DDREFGH_CPU0_R_SDA   @S9S_MB_2U_LIB.S9S_MB_2U(SCH_1):I3C_SPD_DDREFGH_CPU0_R_SDA
  R685     1      A  Q_RES       I68
  R690     2      B  Q_RES       I29
  U15     14    I0D  IDTQS3VH257QG  I25

I3C_SPD_DDREFGH_CPU0_SCL   @S9S_MB_2U_LIB.S9S_MB_2U(SCH_1):I3C_SPD_DDREFGH_CPU0_SCL
  R681     2      B  Q_RES       I87
  R689     1      A  Q_RES       I30
  U2     CU17  SPD_I2CBUS_SCL1  SOCKET4677_AZIFS054P001C01  I57

I3C_SPD_DDREFGH_CPU0_SDA   @S9S_MB_2U_LIB.S9S_MB_2U(SCH_1):I3C_SPD_DDREFGH_CPU0_SDA
  R686     2      B  Q_RES       I86
  R690     1      A  Q_RES       I29
  U2     CT18  SPD_I2CBUS_SDA1  SOCKET4677_AZIFS054P001C01  I57

I3C_SPD_DDREFGH_CPU1_BMC_R_SCL   @S9S_MB_2U_LIB.S9S_MB_2U(SCH_1):I3C_SPD_DDREFGH_CPU1_BMC_R_SCL
  J41    OCP_A11  REFCLKN3  SCONN168_623403212  I115
  R599     1      A  Q_RES       I64

I3C_SPD_DDREFGH_CPU1_BMC_R_SDA   @S9S_MB_2U_LIB.S9S_MB_2U(SCH_1):I3C_SPD_DDREFGH_CPU1_BMC_R_SDA
  J41    OCP_A12  REFCLKP3  SCONN168_623403212  I115
  R600     1      A  Q_RES       I65

I3C_SPD_DDREFGH_CPU1_BMC_SCL   @S9S_MB_2U_LIB.S9S_MB_2U(SCH_1):I3C_SPD_DDREFGH_CPU1_BMC_SCL
  R599     2      B  Q_RES       I64
  U14     10    I1C  IDTQS3VH257QG  I17

I3C_SPD_DDREFGH_CPU1_BMC_SDA   @S9S_MB_2U_LIB.S9S_MB_2U(SCH_1):I3C_SPD_DDREFGH_CPU1_BMC_SDA
  R600     2      B  Q_RES       I65
  U14     13    I1D  IDTQS3VH257QG  I17

I3C_SPD_DDREFGH_CPU1_LVC1_R_SCL   @S9S_MB_2U_LIB.S9S_MB_2U(SCH_1):I3C_SPD_DDREFGH_CPU1_LVC1_R_SCL
  R667     2      B  Q_RES       I15
  R676     1      A  Q_RES       I32
  U14      9     YC  IDTQS3VH257QG  I17

I3C_SPD_DDREFGH_CPU1_LVC1_R_SDA   @S9S_MB_2U_LIB.S9S_MB_2U(SCH_1):I3C_SPD_DDREFGH_CPU1_LVC1_R_SDA
  R668     2      B  Q_RES       I14
  R677     1      A  Q_RES       I30
  U14     12     YD  IDTQS3VH257QG  I17

I3C_SPD_DDREFGH_CPU1_LVC1_SCL   @S9S_MB_2U_LIB.S9S_MB_2U(SCH_1):I3C_SPD_DDREFGH_CPU1_LVC1_SCL
  J25      4   HSCL  SCONN288_ADR50001P013C01  I180
  J26      4   HSCL  SCONN288_ADR50001P003C01  I180
  J27      4   HSCL  SCONN288_ADR50001P013C01  I179
  J28      4   HSCL  SCONN288_ADR50001P003C01  I47
  J29      4   HSCL  SCONN288_ADR50001P013C01  I179
  J30      4   HSCL  SCONN288_ADR50001P003C01  I179
  J31      4   HSCL  SCONN288_ADR50001P013C01  I180
  J32      4   HSCL  SCONN288_ADR50001P003C01  I179
  R676     2      B  Q_RES       I32

I3C_SPD_DDREFGH_CPU1_LVC1_SDA   @S9S_MB_2U_LIB.S9S_MB_2U(SCH_1):I3C_SPD_DDREFGH_CPU1_LVC1_SDA
  J25      5   HSDA  SCONN288_ADR50001P013C01  I180
  J26      5   HSDA  SCONN288_ADR50001P003C01  I180
  J27      5   HSDA  SCONN288_ADR50001P013C01  I179
  J28      5   HSDA  SCONN288_ADR50001P003C01  I47
  J29      5   HSDA  SCONN288_ADR50001P013C01  I179
  J30      5   HSDA  SCONN288_ADR50001P003C01  I179
  J31      5   HSDA  SCONN288_ADR50001P013C01  I180
  J32      5   HSDA  SCONN288_ADR50001P003C01  I179
  R677     2      B  Q_RES       I30

I3C_SPD_DDREFGH_CPU1_R_SCL   @S9S_MB_2U_LIB.S9S_MB_2U(SCH_1):I3C_SPD_DDREFGH_CPU1_R_SCL
  R667     1      A  Q_RES       I15
  R672     2      B  Q_RES       I21
  U14     11    I0C  IDTQS3VH257QG  I17

I3C_SPD_DDREFGH_CPU1_R_SDA   @S9S_MB_2U_LIB.S9S_MB_2U(SCH_1):I3C_SPD_DDREFGH_CPU1_R_SDA
  R668     1      A  Q_RES       I14
  R673     2      B  Q_RES       I22
  U14     14    I0D  IDTQS3VH257QG  I17

I3C_SPD_DDREFGH_CPU1_SCL   @S9S_MB_2U_LIB.S9S_MB_2U(SCH_1):I3C_SPD_DDREFGH_CPU1_SCL
  R664     2      B  Q_RES       I47
  R672     1      A  Q_RES       I21
  U1     CU17  SPD_I2CBUS_SCL1  SOCKET4677_AZIFS054P001C01  I51

I3C_SPD_DDREFGH_CPU1_SDA   @S9S_MB_2U_LIB.S9S_MB_2U(SCH_1):I3C_SPD_DDREFGH_CPU1_SDA
  R669     2      B  Q_RES       I46
  R673     1      A  Q_RES       I22
  U1     CT18  SPD_I2CBUS_SDA1  SOCKET4677_AZIFS054P001C01  I51

IND_P0_CPL1     @S9S_MB_2U_LIB.S9S_MB_2U(SCH_1):IND_P0_CPL1
  PL9      3      3  Q_INDUCTOR4P_14  I90
  PL114    2      2  Q_INDUCTOR4P_14  I104

IND_P0_CPL2     @S9S_MB_2U_LIB.S9S_MB_2U(SCH_1):IND_P0_CPL2
  PL13     2      2  Q_INDUCTOR4P_14  I122
  PL114    3      3  Q_INDUCTOR4P_14  I104

IND_P0_CPL3     @S9S_MB_2U_LIB.S9S_MB_2U(SCH_1):IND_P0_CPL3
  PL13     3      3  Q_INDUCTOR4P_14  I122
  PL112    2      2  Q_INDUCTOR4P_14  I74

IND_P0_CPL4     @S9S_MB_2U_LIB.S9S_MB_2U(SCH_1):IND_P0_CPL4
  PL11     2      2  Q_INDUCTOR4P_14  I90
  PL112    3      3  Q_INDUCTOR4P_14  I74

IND_P0_CPL5     @S9S_MB_2U_LIB.S9S_MB_2U(SCH_1):IND_P0_CPL5
  PL10     2      2  Q_INDUCTOR4P_14  I74
  PL11     3      3  Q_INDUCTOR4P_14  I90

IND_P0_CPL6     @S9S_MB_2U_LIB.S9S_MB_2U(SCH_1):IND_P0_CPL6
  PL8      3      3  Q_INDUCTOR4P_14  I81
  PL9      2      2  Q_INDUCTOR4P_14  I90

IND_P0_CPL7     @S9S_MB_2U_LIB.S9S_MB_2U(SCH_1):IND_P0_CPL7
  PL8      2      2  Q_INDUCTOR4P_14  I81
  PL105    1      1  Q_INDUCTOR  I110

IND_P0_CPL8     @S9S_MB_2U_LIB.S9S_MB_2U(SCH_1):IND_P0_CPL8
  PL7      2      2  Q_INDUCTOR4P_14  I117
  PL10     3      3  Q_INDUCTOR4P_14  I74

IND_P1_CPL1     @S9S_MB_2U_LIB.S9S_MB_2U(SCH_1):IND_P1_CPL1
  PL30     3      3  Q_INDUCTOR4P_14  I103
  PL31     2      2  Q_INDUCTOR4P_14  I89

IND_P1_CPL2     @S9S_MB_2U_LIB.S9S_MB_2U(SCH_1):IND_P1_CPL2
  PL29     3      3  Q_INDUCTOR4P_14  I74
  PL30     2      2  Q_INDUCTOR4P_14  I103

IND_P1_CPL3     @S9S_MB_2U_LIB.S9S_MB_2U(SCH_1):IND_P1_CPL3
  PL28     3      3  Q_INDUCTOR4P_14  I90
  PL29     2      2  Q_INDUCTOR4P_14  I74

IND_P1_CPL4     @S9S_MB_2U_LIB.S9S_MB_2U(SCH_1):IND_P1_CPL4
  PL27     3      3  Q_INDUCTOR4P_14  I73
  PL28     2      2  Q_INDUCTOR4P_14  I90

IND_P1_CPL5     @S9S_MB_2U_LIB.S9S_MB_2U(SCH_1):IND_P1_CPL5
  PL24     3      3  Q_INDUCTOR4P_14  I95
  PL27     2      2  Q_INDUCTOR4P_14  I73

IND_P1_CPL6     @S9S_MB_2U_LIB.S9S_MB_2U(SCH_1):IND_P1_CPL6
  PL26     2      2  Q_INDUCTOR4P_14  I90
  PL31     3      3  Q_INDUCTOR4P_14  I89

IND_P1_CPL7     @S9S_MB_2U_LIB.S9S_MB_2U(SCH_1):IND_P1_CPL7
  PL25     2      2  Q_INDUCTOR4P_14  I76
  PL26     3      3  Q_INDUCTOR4P_14  I90

IND_P1_CPL8     @S9S_MB_2U_LIB.S9S_MB_2U(SCH_1):IND_P1_CPL8
  PL24     2      2  Q_INDUCTOR4P_14  I95
  PL106    1      1  Q_INDUCTOR  I107

IRQ0_A57        @S9S_MB_2U_LIB.S9S_MB_2U(SCH_1):IRQ0_A57
  J41    A56  PERN12  SCONN168_623403212  I115
  R506     2      B  Q_RES       I543
  R1925    2      B  Q_RES       I524

IRQ0_A57_R      @S9S_MB_2U_LIB.S9S_MB_2U(SCH_1):IRQ0_A57_R
  R1925    1      A  Q_RES       I524
  U122    D1  DIFFIO_RX_L6N||ADC1IN13  10M04SAU324I7G  I93

IRQ_BMC_CPU_NMI_R1   @S9S_MB_2U_LIB.S9S_MB_2U(SCH_1):IRQ_BMC_CPU_NMI_R1
  R1465    2      B  Q_RES       I226
  U122    E1  DIFFIO_RX_L6P||ADC1IN14  10M04SAU324I7G  I93

IRQ_BMC_PCH_NMI   @S9S_MB_2U_LIB.S9S_MB_2U(SCH_1):IRQ_BMC_PCH_NMI
  R1268    2      B  Q_RES       I222
  R1269    1      A  Q_RES       I225
  U4     BF13  GPPC_A_17_SRCCLKREQ_N_7  EMMITSBURG_REV0P9  I93

IRQ_BMC_PCH_NMI_R   @S9S_MB_2U_LIB.S9S_MB_2U(SCH_1):IRQ_BMC_PCH_NMI_R
  R631     1      A  Q_RES       I226
  U101     2      A  SN74LVC1G17DCKR  I205
  U122   P15  DIFFIO_RX_R7N  10M04SAU324I7G  I155

IRQ_BMC_PCH_NMI_R1   @S9S_MB_2U_LIB.S9S_MB_2U(SCH_1):IRQ_BMC_PCH_NMI_R1
  R631     2      B  Q_RES       I226
  R1268    1      A  Q_RES       I222
  U101     4      Y  SN74LVC1G17DCKR  I205

IRQ_CPU0_VRHOT_N   @S9S_MB_2U_LIB.S9S_MB_2U(SCH_1):IRQ_CPU0_VRHOT_N
  PR131    2      B  Q_RES       I80
  PR177    2      B  Q_RES       I55
  PU5     14  NVRHOT  ISL69260IRAZT  I51
  PU14    18  NVRHOT  RAA229126GNPHA0  I48
  U122   G16  DIFFIO_RX_R28P  10M04SAU324I7G  I93

IRQ_CPU1_VRHOT_N   @S9S_MB_2U_LIB.S9S_MB_2U(SCH_1):IRQ_CPU1_VRHOT_N
  PR249    2      B  Q_RES       I218
  PR284    2      B  Q_RES       I92
  PU22    14  NVRHOT  ISL69260IRAZT  I61
  PU29    18  NVRHOT  RAA229126GNPHA0  I211
  U122   G17  DIFFIO_RX_R19N  10M04SAU324I7G  I93

IRQ_ESPI_LPC_SERIRQ_ALERT_N   @S9S_MB_2U_LIB.S9S_MB_2U(SCH_1):IRQ_ESPI_LPC_SERIRQ_ALERT_N
  R1215    1      A  Q_RES       I38
  U60      4      A  NC7SB3157   I34

IRQ_ESPI_LPC_SERIRQ_ALERT_R_N   @S9S_MB_2U_LIB.S9S_MB_2U(SCH_1):IRQ_ESPI_LPC_SERIRQ_ALERT_R_N
  J41     B3  +12V_EDGE_B3  SCONN168_623403212  I115
  R1215    2      B  Q_RES       I38

IRQ_LPC_PIRQA_N_ESPI_ALERT0_N   @S9S_MB_2U_LIB.S9S_MB_2U(SCH_1):IRQ_LPC_PIRQA_N_ESPI_ALERT0_N
  R1214    1      A  Q_RES       I33
  R1253    2      B  Q_RES       I23
  U4     BG20  GPPC_A_0_ESPI_ALERT0_N  EMMITSBURG_REV0P9  I93

IRQ_LPC_PIRQA_N_ESPI_ALERT0_R_N   @S9S_MB_2U_LIB.S9S_MB_2U(SCH_1):IRQ_LPC_PIRQA_N_ESPI_ALERT0_R_N
  R1214    2      B  Q_RES       I33
  U60      1     B1  NC7SB3157   I34

IRQ_LPC_SERIRQ_ESPI_CS1_N   @S9S_MB_2U_LIB.S9S_MB_2U(SCH_1):IRQ_LPC_SERIRQ_ESPI_CS1_N
  R1254    2      B  Q_RES       I24
  U4     BE16  GPPC_A_7_ESPI_CS1_N  EMMITSBURG_REV0P9  I93
  U60      3     B0  NC7SB3157   I34

IRQ_LVC3_OCP_SFF_WAKE_N   @S9S_MB_2U_LIB.S9S_MB_2U(SCH_1):IRQ_LVC3_OCP_SFF_WAKE_N
  J37    OCP_A3  WAKE#  SCONN168_623403212  I86
  R1824    2      B  Q_RES       I62
  U82      2      A  74LVC1G126GW  I35

IRQ_LVC3_WAKE_EDSFF3_N   @S9S_MB_2U_LIB.S9S_MB_2U(SCH_1):IRQ_LVC3_WAKE_EDSFF3_N
  J35    A42  GND_A42  SCONN140_G64V3431BHR  I64
  R2078    1      A  Q_RES       I427

IRQ_LVC3_WAKE_EDSFF4_N   @S9S_MB_2U_LIB.S9S_MB_2U(SCH_1):IRQ_LVC3_WAKE_EDSFF4_N
  J88    A42    RFU  SCONN84_123318136  I16
  R2077    1      A  Q_RES       I94

IRQ_LVC3_WAKE_N   @S9S_MB_2U_LIB.S9S_MB_2U(SCH_1):IRQ_LVC3_WAKE_N
  R494     2      B  Q_RES        I4
  R1481    1      A  Q_RES       I293
  R1482    2      B  Q_RES       I428
  R1594    2      B  Q_RES       I26
  R2077    2      B  Q_RES       I94
  R2078    2      B  Q_RES       I427
  R2171    2      B  Q_RES       I144
  U4     AH11  WAKE_N  EMMITSBURG_REV0P9  I36

IRQ_LVC3_WAKE_R1_N   @S9S_MB_2U_LIB.S9S_MB_2U(SCH_1):IRQ_LVC3_WAKE_R1_N
  J55    B70  GND_B70  SCONN140_G64V3431BHR  I150
  R2171    1      A  Q_RES       I144

IRQ_LVC3_WAKE_R2_N   @S9S_MB_2U_LIB.S9S_MB_2U(SCH_1):IRQ_LVC3_WAKE_R2_N
  J89    B30    B30  SCONN280_ME1028040102011  I239
  R1481    2      B  Q_RES       I293

IRQ_LVC3_WAKE_R3_N   @S9S_MB_2U_LIB.S9S_MB_2U(SCH_1):IRQ_LVC3_WAKE_R3_N
  J57    B70  GND_B70  SCONN140_G64V3431BHR  I242
  R1482    1      A  Q_RES       I428

IRQ_P12V_HSC_FAULT_N   @S9S_MB_2U_LIB.S9S_MB_2U(SCH_1):IRQ_P12V_HSC_FAULT_N
  J44     13     13  CONN24_52SH90245BRD  I125
  R1836    2      B  Q_RES       I176

IRQ_PCH_CPU_NMI_EVENT_N   @S9S_MB_2U_LIB.S9S_MB_2U(SCH_1):IRQ_PCH_CPU_NMI_EVENT_N
  R1310    2      B  Q_RES       I20
  U122    G3  DIFFIO_RX_L7N||ADC1IN7  10M04SAU324I7G  I93

IRQ_PCH_CPU_NMI_EVENT_R_N   @S9S_MB_2U_LIB.S9S_MB_2U(SCH_1):IRQ_PCH_CPU_NMI_EVENT_R_N
  R1310    1      A  Q_RES       I20
  R1459    2      B  Q_RES       I51
  U4     AP15  GPPC_S_8_NMI_N  EMMITSBURG_REV0P9  I27

IRQ_PCH_SCI_WHEA_N   @S9S_MB_2U_LIB.S9S_MB_2U(SCH_1):IRQ_PCH_SCI_WHEA_N
  R1256    2      B  Q_RES        I1
  R1944    2      B  Q_RES       I384
  U4     AB2  GPP_D_10_BM_BUSY_N_SX_EXIT_HOLDOFF_N  EMMITSBURG_REV0P9  I93

IRQ_PCH_SCI_WHEA_R_N   @S9S_MB_2U_LIB.S9S_MB_2U(SCH_1):IRQ_PCH_SCI_WHEA_R_N
  R1944    1      A  Q_RES       I384
  U122   P17  IO_5||VREFB5N0  10M04SAU324I7G  I139

IRQ_PDB_R_N     @S9S_MB_2U_LIB.S9S_MB_2U(SCH_1):IRQ_PDB_R_N
  R948     1      A  Q_RES       I206
  R952     2      B  Q_RES       I201
  U122   D12  DIFFIO_RX_T3P  10M04SAU324I7G  I155

IRQ_PSU_ALERT_N   @S9S_MB_2U_LIB.S9S_MB_2U(SCH_1):IRQ_PSU_ALERT_N
  L11      1      1  Q_INDUCTOR  I56
  R473     1      A  Q_RES       I204
  R1608    2      B  Q_RES       I203
  R1836    1      A  Q_RES       I176

IRQ_PSYS_CRIT_N   @S9S_MB_2U_LIB.S9S_MB_2U(SCH_1):IRQ_PSYS_CRIT_N
  R541     1      A  Q_RES       I15
  U122   P18  DIFFIO_RX_R12N  10M04SAU324I7G  I93

IRQ_PVCCD_CPU0_VRHOT_LVC3_N   @S9S_MB_2U_LIB.S9S_MB_2U(SCH_1):IRQ_PVCCD_CPU0_VRHOT_LVC3_N
  PR378    2      B  Q_RES       I60
  PU35    14  NVRHOT  ISL69260IRAZT  I51
  U122   B11  DIFFIO_RX_T10N  10M04SAU324I7G  I155

IRQ_PVCCD_CPU1_VRHOT_LVC3_N   @S9S_MB_2U_LIB.S9S_MB_2U(SCH_1):IRQ_PVCCD_CPU1_VRHOT_LVC3_N
  PR223    2      B  Q_RES       I261
  PU18    14  NVRHOT  ISL69260IRAZT  I243
  U122   B12  DIFFIO_RX_T9N  10M04SAU324I7G  I155

IRQ_SGPIO_INTR_N   @S9S_MB_2U_LIB.S9S_MB_2U(SCH_1):IRQ_SGPIO_INTR_N
  J41    B40  PETP7  SCONN168_623403212  I115
  R1812    1      A  Q_RES       I111

IRQ_SGPIO_INTR_N_R   @S9S_MB_2U_LIB.S9S_MB_2U(SCH_1):IRQ_SGPIO_INTR_N_R
  R1812    2      B  Q_RES       I111
  U122   P14  DIFFIO_RX_R1N  10M04SAU324I7G  I93

IRQ_SMI_ACTIVE_BMC_N   @S9S_MB_2U_LIB.S9S_MB_2U(SCH_1):IRQ_SMI_ACTIVE_BMC_N
  R506     1      A  Q_RES       I543
  R1309    2      B  Q_RES       I10

IRQ_SMI_ACTIVE_N   @S9S_MB_2U_LIB.S9S_MB_2U(SCH_1):IRQ_SMI_ACTIVE_N
  R1309    1      A  Q_RES       I10
  R1458    2      B  Q_RES       I50
  U4     AV18  GPPC_S_9_SMI_N  EMMITSBURG_REV0P9  I27

IRQ_SML0_ALERT_N   @S9S_MB_2U_LIB.S9S_MB_2U(SCH_1):IRQ_SML0_ALERT_N
  R1600    1      A  Q_RES       I148
  R1601    1      A  Q_RES       I151
  U4     AU2  GPPC_C_2_ME_SML0ALERT_N  EMMITSBURG_REV0P9  I93

IRQ_SML0_ALERT_R_N   @S9S_MB_2U_LIB.S9S_MB_2U(SCH_1):IRQ_SML0_ALERT_R_N
  R1600    2      B  Q_RES       I148
  U122    T1  DIFFIO_RX_L26N  10M04SAU324I7G  I93

IRQ_SML1_PMBUS_ALERT_N   @S9S_MB_2U_LIB.S9S_MB_2U(SCH_1):IRQ_SML1_PMBUS_ALERT_N
  R951     1      A  Q_RES       I178
  R1656    1      A  Q_RES       I178
  R1657    1      A  Q_RES       I180
  R1658    1      A  Q_RES       I174
  U4     AR4  GPPC_C_8_ME_SML1ALERT_N  EMMITSBURG_REV0P9  I93

IRQ_SML1_PMBUS_ALERT_R_N   @S9S_MB_2U_LIB.S9S_MB_2U(SCH_1):IRQ_SML1_PMBUS_ALERT_R_N
  J44     15     15  CONN24_52SH90245BRD  I125
  R951     2      B  Q_RES       I178

IRQ_SML1_PMBUS_BMC_ALERT_N   @S9S_MB_2U_LIB.S9S_MB_2U(SCH_1):IRQ_SML1_PMBUS_BMC_ALERT_N
  R1657    2      B  Q_RES       I180
  U122    M7  DIFFIO_RX_L25P  10M04SAU324I7G  I93

IRQ_SML1_PMBUS_PLD_ALERT_N   @S9S_MB_2U_LIB.S9S_MB_2U(SCH_1):IRQ_SML1_PMBUS_PLD_ALERT_N
  R1656    2      B  Q_RES       I178
  U122    T2  DIFFIO_RX_L26P  10M04SAU324I7G  I93

IRQ_TPM_SPI_N   @S9S_MB_2U_LIB.S9S_MB_2U(SCH_1):IRQ_TPM_SPI_N
  R401     2      B  Q_RES       I69
  U4      N4  GPP_I_21  EMMITSBURG_REV0P9  I22
  U122   P16   IO_5  10M04SAU324I7G  I155

JTAG_BMC_CPU_TCK   @S9S_MB_2U_LIB.S9S_MB_2U(SCH_1):JTAG_BMC_CPU_TCK
  R1373    1      A  Q_RES       I105
  U85      3     B0  NC7SB3157   I109
  U86      4    2OE  74CBTLV3126PW  I84

JTAG_BMC_DBP_PREQ_N   @S9S_MB_2U_LIB.S9S_MB_2U(SCH_1):JTAG_BMC_DBP_PREQ_N
  J41    A49  GND_A49  SCONN168_623403212  I115
  R1379    2      B  Q_RES       I12
  R1383    2      B  Q_RES        I1
  R1832    1      A  Q_RES       I80

JTAG_BMC_DBP_TCK   @S9S_MB_2U_LIB.S9S_MB_2U(SCH_1):JTAG_BMC_DBP_TCK
  U85      4      A  NC7SB3157   I109
  U97      4    NO2  TS3A24157RSER  I38

JTAG_BMC_DBP_TDI   @S9S_MB_2U_LIB.S9S_MB_2U(SCH_1):JTAG_BMC_DBP_TDI
  R1345    2      B  Q_RES       I13
  U96      2    NO1  TS3A24157RSER  I68

JTAG_BMC_DBP_TDI_R   @S9S_MB_2U_LIB.S9S_MB_2U(SCH_1):JTAG_BMC_DBP_TDI_R
  R1345    1      A  Q_RES       I13
  U84     10     A2  GTL2014PW   I18

JTAG_BMC_DBP_TDO   @S9S_MB_2U_LIB.S9S_MB_2U(SCH_1):JTAG_BMC_DBP_TDO
  R483     2      B  Q_RES       I37
  R1380    2      B  Q_RES       I31
  U96      4    NO2  TS3A24157RSER  I68

JTAG_BMC_DBP_TDO_R   @S9S_MB_2U_LIB.S9S_MB_2U(SCH_1):JTAG_BMC_DBP_TDO_R
  R483     1      A  Q_RES       I37
  U83      9     A3  GTL2014PW   I45

JTAG_BMC_DBP_TMS   @S9S_MB_2U_LIB.S9S_MB_2U(SCH_1):JTAG_BMC_DBP_TMS
  R1184    2      B  Q_RES       I14
  U97      2    NO1  TS3A24157RSER  I38

JTAG_BMC_DBP_TMS_R   @S9S_MB_2U_LIB.S9S_MB_2U(SCH_1):JTAG_BMC_DBP_TMS_R
  R1184    1      A  Q_RES       I14
  U84      9     A3  GTL2014PW   I18

JTAG_BMC_PCH_TCK   @S9S_MB_2U_LIB.S9S_MB_2U(SCH_1):JTAG_BMC_PCH_TCK
  R1371    1      A  Q_RES       I106
  U85      1     B1  NC7SB3157   I109
  U86     10    3OE  74CBTLV3126PW  I84

JTAG_BMC_PLD_TCK   @S9S_MB_2U_LIB.S9S_MB_2U(SCH_1):JTAG_BMC_PLD_TCK
  J43      1      1  CONN10_G2100HT0038071  I42
  R806     2      B  Q_RES       I54
  R930     1      A  Q_RES       I63
  U97      3    NC2  TS3A24157RSER  I38

JTAG_BMC_PLD_TDI   @S9S_MB_2U_LIB.S9S_MB_2U(SCH_1):JTAG_BMC_PLD_TDI
  J43      9      9  CONN10_G2100HT0038071  I42
  R803     2      B  Q_RES       I19
  R927     2      B  Q_RES       I61
  U96      1    NC1  TS3A24157RSER  I68

JTAG_BMC_PLD_TDO   @S9S_MB_2U_LIB.S9S_MB_2U(SCH_1):JTAG_BMC_PLD_TDO
  J43      3      3  CONN10_G2100HT0038071  I42
  R804     2      B  Q_RES       I20
  R928     2      B  Q_RES       I60
  U96      3    NC2  TS3A24157RSER  I68

JTAG_BMC_PLD_TMS   @S9S_MB_2U_LIB.S9S_MB_2U(SCH_1):JTAG_BMC_PLD_TMS
  J43      5      5  CONN10_G2100HT0038071  I42
  R805     2      B  Q_RES       I25
  R929     2      B  Q_RES       I59
  U97      1    NC1  TS3A24157RSER  I38

JTAG_BMC_TCK    @S9S_MB_2U_LIB.S9S_MB_2U(SCH_1):JTAG_BMC_TCK
  J41    A34  PERP5  SCONN168_623403212  I115
  U97      6   COM2  TS3A24157RSER  I38

JTAG_BMC_TDI    @S9S_MB_2U_LIB.S9S_MB_2U(SCH_1):JTAG_BMC_TDI
  J41    A36  PERN6  SCONN168_623403212  I115
  U96      9   COM1  TS3A24157RSER  I68

JTAG_BMC_TDO    @S9S_MB_2U_LIB.S9S_MB_2U(SCH_1):JTAG_BMC_TDO
  J41    A37  PERP6  SCONN168_623403212  I115
  U96      6   COM2  TS3A24157RSER  I68

JTAG_BMC_TMS    @S9S_MB_2U_LIB.S9S_MB_2U(SCH_1):JTAG_BMC_TMS
  J41    A35  GND_A35  SCONN168_623403212  I115
  U97      9   COM1  TS3A24157RSER  I38

JTAG_CPU0_MUX_GTL_TDO   @S9S_MB_2U_LIB.S9S_MB_2U(SCH_1):JTAG_CPU0_MUX_GTL_TDO
  R744     2      B  Q_RES       I77
  U2     BW25    TDO  SOCKET4677_AZIFS054P001C01  I57
  U16      1      A  NC7SZ66M5X  I88
  U22      1     B1  NC7SB3157   I71

JTAG_CPU0_PLD_TCK   @S9S_MB_2U_LIB.S9S_MB_2U(SCH_1):JTAG_CPU0_PLD_TCK
  R1226    1      A  Q_RES       I52
  U2     CY22  CPLD_TCK  SOCKET4677_AZIFS054P001C01   I1

JTAG_CPU0_PLD_TDI   @S9S_MB_2U_LIB.S9S_MB_2U(SCH_1):JTAG_CPU0_PLD_TDI
  R1223    1      A  Q_RES       I49
  U2     CT22  CPLD_TDI  SOCKET4677_AZIFS054P001C01   I1

JTAG_CPU0_PLD_TDO   @S9S_MB_2U_LIB.S9S_MB_2U(SCH_1):JTAG_CPU0_PLD_TDO
  R1225    1      A  Q_RES       I51
  U2     CP22  CPLD_TDO  SOCKET4677_AZIFS054P001C01   I1

JTAG_CPU0_PLD_TMS   @S9S_MB_2U_LIB.S9S_MB_2U(SCH_1):JTAG_CPU0_PLD_TMS
  R1224    1      A  Q_RES       I50
  U2     CV22  CPLD_TMS  SOCKET4677_AZIFS054P001C01   I1

JTAG_CPU1_MUX_GTL_TDO   @S9S_MB_2U_LIB.S9S_MB_2U(SCH_1):JTAG_CPU1_MUX_GTL_TDO
  R742     2      B  Q_RES       I78
  U1     BW25    TDO  SOCKET4677_AZIFS054P001C01  I51
  U22      3     B0  NC7SB3157   I71

JTAG_DBP_BMC_PRDY_N   @S9S_MB_2U_LIB.S9S_MB_2U(SCH_1):JTAG_DBP_BMC_PRDY_N
  J41    A50  PERN10  SCONN168_623403212  I115
  R1378    2      B  Q_RES       I36
  R1382    2      B  Q_RES       I20
  R1831    1      A  Q_RES       I82

JTAG_DBP_BMC_PRDY_R1_N   @S9S_MB_2U_LIB.S9S_MB_2U(SCH_1):JTAG_DBP_BMC_PRDY_R1_N
  R1378    1      A  Q_RES       I36
  U83     12     A1  GTL2014PW   I45

JTAG_DBP_BMC_PRDY_R_N   @S9S_MB_2U_LIB.S9S_MB_2U(SCH_1):JTAG_DBP_BMC_PRDY_R_N
  R1831    2      B  Q_RES       I82
  U122    D7  DIFFIO_RX_T18N  10M04SAU324I7G  I155

JTAG_DBP_BMC_PREQ_R1_N   @S9S_MB_2U_LIB.S9S_MB_2U(SCH_1):JTAG_DBP_BMC_PREQ_R1_N
  R1379    1      A  Q_RES       I12
  U84     13     A0  GTL2014PW   I18

JTAG_DBP_BMC_PREQ_R_N   @S9S_MB_2U_LIB.S9S_MB_2U(SCH_1):JTAG_DBP_BMC_PREQ_R_N
  R1832    2      B  Q_RES       I80
  U122    D8  DIFFIO_RX_T18P||DEV_OE  10M04SAU324I7G  I139

JTAG_DBP_BOOT_HALT_N   @S9S_MB_2U_LIB.S9S_MB_2U(SCH_1):JTAG_DBP_BOOT_HALT_N
  J42     36     36  SCONN60_QSH03001LDAKTR  I44
  R773     1      A  Q_RES       I124
  R778     2      B  Q_RES       I15

JTAG_DBP_CPU0_GTL_R_TCK   @S9S_MB_2U_LIB.S9S_MB_2U(SCH_1):JTAG_DBP_CPU0_GTL_R_TCK
  R5       2      B  Q_RES       I24
  U2     BT24    TCK  SOCKET4677_AZIFS054P001C01  I57

JTAG_DBP_CPU0_GTL_R_TDI   @S9S_MB_2U_LIB.S9S_MB_2U(SCH_1):JTAG_DBP_CPU0_GTL_R_TDI
  R4       2      B  Q_RES       I29
  U2     BV24    TDI  SOCKET4677_AZIFS054P001C01  I57

JTAG_DBP_CPU0_QS_GTL_R_TMS   @S9S_MB_2U_LIB.S9S_MB_2U(SCH_1):JTAG_DBP_CPU0_QS_GTL_R_TMS
  R6       2      B  Q_RES       I25
  U2     BR25    TMS  SOCKET4677_AZIFS054P001C01  I57

JTAG_DBP_CPU1_GTL_R_TCK   @S9S_MB_2U_LIB.S9S_MB_2U(SCH_1):JTAG_DBP_CPU1_GTL_R_TCK
  R65      2      B  Q_RES        I8
  U1     BT24    TCK  SOCKET4677_AZIFS054P001C01  I51

JTAG_DBP_CPU1_GTL_R_TDI   @S9S_MB_2U_LIB.S9S_MB_2U(SCH_1):JTAG_DBP_CPU1_GTL_R_TDI
  R64      2      B  Q_RES        I9
  U1     BV24    TDI  SOCKET4677_AZIFS054P001C01  I51

JTAG_DBP_CPU1_QS_GTL_R_TMS   @S9S_MB_2U_LIB.S9S_MB_2U(SCH_1):JTAG_DBP_CPU1_QS_GTL_R_TMS
  R66      2      B  Q_RES        I7
  U1     BR25    TMS  SOCKET4677_AZIFS054P001C01  I51

JTAG_DBP_CPU_GTL_TCK   @S9S_MB_2U_LIB.S9S_MB_2U(SCH_1):JTAG_DBP_CPU_GTL_TCK
  R5       1      A  Q_RES       I24
  R65      1      A  Q_RES        I8
  R762     1      A  Q_RES       I71
  R774     1      A  Q_RES       I132
  R1025    1      A  Q_RES       I38
  R1348    2      B  Q_RES       I88
  U4     BD35  JTAGX  EMMITSBURG_REV0P9  I36

JTAG_DBP_CPU_GTL_TCK_R   @S9S_MB_2U_LIB.S9S_MB_2U(SCH_1):JTAG_DBP_CPU_GTL_TCK_R
  J42      3      3  SCONN60_QSH03001LDAKTR  I44
  R762     2      B  Q_RES       I71

JTAG_DBP_CPU_GTL_TCK_R1   @S9S_MB_2U_LIB.S9S_MB_2U(SCH_1):JTAG_DBP_CPU_GTL_TCK_R1
  R1348    1      A  Q_RES       I88
  U86      6     2B  74CBTLV3126PW  I84

JTAG_DBP_CPU_HOOK8_MBP2_GTL_N   @S9S_MB_2U_LIB.S9S_MB_2U(SCH_1):JTAG_DBP_CPU_HOOK8_MBP2_GTL_N
  J42     55     55  SCONN60_QSH03001LDAKTR  I44
  U18      5     2A  74CBTLV3126PW  I129

JTAG_DBP_CPU_HOOK9_MBP3_GTL_N   @S9S_MB_2U_LIB.S9S_MB_2U(SCH_1):JTAG_DBP_CPU_HOOK9_MBP3_GTL_N
  J42     53     53  SCONN60_QSH03001LDAKTR  I44
  U18      2     1A  74CBTLV3126PW  I129

JTAG_DBP_CPU_QS_GTL_TMS   @S9S_MB_2U_LIB.S9S_MB_2U(SCH_1):JTAG_DBP_CPU_QS_GTL_TMS
  R6       1      A  Q_RES       I25
  R66      1      A  Q_RES        I7
  R757     2      B  Q_RES       I166
  U17      3     1B  74CBTLV3126PW  I80

JTAG_DBP_FB_TDI   @S9S_MB_2U_LIB.S9S_MB_2U(SCH_1):JTAG_DBP_FB_TDI
  R481     2      B  Q_RES       I58
  U84      5     B2  GTL2014PW   I18

JTAG_DBP_FB_TDO   @S9S_MB_2U_LIB.S9S_MB_2U(SCH_1):JTAG_DBP_FB_TDO
  R1366    2      B  Q_RES       I64
  U83      6     B3  GTL2014PW   I45

JTAG_DBP_FB_TMS   @S9S_MB_2U_LIB.S9S_MB_2U(SCH_1):JTAG_DBP_FB_TMS
  R480     2      B  Q_RES       I59
  U84      6     B3  GTL2014PW   I18

JTAG_DBP_PCH_DEBUG_CONSENT_N   @S9S_MB_2U_LIB.S9S_MB_2U(SCH_1):JTAG_DBP_PCH_DEBUG_CONSENT_N
  J42     15     15  SCONN60_QSH03001LDAKTR  I44
  R771     1      A  Q_RES       I120

JTAG_DBP_PMODE   @S9S_MB_2U_LIB.S9S_MB_2U(SCH_1):JTAG_DBP_PMODE
  J42      7      7  SCONN60_QSH03001LDAKTR  I44
  R1026    1      A  Q_RES       I37
  U4     BE40  DBG_PMODE  EMMITSBURG_REV0P9  I36

JTAG_DBP_POWER_BTN_N   @S9S_MB_2U_LIB.S9S_MB_2U(SCH_1):JTAG_DBP_POWER_BTN_N
  C548     1      A  Q_CAP       I130
  J42     40     40  SCONN60_QSH03001LDAKTR  I44
  R766     2      B  Q_RES       I111

JTAG_DBP_PRDY_N   @S9S_MB_2U_LIB.S9S_MB_2U(SCH_1):JTAG_DBP_PRDY_N
  R756     1      A  Q_RES       I148
  R764     1      A  Q_RES       I83
  R1367    1      A  Q_RES       I65
  U18      9     3A  74CBTLV3126PW  I129

JTAG_DBP_PRDY_R1_N   @S9S_MB_2U_LIB.S9S_MB_2U(SCH_1):JTAG_DBP_PRDY_R1_N
  J42     11     11  SCONN60_QSH03001LDAKTR  I44
  R764     2      B  Q_RES       I83

JTAG_DBP_PRDY_R_N   @S9S_MB_2U_LIB.S9S_MB_2U(SCH_1):JTAG_DBP_PRDY_R_N
  R1367    2      B  Q_RES       I65
  U83      3     B1  GTL2014PW   I45

JTAG_DBP_PREQ_N   @S9S_MB_2U_LIB.S9S_MB_2U(SCH_1):JTAG_DBP_PREQ_N
  R482     1      A  Q_RES       I57
  R755     1      A  Q_RES       I147
  R777     2      B  Q_RES       I10
  U18     12     4A  74CBTLV3126PW  I129

JTAG_DBP_PREQ_N_R   @S9S_MB_2U_LIB.S9S_MB_2U(SCH_1):JTAG_DBP_PREQ_N_R
  J42     10     10  SCONN60_QSH03001LDAKTR  I44
  R777     1      A  Q_RES       I10

JTAG_DBP_PREQ_R_N   @S9S_MB_2U_LIB.S9S_MB_2U(SCH_1):JTAG_DBP_PREQ_R_N
  R482     2      B  Q_RES       I57
  U84      2     B0  GTL2014PW   I18

JTAG_DBP_PRESENT_R_N   @S9S_MB_2U_LIB.S9S_MB_2U(SCH_1):JTAG_DBP_PRESENT_R_N
  J42     17     17  SCONN60_QSH03001LDAKTR  I44
  R768     2      B  Q_RES       I112
  R1472    1      A  Q_RES       I144

JTAG_DBP_TCK_PCH   @S9S_MB_2U_LIB.S9S_MB_2U(SCH_1):JTAG_DBP_TCK_PCH
  R765     1      A  Q_RES       I74
  R1024    1      A  Q_RES       I41
  R1349    2      B  Q_RES       I87
  U4     BF35  JTAG_TCK  EMMITSBURG_REV0P9  I36

JTAG_DBP_TCK_PCH_R   @S9S_MB_2U_LIB.S9S_MB_2U(SCH_1):JTAG_DBP_TCK_PCH_R
  R1349    1      A  Q_RES       I87
  U86      8     3B  74CBTLV3126PW  I84

JTAG_DBP_TCK_R_TCK   @S9S_MB_2U_LIB.S9S_MB_2U(SCH_1):JTAG_DBP_TCK_R_TCK
  J42     51     51  SCONN60_QSH03001LDAKTR  I44
  R765     2      B  Q_RES       I74

JTAG_DBP_TDI    @S9S_MB_2U_LIB.S9S_MB_2U(SCH_1):JTAG_DBP_TDI
  R481     1      A  Q_RES       I58
  R753     1      A  Q_RES       I128
  R763     1      A  Q_RES       I70
  U17      5     2A  74CBTLV3126PW  I80

JTAG_DBP_TDI_PCH   @S9S_MB_2U_LIB.S9S_MB_2U(SCH_1):JTAG_DBP_TDI_PCH
  R748     2      B  Q_RES       I180
  R753     2      B  Q_RES       I128
  U4     BE38  JTAG_TDI  EMMITSBURG_REV0P9  I36

JTAG_DBP_TDI_R   @S9S_MB_2U_LIB.S9S_MB_2U(SCH_1):JTAG_DBP_TDI_R
  J42      5      5  SCONN60_QSH03001LDAKTR  I44
  R763     2      B  Q_RES       I70

JTAG_DBP_TDO    @S9S_MB_2U_LIB.S9S_MB_2U(SCH_1):JTAG_DBP_TDO
  R752     1      A  Q_RES       I127
  R776     2      B  Q_RES        I7
  R1366    1      A  Q_RES       I64
  U17     12     4A  74CBTLV3126PW  I80

JTAG_DBP_TDO_PCH   @S9S_MB_2U_LIB.S9S_MB_2U(SCH_1):JTAG_DBP_TDO_PCH
  R747     2      B  Q_RES       I176
  R752     2      B  Q_RES       I127
  U4     BE36  JTAG_TDO  EMMITSBURG_REV0P9  I36

JTAG_DBP_TDO_R   @S9S_MB_2U_LIB.S9S_MB_2U(SCH_1):JTAG_DBP_TDO_R
  J42      4      4  SCONN60_QSH03001LDAKTR  I44
  R776     1      A  Q_RES        I7

JTAG_DBP_TMS    @S9S_MB_2U_LIB.S9S_MB_2U(SCH_1):JTAG_DBP_TMS
  R480     1      A  Q_RES       I59
  R754     1      A  Q_RES       I126
  R775     2      B  Q_RES        I5
  U17      2     1A  74CBTLV3126PW  I80

JTAG_DBP_TMS_PCH   @S9S_MB_2U_LIB.S9S_MB_2U(SCH_1):JTAG_DBP_TMS_PCH
  R749     2      B  Q_RES       I179
  R754     2      B  Q_RES       I126
  U4     BD37  JTAG_TMS  EMMITSBURG_REV0P9  I36

JTAG_DBP_TMS_R   @S9S_MB_2U_LIB.S9S_MB_2U(SCH_1):JTAG_DBP_TMS_R
  J42      2      2  SCONN60_QSH03001LDAKTR  I44
  R775     1      A  Q_RES        I5

JTAG_EDSFF4_TCK   @S9S_MB_2U_LIB.S9S_MB_2U(SCH_1):JTAG_EDSFF4_TCK
  J61    A14  REFCLKN1  SCONN84_123318136  I49
  R2082    1      A  Q_RES       I114

JTAG_EDSFF4_TDI   @S9S_MB_2U_LIB.S9S_MB_2U(SCH_1):JTAG_EDSFF4_TDI
  J61     B9  DUALPORTEN_N  SCONN84_123318136  I49
  R2079    1      A  Q_RES       I117

JTAG_EDSFF4_TDO   @S9S_MB_2U_LIB.S9S_MB_2U(SCH_1):JTAG_EDSFF4_TDO
  J61     B8  RFUB8  SCONN84_123318136  I49
  R2080    1      A  Q_RES       I113

JTAG_EDSFF4_TMS   @S9S_MB_2U_LIB.S9S_MB_2U(SCH_1):JTAG_EDSFF4_TMS
  J61    A15  REFCLKP1  SCONN84_123318136  I49
  R2081    1      A  Q_RES       I112

JTAG_EDSFF4_TRST_N   @S9S_MB_2U_LIB.S9S_MB_2U(SCH_1):JTAG_EDSFF4_TRST_N
  J61    A42    RFU  SCONN84_123318136  I49
  R2083    1      A  Q_RES       I111

JTAG_MUX_CPU0_GTL_TDI   @S9S_MB_2U_LIB.S9S_MB_2U(SCH_1):JTAG_MUX_CPU0_GTL_TDI
  R4       1      A  Q_RES       I29
  R741     2      B  Q_RES       I66
  U21      3     B0  NC7SB3157   I58

JTAG_MUX_CPU1_GTL_TDI   @S9S_MB_2U_LIB.S9S_MB_2U(SCH_1):JTAG_MUX_CPU1_GTL_TDI
  R64      1      A  Q_RES        I9
  R743     2      B  Q_RES       I65
  U16      2      B  NC7SZ66M5X  I88
  U21      1     B1  NC7SB3157   I58

JTAG_MUX_QS_GTL_TDO   @S9S_MB_2U_LIB.S9S_MB_2U(SCH_1):JTAG_MUX_QS_GTL_TDO
  U17     11     4B  74CBTLV3126PW  I80
  U22      4      A  NC7SB3157   I71

JTAG_PLD_JTAGEN   @S9S_MB_2U_LIB.S9S_MB_2U(SCH_1):JTAG_PLD_JTAGEN
  R919     2      B  Q_RES       I75
  R920     1      A  Q_RES       I76
  R931     1      A  Q_RES       I48
  U122    H7  JTAGEN||DIFFIO_RX_L9P  10M04SAU324I7G  I139

JTAG_PLD_JTAGEN_R   @S9S_MB_2U_LIB.S9S_MB_2U(SCH_1):JTAG_PLD_JTAGEN_R
  J43      8      8  CONN10_G2100HT0038071  I42
  R931     2      B  Q_RES       I48

JTAG_PLD_TCK_R   @S9S_MB_2U_LIB.S9S_MB_2U(SCH_1):JTAG_PLD_TCK_R
  R806     1      A  Q_RES       I54
  R1441    1      A  Q_RES       I235
  U122    J8  TCK||DIFFIO_RX_L11P  10M04SAU324I7G  I139

JTAG_PLD_TDI_R   @S9S_MB_2U_LIB.S9S_MB_2U(SCH_1):JTAG_PLD_TDI_R
  R803     1      A  Q_RES       I19
  R1438    1      A  Q_RES       I226
  U122    H3  TDI||DIFFIO_RX_L12N  10M04SAU324I7G  I139

JTAG_PLD_TDO_R   @S9S_MB_2U_LIB.S9S_MB_2U(SCH_1):JTAG_PLD_TDO_R
  R804     1      A  Q_RES       I20
  R1440    1      A  Q_RES       I231
  U122    H4  TDO||DIFFIO_RX_L12P  10M04SAU324I7G  I139

JTAG_PLD_TMS_R   @S9S_MB_2U_LIB.S9S_MB_2U(SCH_1):JTAG_PLD_TMS_R
  R805     1      A  Q_RES       I25
  R1439    1      A  Q_RES       I229
  U122    J7  TMS||DIFFIO_RX_L11N  10M04SAU324I7G  I139

JTAG_QS_MUX_GTL_TDI   @S9S_MB_2U_LIB.S9S_MB_2U(SCH_1):JTAG_QS_MUX_GTL_TDI
  U17      6     2B  74CBTLV3126PW  I80
  U21      4      A  NC7SB3157   I58

JTAG_RISER1_TCK   @S9S_MB_2U_LIB.S9S_MB_2U(SCH_1):JTAG_RISER1_TCK
  J55     B2  SIGNAL_B2  SCONN140_G64V3431BHR  I150
  R2178    1      A  Q_RES       I146

JTAG_RISER1_TDI   @S9S_MB_2U_LIB.S9S_MB_2U(SCH_1):JTAG_RISER1_TDI
  J55     B3  SIGNAL_B3  SCONN140_G64V3431BHR  I150
  R2175    1      A  Q_RES       I148

JTAG_RISER1_TDO   @S9S_MB_2U_LIB.S9S_MB_2U(SCH_1):JTAG_RISER1_TDO
  J55     B4  GND_B4  SCONN140_G64V3431BHR  I150
  R2176    1      A  Q_RES       I149

JTAG_RISER1_TMS   @S9S_MB_2U_LIB.S9S_MB_2U(SCH_1):JTAG_RISER1_TMS
  J55    B42  GND_B42  SCONN140_G64V3431BHR  I150
  R2177    1      A  Q_RES       I147

JTAG_RISER1_TRST_N   @S9S_MB_2U_LIB.S9S_MB_2U(SCH_1):JTAG_RISER1_TRST_N
  J55    B68  SIGNAL_B68  SCONN140_G64V3431BHR  I150
  R2179    1      A  Q_RES       I145

JTAG_RISER2_TCK   @S9S_MB_2U_LIB.S9S_MB_2U(SCH_1):JTAG_RISER2_TCK
  J89    A23    A23  SCONN280_ME1028040102011  I239
  R1530    1      A  Q_RES       I161

JTAG_RISER2_TDI   @S9S_MB_2U_LIB.S9S_MB_2U(SCH_1):JTAG_RISER2_TDI
  J89    A24    A24  SCONN280_ME1028040102011  I239
  R640     1      A  Q_RES       I164

JTAG_RISER2_TDO   @S9S_MB_2U_LIB.S9S_MB_2U(SCH_1):JTAG_RISER2_TDO
  J89    A25    A25  SCONN280_ME1028040102011  I239
  R1528    1      A  Q_RES       I163

JTAG_RISER2_TMS   @S9S_MB_2U_LIB.S9S_MB_2U(SCH_1):JTAG_RISER2_TMS
  J89    A26    A26  SCONN280_ME1028040102011  I239
  R1529    1      A  Q_RES       I162

JTAG_RISER2_TRST_N   @S9S_MB_2U_LIB.S9S_MB_2U(SCH_1):JTAG_RISER2_TRST_N
  J89    A27    A27  SCONN280_ME1028040102011  I239
  R1531    1      A  Q_RES       I160

JTAG_RISER3_TCK   @S9S_MB_2U_LIB.S9S_MB_2U(SCH_1):JTAG_RISER3_TCK
  J57     B2  SIGNAL_B2  SCONN140_G64V3431BHR  I242
  R1535    1      A  Q_RES       I371

JTAG_RISER3_TDI   @S9S_MB_2U_LIB.S9S_MB_2U(SCH_1):JTAG_RISER3_TDI
  J57     B3  SIGNAL_B3  SCONN140_G64V3431BHR  I242
  R1532    1      A  Q_RES       I370

JTAG_RISER3_TDO   @S9S_MB_2U_LIB.S9S_MB_2U(SCH_1):JTAG_RISER3_TDO
  J57     B4  GND_B4  SCONN140_G64V3431BHR  I242
  R1533    1      A  Q_RES       I369

JTAG_RISER3_TMS   @S9S_MB_2U_LIB.S9S_MB_2U(SCH_1):JTAG_RISER3_TMS
  J57    B42  GND_B42  SCONN140_G64V3431BHR  I242
  R1534    1      A  Q_RES       I373

JTAG_RISER3_TRST_N   @S9S_MB_2U_LIB.S9S_MB_2U(SCH_1):JTAG_RISER3_TRST_N
  J57    B68  SIGNAL_B68  SCONN140_G64V3431BHR  I242
  R1536    1      A  Q_RES       I372

JTAG_RST_DBP_RSMRST_N   @S9S_MB_2U_LIB.S9S_MB_2U(SCH_1):JTAG_RST_DBP_RSMRST_N
  J42     42     42  SCONN60_QSH03001LDAKTR  I44
  R772     1      A  Q_RES       I118

JTAG_RST_DBP_RST_CO_N   @S9S_MB_2U_LIB.S9S_MB_2U(SCH_1):JTAG_RST_DBP_RST_CO_N
  C549     1      A  Q_CAP       I129
  J42      6      6  SCONN60_QSH03001LDAKTR  I44
  R767     2      B  Q_RES       I113

JTAG_TRC_PCH_PTI0_CLK   @S9S_MB_2U_LIB.S9S_MB_2U(SCH_1):JTAG_TRC_PCH_PTI0_CLK
  J42     13     13  SCONN60_QSH03001LDAKTR  I44
  U4     BD33  GPPC_B_0_GSXDOUT  EMMITSBURG_REV0P9  I93

JTAG_TRC_PCH_PTI1_CLK   @S9S_MB_2U_LIB.S9S_MB_2U(SCH_1):JTAG_TRC_PCH_PTI1_CLK
  J42     59     59  SCONN60_QSH03001LDAKTR  I44
  U4     BD23  GPPC_B_23  EMMITSBURG_REV0P9  I93

JTAG_TRC_PCH_PTI<0>   @S9S_MB_2U_LIB.S9S_MB_2U(SCH_1):JTAG_TRC_PCH_PTI<0>
  J42     19     19  SCONN60_QSH03001LDAKTR  I44
  U4     BE32  GPPC_B_1_GSXSLOAD  EMMITSBURG_REV0P9  I93

JTAG_TRC_PCH_PTI<1>   @S9S_MB_2U_LIB.S9S_MB_2U(SCH_1):JTAG_TRC_PCH_PTI<1>
  J42     21     21  SCONN60_QSH03001LDAKTR  I44
  U4     BF33  GPPC_B_2_GSXDIN  EMMITSBURG_REV0P9  I93

JTAG_TRC_PCH_PTI<2>   @S9S_MB_2U_LIB.S9S_MB_2U(SCH_1):JTAG_TRC_PCH_PTI<2>
  J42     23     23  SCONN60_QSH03001LDAKTR  I44
  U4     BD31  GPPC_B_3_GSXRESET_N  EMMITSBURG_REV0P9  I93

JTAG_TRC_PCH_PTI<3>   @S9S_MB_2U_LIB.S9S_MB_2U(SCH_1):JTAG_TRC_PCH_PTI<3>
  J42     25     25  SCONN60_QSH03001LDAKTR  I44
  U4     BE30  GPPC_B_4_GSXCLK  EMMITSBURG_REV0P9  I93

JTAG_TRC_PCH_PTI<4>   @S9S_MB_2U_LIB.S9S_MB_2U(SCH_1):JTAG_TRC_PCH_PTI<4>
  J42     27     27  SCONN60_QSH03001LDAKTR  I44
  U4     BF31  GPPC_B_5_USB2_OCB_0  EMMITSBURG_REV0P9  I93

JTAG_TRC_PCH_PTI<5>   @S9S_MB_2U_LIB.S9S_MB_2U(SCH_1):JTAG_TRC_PCH_PTI<5>
  J42     29     29  SCONN60_QSH03001LDAKTR  I44
  U4     BD29  GPPC_B_12_HS_UART0_RXD  EMMITSBURG_REV0P9  I93

JTAG_TRC_PCH_PTI<6>   @S9S_MB_2U_LIB.S9S_MB_2U(SCH_1):JTAG_TRC_PCH_PTI<6>
  J42     31     31  SCONN60_QSH03001LDAKTR  I44
  R2132    1      A  Q_RES       I74
  R2134    1      A  Q_RES       I83
  S1       8     B1  SW8S_DHNF04FTVTR   I4
  U4     BE28  GPPC_B_13_HS_UART0_TXD  EMMITSBURG_REV0P9  I93

JTAG_TRC_PCH_PTI<7>   @S9S_MB_2U_LIB.S9S_MB_2U(SCH_1):JTAG_TRC_PCH_PTI<7>
  J42     33     33  SCONN60_QSH03001LDAKTR  I44
  U4     BF29  GPPC_B_14_HS_UART0_RTS_N  EMMITSBURG_REV0P9  I93

JTAG_TRC_PCH_PTI<8>   @S9S_MB_2U_LIB.S9S_MB_2U(SCH_1):JTAG_TRC_PCH_PTI<8>
  J42     35     35  SCONN60_QSH03001LDAKTR  I44
  U4     BD27  GPPC_B_15_HS_UART0_CTS_N  EMMITSBURG_REV0P9  I93

JTAG_TRC_PCH_PTI<9>   @S9S_MB_2U_LIB.S9S_MB_2U(SCH_1):JTAG_TRC_PCH_PTI<9>
  J42     37     37  SCONN60_QSH03001LDAKTR  I44
  U4     BE26  GPPC_B_16_HS_UART1_RXD  EMMITSBURG_REV0P9  I93

JTAG_TRC_PCH_PTI<10>   @S9S_MB_2U_LIB.S9S_MB_2U(SCH_1):JTAG_TRC_PCH_PTI<10>
  J42     39     39  SCONN60_QSH03001LDAKTR  I44
  U4     BF27  GPPC_B_17_HS_UART1_TXD  EMMITSBURG_REV0P9  I93

JTAG_TRC_PCH_PTI<11>   @S9S_MB_2U_LIB.S9S_MB_2U(SCH_1):JTAG_TRC_PCH_PTI<11>
  J42     41     41  SCONN60_QSH03001LDAKTR  I44
  U4     BD25  GPPC_B_18_HS_UART1_RTS_N  EMMITSBURG_REV0P9  I93

JTAG_TRC_PCH_PTI<12>   @S9S_MB_2U_LIB.S9S_MB_2U(SCH_1):JTAG_TRC_PCH_PTI<12>
  J42     43     43  SCONN60_QSH03001LDAKTR  I44
  U4     BF25  GPPC_B_19_HS_UART1_CTS_N  EMMITSBURG_REV0P9  I93

JTAG_TRC_PCH_PTI<13>   @S9S_MB_2U_LIB.S9S_MB_2U(SCH_1):JTAG_TRC_PCH_PTI<13>
  J42     45     45  SCONN60_QSH03001LDAKTR  I44
  U4     BE24  GPPC_B_20  EMMITSBURG_REV0P9  I93

JTAG_TRC_PCH_PTI<14>   @S9S_MB_2U_LIB.S9S_MB_2U(SCH_1):JTAG_TRC_PCH_PTI<14>
  J42     47     47  SCONN60_QSH03001LDAKTR  I44
  U4     BF23  GPPC_B_21  EMMITSBURG_REV0P9  I93

JTAG_TRC_PCH_PTI<15>   @S9S_MB_2U_LIB.S9S_MB_2U(SCH_1):JTAG_TRC_PCH_PTI<15>
  J42     49     49  SCONN60_QSH03001LDAKTR  I44
  U4     BE22  GPPC_B_22  EMMITSBURG_REV0P9  I93

LED_CPU_RMCA_CATERR   @S9S_MB_2U_LIB.S9S_MB_2U(SCH_1):LED_CPU_RMCA_CATERR
  D6       A      A  Q_LED       I248
  R366     1      A  Q_RES       I246

LED_CPU_RMCA_CATERR_R   @S9S_MB_2U_LIB.S9S_MB_2U(SCH_1):LED_CPU_RMCA_CATERR_R
  Q33      S      S  MOSFET_PCH_GDS_ESD_PROTECTED  I242
  R366     2      B  Q_RES       I246

M2_SSD0_CLKREQ_EN_N   @S9S_MB_2U_LIB.S9S_MB_2U(SCH_1):M2_SSD0_CLKREQ_EN_N
  R486     1      A  Q_RES       I162
  R491     1      A  Q_RES       I164
  R1778    1      A  Q_RES       I244
  U54      2      A  74LVC1G07GV  I165

M2_SSD0_CLKREQ_EN_N_BUF   @S9S_MB_2U_LIB.S9S_MB_2U(SCH_1):M2_SSD0_CLKREQ_EN_N_BUF
  J59     52  CLKREQ#  SCONN75K_APCI0155P004A  I178
  R486     2      B  Q_RES       I162
  R487     2      B  Q_RES       I173

M2_SSD0_CLKREQ_LV_EN_N   @S9S_MB_2U_LIB.S9S_MB_2U(SCH_1):M2_SSD0_CLKREQ_LV_EN_N
  R1697    2      B  Q_RES       I186
  R1778    2      B  Q_RES       I244
  U4     BG16  GPPC_A_12_SRCCLKREQ_N_2  EMMITSBURG_REV0P9  I93
  U54      4      Y  74LVC1G07GV  I165

MB_FRU_ADDR0    @S9S_MB_2U_LIB.S9S_MB_2U(SCH_1):MB_FRU_ADDR0
  R721     2      B  Q_RES       I62
  R722     1      A  Q_RES       I61
  U64      1     E0  M24128BWDW6TP  I35

MB_FRU_ADDR1    @S9S_MB_2U_LIB.S9S_MB_2U(SCH_1):MB_FRU_ADDR1
  R717     2      B  Q_RES       I45
  R718     1      A  Q_RES       I50
  U64      2     E1  M24128BWDW6TP  I35

MB_FRU_ADDR2    @S9S_MB_2U_LIB.S9S_MB_2U(SCH_1):MB_FRU_ADDR2
  R713     2      B  Q_RES       I47
  R714     1      A  Q_RES       I52
  U64      3     E2  M24128BWDW6TP  I35

MP5981_0_CLREF   @S9S_MB_2U_LIB.S9S_MB_2U(SCH_1):MP5981_0_CLREF
  C1580    1      A  Q_CAP       I120
  R2075    1      A  Q_RES       I118
  U107    24  CLREF  MP5981GLUZ  I113

MP5981_0_CS     @S9S_MB_2U_LIB.S9S_MB_2U(SCH_1):MP5981_0_CS
  R2076    1      A  Q_RES       I122
  U107    23     CS  MP5981GLUZ  I113

MP5981_0_ON_PD   @S9S_MB_2U_LIB.S9S_MB_2U(SCH_1):MP5981_0_ON_PD
  C1582    1      A  Q_CAP       I142
  U107     4  ON||PD  MP5981GLUZ  I113

MP5981_1_CLREF   @S9S_MB_2U_LIB.S9S_MB_2U(SCH_1):MP5981_1_CLREF
  C1585    1      A  Q_CAP       I105
  R2087    1      A  Q_RES       I106
  U81     24  CLREF  MP5981GLUZ  I66

MP5981_1_CS     @S9S_MB_2U_LIB.S9S_MB_2U(SCH_1):MP5981_1_CS
  R2088    1      A  Q_RES       I107
  U81     23     CS  MP5981GLUZ  I66

MP5981_1_ON_PD   @S9S_MB_2U_LIB.S9S_MB_2U(SCH_1):MP5981_1_ON_PD
  C1584    1      A  Q_CAP       I68
  U81      4  ON||PD  MP5981GLUZ  I66

MPS5981_1_SS    @S9S_MB_2U_LIB.S9S_MB_2U(SCH_1):MPS5981_1_SS
  C1586    1      A  Q_CAP       I91
  U81     19     SS  MP5981GLUZ  I66

MPS5981_SS      @S9S_MB_2U_LIB.S9S_MB_2U(SCH_1):MPS5981_SS
  C1583    1      A  Q_CAP       I140
  U107    19     SS  MP5981GLUZ  I113

M_A_CPU0_ALERT_N   @S9S_MB_2U_LIB.S9S_MB_2U(SCH_1):M_A_CPU0_ALERT_N
  J1      62  ALERT_N  SCONN288_ADR50001P013C01  I198
  J2      62  ALERT_N  SCONN288_ADR50001P003C01  I177
  U2     AT49  DDR0_ALERT_N  SOCKET4677_AZIFS054P001C01   I1

M_A_CPU0_CLK_DN<0>   @S9S_MB_2U_LIB.S9S_MB_2U(SCH_1):M_A_CPU0_CLK_DN<0>
  J1     218   CK_N  SCONN288_ADR50001P013C01  I198
  U2     B44  DDR0_CLK_DN0  SOCKET4677_AZIFS054P001C01   I1

M_A_CPU0_CLK_DN<1>   @S9S_MB_2U_LIB.S9S_MB_2U(SCH_1):M_A_CPU0_CLK_DN<1>
  J2     218   CK_N  SCONN288_ADR50001P003C01  I177
  U2     G45  DDR0_CLK_DN1  SOCKET4677_AZIFS054P001C01   I1

M_A_CPU0_CLK_DP<0>   @S9S_MB_2U_LIB.S9S_MB_2U(SCH_1):M_A_CPU0_CLK_DP<0>
  J1     217   CK_P  SCONN288_ADR50001P013C01  I198
  U2     C43  DDR0_CLK_DP0  SOCKET4677_AZIFS054P001C01   I1

M_A_CPU0_CLK_DP<1>   @S9S_MB_2U_LIB.S9S_MB_2U(SCH_1):M_A_CPU0_CLK_DP<1>
  J2     217   CK_P  SCONN288_ADR50001P003C01  I177
  U2     E45  DDR0_CLK_DP1  SOCKET4677_AZIFS054P001C01   I1

M_A_CPU0_SA_CA<0>   @S9S_MB_2U_LIB.S9S_MB_2U(SCH_1):M_A_CPU0_SA_CA<0>
  J1      66  CA0_A  SCONN288_ADR50001P013C01  I198
  J2      66  CA0_A  SCONN288_ADR50001P003C01  I177
  U2     A52  DDR0_SA_CA0  SOCKET4677_AZIFS054P001C01   I1

M_A_CPU0_SA_CA<1>   @S9S_MB_2U_LIB.S9S_MB_2U(SCH_1):M_A_CPU0_SA_CA<1>
  J1     211  CA1_A  SCONN288_ADR50001P013C01  I198
  J2     211  CA1_A  SCONN288_ADR50001P003C01  I177
  U2     G52  DDR0_SA_CA1  SOCKET4677_AZIFS054P001C01   I1

M_A_CPU0_SA_CA<2>   @S9S_MB_2U_LIB.S9S_MB_2U(SCH_1):M_A_CPU0_SA_CA<2>
  J1      68  CA2_A  SCONN288_ADR50001P013C01  I198
  J2      68  CA2_A  SCONN288_ADR50001P003C01  I177
  U2     B51  DDR0_SA_CA2  SOCKET4677_AZIFS054P001C01   I1

M_A_CPU0_SA_CA<3>   @S9S_MB_2U_LIB.S9S_MB_2U(SCH_1):M_A_CPU0_SA_CA<3>
  J1     213  CA3_A  SCONN288_ADR50001P013C01  I198
  J2     213  CA3_A  SCONN288_ADR50001P003C01  I177
  U2     F51  DDR0_SA_CA3  SOCKET4677_AZIFS054P001C01   I1

M_A_CPU0_SA_CA<4>   @S9S_MB_2U_LIB.S9S_MB_2U(SCH_1):M_A_CPU0_SA_CA<4>
  J1      70  CA4_A  SCONN288_ADR50001P013C01  I198
  J2      70  CA4_A  SCONN288_ADR50001P003C01  I177
  U2     C50  DDR0_SA_CA4  SOCKET4677_AZIFS054P001C01   I1

M_A_CPU0_SA_CA<5>   @S9S_MB_2U_LIB.S9S_MB_2U(SCH_1):M_A_CPU0_SA_CA<5>
  J1     215  CA5_A  SCONN288_ADR50001P013C01  I198
  J2     215  CA5_A  SCONN288_ADR50001P003C01  I177
  U2     E50  DDR0_SA_CA5  SOCKET4677_AZIFS054P001C01   I1

M_A_CPU0_SA_CA<6>   @S9S_MB_2U_LIB.S9S_MB_2U(SCH_1):M_A_CPU0_SA_CA<6>
  J1      72  CA6_A  SCONN288_ADR50001P013C01  I198
  J2      72  CA6_A  SCONN288_ADR50001P003C01  I177
  U2     C48  DDR0_SA_CA6  SOCKET4677_AZIFS054P001C01   I1

M_A_CPU0_SA_CB<0>   @S9S_MB_2U_LIB.S9S_MB_2U(SCH_1):M_A_CPU0_SA_CB<0>
  J1      51  CB_A0  SCONN288_ADR50001P013C01  I198
  J2      51  CB_A0  SCONN288_ADR50001P003C01  I177
  U2     C60  DDR0_SA_ECC0  SOCKET4677_AZIFS054P001C01   I1

M_A_CPU0_SA_CB<1>   @S9S_MB_2U_LIB.S9S_MB_2U(SCH_1):M_A_CPU0_SA_CB<1>
  J1      53  CB_A1  SCONN288_ADR50001P013C01  I198
  J2      53  CB_A1  SCONN288_ADR50001P003C01  I177
  U2     B59  DDR0_SA_ECC1  SOCKET4677_AZIFS054P001C01   I1

M_A_CPU0_SA_CB<2>   @S9S_MB_2U_LIB.S9S_MB_2U(SCH_1):M_A_CPU0_SA_CB<2>
  J1     196  CB_A2  SCONN288_ADR50001P013C01  I198
  J2     196  CB_A2  SCONN288_ADR50001P003C01  I177
  U2     E60  DDR0_SA_ECC2  SOCKET4677_AZIFS054P001C01   I1

M_A_CPU0_SA_CB<3>   @S9S_MB_2U_LIB.S9S_MB_2U(SCH_1):M_A_CPU0_SA_CB<3>
  J1     198  CB_A3  SCONN288_ADR50001P013C01  I198
  J2     198  CB_A3  SCONN288_ADR50001P003C01  I177
  U2     F59  DDR0_SA_ECC3  SOCKET4677_AZIFS054P001C01   I1

M_A_CPU0_SA_CB<4>   @S9S_MB_2U_LIB.S9S_MB_2U(SCH_1):M_A_CPU0_SA_CB<4>
  J1      58  CB_A4  SCONN288_ADR50001P013C01  I198
  J2      58  CB_A4  SCONN288_ADR50001P003C01  I177
  U2     B57  DDR0_SA_ECC4  SOCKET4677_AZIFS054P001C01   I1

M_A_CPU0_SA_CB<5>   @S9S_MB_2U_LIB.S9S_MB_2U(SCH_1):M_A_CPU0_SA_CB<5>
  J1      60  CB_A5  SCONN288_ADR50001P013C01  I198
  J2      60  CB_A5  SCONN288_ADR50001P003C01  I177
  U2     C56  DDR0_SA_ECC5  SOCKET4677_AZIFS054P001C01   I1

M_A_CPU0_SA_CB<6>   @S9S_MB_2U_LIB.S9S_MB_2U(SCH_1):M_A_CPU0_SA_CB<6>
  J1     203  CB_A6  SCONN288_ADR50001P013C01  I198
  J2     203  CB_A6  SCONN288_ADR50001P003C01  I177
  U2     F57  DDR0_SA_ECC6  SOCKET4677_AZIFS054P001C01   I1

M_A_CPU0_SA_CB<7>   @S9S_MB_2U_LIB.S9S_MB_2U(SCH_1):M_A_CPU0_SA_CB<7>
  J1     205  CB_A7  SCONN288_ADR50001P013C01  I198
  J2     205  CB_A7  SCONN288_ADR50001P003C01  I177
  U2     E56  DDR0_SA_ECC7  SOCKET4677_AZIFS054P001C01   I1

M_A_CPU0_SA_CS_N<0>   @S9S_MB_2U_LIB.S9S_MB_2U(SCH_1):M_A_CPU0_SA_CS_N<0>
  J1      64  CS0_N_A  SCONN288_ADR50001P013C01  I198
  U2     C54  DDR0_SA_CS0_N  SOCKET4677_AZIFS054P001C01   I1

M_A_CPU0_SA_CS_N<1>   @S9S_MB_2U_LIB.S9S_MB_2U(SCH_1):M_A_CPU0_SA_CS_N<1>
  J1     209  CS1_N_A  SCONN288_ADR50001P013C01  I198
  U2     B53  DDR0_SA_CS1_N  SOCKET4677_AZIFS054P001C01   I1

M_A_CPU0_SA_CS_N<2>   @S9S_MB_2U_LIB.S9S_MB_2U(SCH_1):M_A_CPU0_SA_CS_N<2>
  J2      64  CS0_N_A  SCONN288_ADR50001P003C01  I177
  U2     E54  DDR0_SA_CS2_N  SOCKET4677_AZIFS054P001C01   I1

M_A_CPU0_SA_CS_N<3>   @S9S_MB_2U_LIB.S9S_MB_2U(SCH_1):M_A_CPU0_SA_CS_N<3>
  J2     209  CS1_N_A  SCONN288_ADR50001P003C01  I177
  U2     F53  DDR0_SA_CS3_N  SOCKET4677_AZIFS054P001C01   I1

M_A_CPU0_SA_DQ<0>   @S9S_MB_2U_LIB.S9S_MB_2U(SCH_1):M_A_CPU0_SA_DQ<0>
  J1       7  DQ_A0  SCONN288_ADR50001P013C01  I198
  J2       7  DQ_A0  SCONN288_ADR50001P003C01  I177
  U2     B81  DDR0_SA_DQ0  SOCKET4677_AZIFS054P001C01   I1

M_A_CPU0_SA_DQ<1>   @S9S_MB_2U_LIB.S9S_MB_2U(SCH_1):M_A_CPU0_SA_DQ<1>
  J1       9  DQ_A1  SCONN288_ADR50001P013C01  I198
  J2       9  DQ_A1  SCONN288_ADR50001P003C01  I177
  U2     B79  DDR0_SA_DQ1  SOCKET4677_AZIFS054P001C01   I1

M_A_CPU0_SA_DQ<2>   @S9S_MB_2U_LIB.S9S_MB_2U(SCH_1):M_A_CPU0_SA_DQ<2>
  J1     152  DQ_A2  SCONN288_ADR50001P013C01  I198
  J2     152  DQ_A2  SCONN288_ADR50001P003C01  I177
  U2     M77  DDR0_SA_DQ2  SOCKET4677_AZIFS054P001C01   I1

M_A_CPU0_SA_DQ<3>   @S9S_MB_2U_LIB.S9S_MB_2U(SCH_1):M_A_CPU0_SA_DQ<3>
  J1     154  DQ_A3  SCONN288_ADR50001P013C01  I198
  J2     154  DQ_A3  SCONN288_ADR50001P003C01  I177
  U2     G78  DDR0_SA_DQ3  SOCKET4677_AZIFS054P001C01   I1

M_A_CPU0_SA_DQ<4>   @S9S_MB_2U_LIB.S9S_MB_2U(SCH_1):M_A_CPU0_SA_DQ<4>
  J1      14  DQ_A4  SCONN288_ADR50001P013C01  I198
  J2      14  DQ_A4  SCONN288_ADR50001P003C01  I177
  U2     C76  DDR0_SA_DQ4  SOCKET4677_AZIFS054P001C01   I1

M_A_CPU0_SA_DQ<5>   @S9S_MB_2U_LIB.S9S_MB_2U(SCH_1):M_A_CPU0_SA_DQ<5>
  J1      16  DQ_A5  SCONN288_ADR50001P013C01  I198
  J2      16  DQ_A5  SCONN288_ADR50001P003C01  I177
  U2     D75  DDR0_SA_DQ5  SOCKET4677_AZIFS054P001C01   I1

M_A_CPU0_SA_DQ<6>   @S9S_MB_2U_LIB.S9S_MB_2U(SCH_1):M_A_CPU0_SA_DQ<6>
  J1     159  DQ_A6  SCONN288_ADR50001P013C01  I198
  J2     159  DQ_A6  SCONN288_ADR50001P003C01  I177
  U2     G76  DDR0_SA_DQ6  SOCKET4677_AZIFS054P001C01   I1

M_A_CPU0_SA_DQ<7>   @S9S_MB_2U_LIB.S9S_MB_2U(SCH_1):M_A_CPU0_SA_DQ<7>
  J1     161  DQ_A7  SCONN288_ADR50001P013C01  I198
  J2     161  DQ_A7  SCONN288_ADR50001P003C01  I177
  U2     F75  DDR0_SA_DQ7  SOCKET4677_AZIFS054P001C01   I1

M_A_CPU0_SA_DQ<8>   @S9S_MB_2U_LIB.S9S_MB_2U(SCH_1):M_A_CPU0_SA_DQ<8>
  J1      18  DQ_A8  SCONN288_ADR50001P013C01  I198
  J2      18  DQ_A8  SCONN288_ADR50001P003C01  I177
  U2     K69  DDR0_SA_DQ8  SOCKET4677_AZIFS054P001C01   I1

M_A_CPU0_SA_DQ<9>   @S9S_MB_2U_LIB.S9S_MB_2U(SCH_1):M_A_CPU0_SA_DQ<9>
  J1      20  DQ_A9  SCONN288_ADR50001P013C01  I198
  J2      20  DQ_A9  SCONN288_ADR50001P003C01  I177
  U2     J68  DDR0_SA_DQ9  SOCKET4677_AZIFS054P001C01   I1

M_A_CPU0_SA_DQ<10>   @S9S_MB_2U_LIB.S9S_MB_2U(SCH_1):M_A_CPU0_SA_DQ<10>
  J1     163  DQ_A10  SCONN288_ADR50001P013C01  I198
  J2     163  DQ_A10  SCONN288_ADR50001P003C01  I177
  U2     M69  DDR0_SA_DQ10  SOCKET4677_AZIFS054P001C01   I1

M_A_CPU0_SA_DQ<11>   @S9S_MB_2U_LIB.S9S_MB_2U(SCH_1):M_A_CPU0_SA_DQ<11>
  J1     165  DQ_A11  SCONN288_ADR50001P013C01  I198
  J2     165  DQ_A11  SCONN288_ADR50001P003C01  I177
  U2     N68  DDR0_SA_DQ11  SOCKET4677_AZIFS054P001C01   I1

M_A_CPU0_SA_DQ<12>   @S9S_MB_2U_LIB.S9S_MB_2U(SCH_1):M_A_CPU0_SA_DQ<12>
  J1      25  DQ_A12  SCONN288_ADR50001P013C01  I198
  J2      25  DQ_A12  SCONN288_ADR50001P003C01  I177
  U2     J66  DDR0_SA_DQ12  SOCKET4677_AZIFS054P001C01   I1

M_A_CPU0_SA_DQ<13>   @S9S_MB_2U_LIB.S9S_MB_2U(SCH_1):M_A_CPU0_SA_DQ<13>
  J1      27  DQ_A13  SCONN288_ADR50001P013C01  I198
  J2      27  DQ_A13  SCONN288_ADR50001P003C01  I177
  U2     K65  DDR0_SA_DQ13  SOCKET4677_AZIFS054P001C01   I1

M_A_CPU0_SA_DQ<14>   @S9S_MB_2U_LIB.S9S_MB_2U(SCH_1):M_A_CPU0_SA_DQ<14>
  J1     170  DQ_A14  SCONN288_ADR50001P013C01  I198
  J2     170  DQ_A14  SCONN288_ADR50001P003C01  I177
  U2     N66  DDR0_SA_DQ14  SOCKET4677_AZIFS054P001C01   I1

M_A_CPU0_SA_DQ<15>   @S9S_MB_2U_LIB.S9S_MB_2U(SCH_1):M_A_CPU0_SA_DQ<15>
  J1     172  DQ_A15  SCONN288_ADR50001P013C01  I198
  J2     172  DQ_A15  SCONN288_ADR50001P003C01  I177
  U2     M65  DDR0_SA_DQ15  SOCKET4677_AZIFS054P001C01   I1

M_A_CPU0_SA_DQ<16>   @S9S_MB_2U_LIB.S9S_MB_2U(SCH_1):M_A_CPU0_SA_DQ<16>
  J1      29  DQ_A16  SCONN288_ADR50001P013C01  I198
  J2      29  DQ_A16  SCONN288_ADR50001P003C01  I177
  U2     B73  DDR0_SA_DQ16  SOCKET4677_AZIFS054P001C01   I1

M_A_CPU0_SA_DQ<17>   @S9S_MB_2U_LIB.S9S_MB_2U(SCH_1):M_A_CPU0_SA_DQ<17>
  J1      31  DQ_A17  SCONN288_ADR50001P013C01  I198
  J2      31  DQ_A17  SCONN288_ADR50001P003C01  I177
  U2     E72  DDR0_SA_DQ17  SOCKET4677_AZIFS054P001C01   I1

M_A_CPU0_SA_DQ<18>   @S9S_MB_2U_LIB.S9S_MB_2U(SCH_1):M_A_CPU0_SA_DQ<18>
  J1     174  DQ_A18  SCONN288_ADR50001P013C01  I198
  J2     174  DQ_A18  SCONN288_ADR50001P003C01  I177
  U2     D73  DDR0_SA_DQ18  SOCKET4677_AZIFS054P001C01   I1

M_A_CPU0_SA_DQ<19>   @S9S_MB_2U_LIB.S9S_MB_2U(SCH_1):M_A_CPU0_SA_DQ<19>
  J1     176  DQ_A19  SCONN288_ADR50001P013C01  I198
  J2     176  DQ_A19  SCONN288_ADR50001P003C01  I177
  U2     F71  DDR0_SA_DQ19  SOCKET4677_AZIFS054P001C01   I1

M_A_CPU0_SA_DQ<20>   @S9S_MB_2U_LIB.S9S_MB_2U(SCH_1):M_A_CPU0_SA_DQ<20>
  J1      36  DQ_A20  SCONN288_ADR50001P013C01  I198
  J2      36  DQ_A20  SCONN288_ADR50001P003C01  I177
  U2     B69  DDR0_SA_DQ20  SOCKET4677_AZIFS054P001C01   I1

M_A_CPU0_SA_DQ<21>   @S9S_MB_2U_LIB.S9S_MB_2U(SCH_1):M_A_CPU0_SA_DQ<21>
  J1      38  DQ_A21  SCONN288_ADR50001P013C01  I198
  J2      38  DQ_A21  SCONN288_ADR50001P003C01  I177
  U2     C68  DDR0_SA_DQ21  SOCKET4677_AZIFS054P001C01   I1

M_A_CPU0_SA_DQ<22>   @S9S_MB_2U_LIB.S9S_MB_2U(SCH_1):M_A_CPU0_SA_DQ<22>
  J1     181  DQ_A22  SCONN288_ADR50001P013C01  I198
  J2     181  DQ_A22  SCONN288_ADR50001P003C01  I177
  U2     F69  DDR0_SA_DQ22  SOCKET4677_AZIFS054P001C01   I1

M_A_CPU0_SA_DQ<23>   @S9S_MB_2U_LIB.S9S_MB_2U(SCH_1):M_A_CPU0_SA_DQ<23>
  J1     183  DQ_A23  SCONN288_ADR50001P013C01  I198
  J2     183  DQ_A23  SCONN288_ADR50001P003C01  I177
  U2     E68  DDR0_SA_DQ23  SOCKET4677_AZIFS054P001C01   I1

M_A_CPU0_SA_DQ<24>   @S9S_MB_2U_LIB.S9S_MB_2U(SCH_1):M_A_CPU0_SA_DQ<24>
  J1      40  DQ_A24  SCONN288_ADR50001P013C01  I198
  J2      40  DQ_A24  SCONN288_ADR50001P003C01  I177
  U2     C66  DDR0_SA_DQ24  SOCKET4677_AZIFS054P001C01   I1

M_A_CPU0_SA_DQ<25>   @S9S_MB_2U_LIB.S9S_MB_2U(SCH_1):M_A_CPU0_SA_DQ<25>
  J1      42  DQ_A25  SCONN288_ADR50001P013C01  I198
  J2      42  DQ_A25  SCONN288_ADR50001P003C01  I177
  U2     B65  DDR0_SA_DQ25  SOCKET4677_AZIFS054P001C01   I1

M_A_CPU0_SA_DQ<26>   @S9S_MB_2U_LIB.S9S_MB_2U(SCH_1):M_A_CPU0_SA_DQ<26>
  J1     185  DQ_A26  SCONN288_ADR50001P013C01  I198
  J2     185  DQ_A26  SCONN288_ADR50001P003C01  I177
  U2     E66  DDR0_SA_DQ26  SOCKET4677_AZIFS054P001C01   I1

M_A_CPU0_SA_DQ<27>   @S9S_MB_2U_LIB.S9S_MB_2U(SCH_1):M_A_CPU0_SA_DQ<27>
  J1     187  DQ_A27  SCONN288_ADR50001P013C01  I198
  J2     187  DQ_A27  SCONN288_ADR50001P003C01  I177
  U2     F65  DDR0_SA_DQ27  SOCKET4677_AZIFS054P001C01   I1

M_A_CPU0_SA_DQ<28>   @S9S_MB_2U_LIB.S9S_MB_2U(SCH_1):M_A_CPU0_SA_DQ<28>
  J1      47  DQ_A28  SCONN288_ADR50001P013C01  I198
  J2      47  DQ_A28  SCONN288_ADR50001P003C01  I177
  U2     B63  DDR0_SA_DQ28  SOCKET4677_AZIFS054P001C01   I1

M_A_CPU0_SA_DQ<29>   @S9S_MB_2U_LIB.S9S_MB_2U(SCH_1):M_A_CPU0_SA_DQ<29>
  J1      49  DQ_A29  SCONN288_ADR50001P013C01  I198
  J2      49  DQ_A29  SCONN288_ADR50001P003C01  I177
  U2     C62  DDR0_SA_DQ29  SOCKET4677_AZIFS054P001C01   I1

M_A_CPU0_SA_DQ<30>   @S9S_MB_2U_LIB.S9S_MB_2U(SCH_1):M_A_CPU0_SA_DQ<30>
  J1     192  DQ_A30  SCONN288_ADR50001P013C01  I198
  J2     192  DQ_A30  SCONN288_ADR50001P003C01  I177
  U2     F63  DDR0_SA_DQ30  SOCKET4677_AZIFS054P001C01   I1

M_A_CPU0_SA_DQ<31>   @S9S_MB_2U_LIB.S9S_MB_2U(SCH_1):M_A_CPU0_SA_DQ<31>
  J1     194  DQ_A31  SCONN288_ADR50001P013C01  I198
  J2     194  DQ_A31  SCONN288_ADR50001P003C01  I177
  U2     E62  DDR0_SA_DQ31  SOCKET4677_AZIFS054P001C01   I1

M_A_CPU0_SA_DQS_DN<0>   @S9S_MB_2U_LIB.S9S_MB_2U(SCH_1):M_A_CPU0_SA_DQS_DN<0>
  J1      12  DQS0_A_N  SCONN288_ADR50001P013C01  I199
  J2      12  DQS0_A_N  SCONN288_ADR50001P003C01  I178
  U2     B77  DDR0_SA_DQS_DN0  SOCKET4677_AZIFS054P001C01   I1

M_A_CPU0_SA_DQS_DN<1>   @S9S_MB_2U_LIB.S9S_MB_2U(SCH_1):M_A_CPU0_SA_DQS_DN<1>
  J1      23  DQS1_A_N  SCONN288_ADR50001P013C01  I199
  J2      23  DQS1_A_N  SCONN288_ADR50001P003C01  I178
  U2     H67  DDR0_SA_DQS_DN1  SOCKET4677_AZIFS054P001C01   I1

M_A_CPU0_SA_DQS_DN<2>   @S9S_MB_2U_LIB.S9S_MB_2U(SCH_1):M_A_CPU0_SA_DQS_DN<2>
  J1      34  DQS2_A_N  SCONN288_ADR50001P013C01  I199
  J2      34  DQS2_A_N  SCONN288_ADR50001P003C01  I178
  U2     B71  DDR0_SA_DQS_DN2  SOCKET4677_AZIFS054P001C01   I1

M_A_CPU0_SA_DQS_DN<3>   @S9S_MB_2U_LIB.S9S_MB_2U(SCH_1):M_A_CPU0_SA_DQS_DN<3>
  J1      45  DQS3_A_N  SCONN288_ADR50001P013C01  I199
  J2      45  DQS3_A_N  SCONN288_ADR50001P003C01  I178
  U2     A64  DDR0_SA_DQS_DN3  SOCKET4677_AZIFS054P001C01   I1

M_A_CPU0_SA_DQS_DN<4>   @S9S_MB_2U_LIB.S9S_MB_2U(SCH_1):M_A_CPU0_SA_DQS_DN<4>
  J1      56  DQS4_A_N  SCONN288_ADR50001P013C01  I199
  J2      56  DQS4_A_N  SCONN288_ADR50001P003C01  I178
  U2     A58  DDR0_SA_DQS_DN4  SOCKET4677_AZIFS054P001C01   I1

M_A_CPU0_SA_DQS_DN<5>   @S9S_MB_2U_LIB.S9S_MB_2U(SCH_1):M_A_CPU0_SA_DQS_DN<5>
  J1     156  DQS5_A_N  SCONN288_ADR50001P013C01  I199
  J2     156  DQS5_A_N  SCONN288_ADR50001P003C01  I178
  U2     H77  DDR0_SA_DQS_DN5  SOCKET4677_AZIFS054P001C01   I1

M_A_CPU0_SA_DQS_DN<6>   @S9S_MB_2U_LIB.S9S_MB_2U(SCH_1):M_A_CPU0_SA_DQS_DN<6>
  J1     167  DQS6_A_N  SCONN288_ADR50001P013C01  I199
  J2     167  DQS6_A_N  SCONN288_ADR50001P003C01  I178
  U2     P67  DDR0_SA_DQS_DN6  SOCKET4677_AZIFS054P001C01   I1

M_A_CPU0_SA_DQS_DN<7>   @S9S_MB_2U_LIB.S9S_MB_2U(SCH_1):M_A_CPU0_SA_DQS_DN<7>
  J1     178  DQS7_A_N  SCONN288_ADR50001P013C01  I199
  J2     178  DQS7_A_N  SCONN288_ADR50001P003C01  I178
  U2     G70  DDR0_SA_DQS_DN7  SOCKET4677_AZIFS054P001C01   I1

M_A_CPU0_SA_DQS_DN<8>   @S9S_MB_2U_LIB.S9S_MB_2U(SCH_1):M_A_CPU0_SA_DQS_DN<8>
  J1     189  DQS8_A_N  SCONN288_ADR50001P013C01  I199
  J2     189  DQS8_A_N  SCONN288_ADR50001P003C01  I178
  U2     G64  DDR0_SA_DQS_DN8  SOCKET4677_AZIFS054P001C01   I1

M_A_CPU0_SA_DQS_DN<9>   @S9S_MB_2U_LIB.S9S_MB_2U(SCH_1):M_A_CPU0_SA_DQS_DN<9>
  J1     200  DQS9_A_N  SCONN288_ADR50001P013C01  I199
  J2     200  DQS9_A_N  SCONN288_ADR50001P003C01  I178
  U2     G58  DDR0_SA_DQS_DN9  SOCKET4677_AZIFS054P001C01   I1

M_A_CPU0_SA_DQS_DP<0>   @S9S_MB_2U_LIB.S9S_MB_2U(SCH_1):M_A_CPU0_SA_DQS_DP<0>
  J1      11  DQS0_A_P  SCONN288_ADR50001P013C01  I199
  J2      11  DQS0_A_P  SCONN288_ADR50001P003C01  I178
  U2     D77  DDR0_SA_DQS_DP0  SOCKET4677_AZIFS054P001C01   I1

M_A_CPU0_SA_DQS_DP<1>   @S9S_MB_2U_LIB.S9S_MB_2U(SCH_1):M_A_CPU0_SA_DQS_DP<1>
  J1      22  DQS1_A_P  SCONN288_ADR50001P013C01  I199
  J2      22  DQS1_A_P  SCONN288_ADR50001P003C01  I178
  U2     K67  DDR0_SA_DQS_DP1  SOCKET4677_AZIFS054P001C01   I1

M_A_CPU0_SA_DQS_DP<2>   @S9S_MB_2U_LIB.S9S_MB_2U(SCH_1):M_A_CPU0_SA_DQS_DP<2>
  J1      33  DQS2_A_P  SCONN288_ADR50001P013C01  I199
  J2      33  DQS2_A_P  SCONN288_ADR50001P003C01  I178
  U2     C70  DDR0_SA_DQS_DP2  SOCKET4677_AZIFS054P001C01   I1

M_A_CPU0_SA_DQS_DP<3>   @S9S_MB_2U_LIB.S9S_MB_2U(SCH_1):M_A_CPU0_SA_DQS_DP<3>
  J1      44  DQS3_A_P  SCONN288_ADR50001P013C01  I199
  J2      44  DQS3_A_P  SCONN288_ADR50001P003C01  I178
  U2     C64  DDR0_SA_DQS_DP3  SOCKET4677_AZIFS054P001C01   I1

M_A_CPU0_SA_DQS_DP<4>   @S9S_MB_2U_LIB.S9S_MB_2U(SCH_1):M_A_CPU0_SA_DQS_DP<4>
  J1      55  DQS4_A_P  SCONN288_ADR50001P013C01  I199
  J2      55  DQS4_A_P  SCONN288_ADR50001P003C01  I178
  U2     C58  DDR0_SA_DQS_DP4  SOCKET4677_AZIFS054P001C01   I1

M_A_CPU0_SA_DQS_DP<5>   @S9S_MB_2U_LIB.S9S_MB_2U(SCH_1):M_A_CPU0_SA_DQS_DP<5>
  J1     157  DQS5_A_P  SCONN288_ADR50001P013C01  I199
  J2     157  DQS5_A_P  SCONN288_ADR50001P003C01  I178
  U2     F77  DDR0_SA_DQS_DP5  SOCKET4677_AZIFS054P001C01   I1

M_A_CPU0_SA_DQS_DP<6>   @S9S_MB_2U_LIB.S9S_MB_2U(SCH_1):M_A_CPU0_SA_DQS_DP<6>
  J1     168  DQS6_A_P  SCONN288_ADR50001P013C01  I199
  J2     168  DQS6_A_P  SCONN288_ADR50001P003C01  I178
  U2     M67  DDR0_SA_DQS_DP6  SOCKET4677_AZIFS054P001C01   I1

M_A_CPU0_SA_DQS_DP<7>   @S9S_MB_2U_LIB.S9S_MB_2U(SCH_1):M_A_CPU0_SA_DQS_DP<7>
  J1     179  DQS7_A_P  SCONN288_ADR50001P013C01  I199
  J2     179  DQS7_A_P  SCONN288_ADR50001P003C01  I178
  U2     E70  DDR0_SA_DQS_DP7  SOCKET4677_AZIFS054P001C01   I1

M_A_CPU0_SA_DQS_DP<8>   @S9S_MB_2U_LIB.S9S_MB_2U(SCH_1):M_A_CPU0_SA_DQS_DP<8>
  J1     190  DQS8_A_P  SCONN288_ADR50001P013C01  I199
  J2     190  DQS8_A_P  SCONN288_ADR50001P003C01  I178
  U2     E64  DDR0_SA_DQS_DP8  SOCKET4677_AZIFS054P001C01   I1

M_A_CPU0_SA_DQS_DP<9>   @S9S_MB_2U_LIB.S9S_MB_2U(SCH_1):M_A_CPU0_SA_DQS_DP<9>
  J1     201  DQS9_A_P  SCONN288_ADR50001P013C01  I199
  J2     201  DQS9_A_P  SCONN288_ADR50001P003C01  I178
  U2     E58  DDR0_SA_DQS_DP9  SOCKET4677_AZIFS054P001C01   I1

M_A_CPU0_SA_PAR   @S9S_MB_2U_LIB.S9S_MB_2U(SCH_1):M_A_CPU0_SA_PAR
  J1      74  PAR_A  SCONN288_ADR50001P013C01  I198
  J2      74  PAR_A  SCONN288_ADR50001P003C01  I177
  U2     E48  DDR0_SA_PAR  SOCKET4677_AZIFS054P001C01   I1

M_A_CPU0_SA_RSP<0>   @S9S_MB_2U_LIB.S9S_MB_2U(SCH_1):M_A_CPU0_SA_RSP<0>
  J1      86  LBD||RSP_N_A  SCONN288_ADR50001P013C01  I198
  U2     AT42  DDR0_A_RSP0  SOCKET4677_AZIFS054P001C01   I1

M_A_CPU0_SA_RSP<1>   @S9S_MB_2U_LIB.S9S_MB_2U(SCH_1):M_A_CPU0_SA_RSP<1>
  J2      86  LBD||RSP_N_A  SCONN288_ADR50001P003C01  I177
  U2     AU43  DDR0_A_RSP1  SOCKET4677_AZIFS054P001C01   I1

M_A_CPU0_SB_CA<0>   @S9S_MB_2U_LIB.S9S_MB_2U(SCH_1):M_A_CPU0_SB_CA<0>
  J1      76  CA0_B  SCONN288_ADR50001P013C01  I198
  J2      76  CA0_B  SCONN288_ADR50001P003C01  I177
  U2     E43  DDR0_SB_CA0  SOCKET4677_AZIFS054P001C01   I1

M_A_CPU0_SB_CA<1>   @S9S_MB_2U_LIB.S9S_MB_2U(SCH_1):M_A_CPU0_SB_CA<1>
  J1     221  CA1_B  SCONN288_ADR50001P013C01  I198
  J2     221  CA1_B  SCONN288_ADR50001P003C01  I177
  U2     F44  DDR0_SB_CA1  SOCKET4677_AZIFS054P001C01   I1

M_A_CPU0_SB_CA<2>   @S9S_MB_2U_LIB.S9S_MB_2U(SCH_1):M_A_CPU0_SB_CA<2>
  J1      78  CA2_B  SCONN288_ADR50001P013C01  I198
  J2      78  CA2_B  SCONN288_ADR50001P003C01  I177
  U2     C41  DDR0_SB_CA2  SOCKET4677_AZIFS054P001C01   I1

M_A_CPU0_SB_CA<3>   @S9S_MB_2U_LIB.S9S_MB_2U(SCH_1):M_A_CPU0_SB_CA<3>
  J1     223  CA3_B  SCONN288_ADR50001P013C01  I198
  J2     223  CA3_B  SCONN288_ADR50001P003C01  I177
  U2     E41  DDR0_SB_CA3  SOCKET4677_AZIFS054P001C01   I1

M_A_CPU0_SB_CA<4>   @S9S_MB_2U_LIB.S9S_MB_2U(SCH_1):M_A_CPU0_SB_CA<4>
  J1      80  CA4_B  SCONN288_ADR50001P013C01  I198
  J2      80  CA4_B  SCONN288_ADR50001P003C01  I177
  U2     B40  DDR0_SB_CA4  SOCKET4677_AZIFS054P001C01   I1

M_A_CPU0_SB_CA<5>   @S9S_MB_2U_LIB.S9S_MB_2U(SCH_1):M_A_CPU0_SB_CA<5>
  J1     225  CA5_B  SCONN288_ADR50001P013C01  I198
  J2     225  CA5_B  SCONN288_ADR50001P003C01  I177
  U2     F40  DDR0_SB_CA5  SOCKET4677_AZIFS054P001C01   I1

M_A_CPU0_SB_CA<6>   @S9S_MB_2U_LIB.S9S_MB_2U(SCH_1):M_A_CPU0_SB_CA<6>
  J1      82  CA6_B  SCONN288_ADR50001P013C01  I198
  J2      82  CA6_B  SCONN288_ADR50001P003C01  I177
  U2     A39  DDR0_SB_CA6  SOCKET4677_AZIFS054P001C01   I1

M_A_CPU0_SB_CB<0>   @S9S_MB_2U_LIB.S9S_MB_2U(SCH_1):M_A_CPU0_SB_CB<0>
  J1      96  CB_B0  SCONN288_ADR50001P013C01  I198
  J2      96  CB_B0  SCONN288_ADR50001P003C01  I177
  U2     B32  DDR0_SB_ECC0  SOCKET4677_AZIFS054P001C01   I1

M_A_CPU0_SB_CB<1>   @S9S_MB_2U_LIB.S9S_MB_2U(SCH_1):M_A_CPU0_SB_CB<1>
  J1      98  CB_B1  SCONN288_ADR50001P013C01  I198
  J2      98  CB_B1  SCONN288_ADR50001P003C01  I177
  U2     C31  DDR0_SB_ECC1  SOCKET4677_AZIFS054P001C01   I1

M_A_CPU0_SB_CB<2>   @S9S_MB_2U_LIB.S9S_MB_2U(SCH_1):M_A_CPU0_SB_CB<2>
  J1     241  CB_B2  SCONN288_ADR50001P013C01  I198
  J2     241  CB_B2  SCONN288_ADR50001P003C01  I177
  U2     F32  DDR0_SB_ECC2  SOCKET4677_AZIFS054P001C01   I1

M_A_CPU0_SB_CB<3>   @S9S_MB_2U_LIB.S9S_MB_2U(SCH_1):M_A_CPU0_SB_CB<3>
  J1     243  CB_B3  SCONN288_ADR50001P013C01  I198
  J2     243  CB_B3  SCONN288_ADR50001P003C01  I177
  U2     E31  DDR0_SB_ECC3  SOCKET4677_AZIFS054P001C01   I1

M_A_CPU0_SB_CB<4>   @S9S_MB_2U_LIB.S9S_MB_2U(SCH_1):M_A_CPU0_SB_CB<4>
  J1      89  CB_B4  SCONN288_ADR50001P013C01  I198
  J2      89  CB_B4  SCONN288_ADR50001P003C01  I177
  U2     C35  DDR0_SB_ECC4  SOCKET4677_AZIFS054P001C01   I1

M_A_CPU0_SB_CB<5>   @S9S_MB_2U_LIB.S9S_MB_2U(SCH_1):M_A_CPU0_SB_CB<5>
  J1      91  CB_B5  SCONN288_ADR50001P013C01  I198
  J2      91  CB_B5  SCONN288_ADR50001P003C01  I177
  U2     B34  DDR0_SB_ECC5  SOCKET4677_AZIFS054P001C01   I1

M_A_CPU0_SB_CB<6>   @S9S_MB_2U_LIB.S9S_MB_2U(SCH_1):M_A_CPU0_SB_CB<6>
  J1     234  CB_B6  SCONN288_ADR50001P013C01  I198
  J2     234  CB_B6  SCONN288_ADR50001P003C01  I177
  U2     E35  DDR0_SB_ECC6  SOCKET4677_AZIFS054P001C01   I1

M_A_CPU0_SB_CB<7>   @S9S_MB_2U_LIB.S9S_MB_2U(SCH_1):M_A_CPU0_SB_CB<7>
  J1     236  CB_B7  SCONN288_ADR50001P013C01  I198
  J2     236  CB_B7  SCONN288_ADR50001P003C01  I177
  U2     F34  DDR0_SB_ECC7  SOCKET4677_AZIFS054P001C01   I1

M_A_CPU0_SB_CS_N<0>   @S9S_MB_2U_LIB.S9S_MB_2U(SCH_1):M_A_CPU0_SB_CS_N<0>
  J1      84  CS0_N_B  SCONN288_ADR50001P013C01  I198
  U2     B38  DDR0_SB_CS0_N  SOCKET4677_AZIFS054P001C01   I1

M_A_CPU0_SB_CS_N<1>   @S9S_MB_2U_LIB.S9S_MB_2U(SCH_1):M_A_CPU0_SB_CS_N<1>
  J1     229  CS1_N_B  SCONN288_ADR50001P013C01  I198
  U2     C37  DDR0_SB_CS1_N  SOCKET4677_AZIFS054P001C01   I1

M_A_CPU0_SB_CS_N<2>   @S9S_MB_2U_LIB.S9S_MB_2U(SCH_1):M_A_CPU0_SB_CS_N<2>
  J2      84  CS0_N_B  SCONN288_ADR50001P003C01  I177
  U2     F38  DDR0_SB_CS2_N  SOCKET4677_AZIFS054P001C01   I1

M_A_CPU0_SB_CS_N<3>   @S9S_MB_2U_LIB.S9S_MB_2U(SCH_1):M_A_CPU0_SB_CS_N<3>
  J2     229  CS1_N_B  SCONN288_ADR50001P003C01  I177
  U2     E37  DDR0_SB_CS3_N  SOCKET4677_AZIFS054P001C01   I1

M_A_CPU0_SB_DQ<0>   @S9S_MB_2U_LIB.S9S_MB_2U(SCH_1):M_A_CPU0_SB_DQ<0>
  J1     100  DQ_B0  SCONN288_ADR50001P013C01  I198
  J2     100  DQ_B0  SCONN288_ADR50001P003C01  I177
  U2     K32  DDR0_SB_DQ0  SOCKET4677_AZIFS054P001C01   I1

M_A_CPU0_SB_DQ<1>   @S9S_MB_2U_LIB.S9S_MB_2U(SCH_1):M_A_CPU0_SB_DQ<1>
  J1     102  DQ_B1  SCONN288_ADR50001P013C01  I198
  J2     102  DQ_B1  SCONN288_ADR50001P003C01  I177
  U2     J31  DDR0_SB_DQ1  SOCKET4677_AZIFS054P001C01   I1

M_A_CPU0_SB_DQ<2>   @S9S_MB_2U_LIB.S9S_MB_2U(SCH_1):M_A_CPU0_SB_DQ<2>
  J1     245  DQ_B2  SCONN288_ADR50001P013C01  I198
  J2     245  DQ_B2  SCONN288_ADR50001P003C01  I177
  U2     M32  DDR0_SB_DQ2  SOCKET4677_AZIFS054P001C01   I1

M_A_CPU0_SB_DQ<3>   @S9S_MB_2U_LIB.S9S_MB_2U(SCH_1):M_A_CPU0_SB_DQ<3>
  J1     247  DQ_B3  SCONN288_ADR50001P013C01  I198
  J2     247  DQ_B3  SCONN288_ADR50001P003C01  I177
  U2     N31  DDR0_SB_DQ3  SOCKET4677_AZIFS054P001C01   I1

M_A_CPU0_SB_DQ<4>   @S9S_MB_2U_LIB.S9S_MB_2U(SCH_1):M_A_CPU0_SB_DQ<4>
  J1     107  DQ_B4  SCONN288_ADR50001P013C01  I198
  J2     107  DQ_B4  SCONN288_ADR50001P003C01  I177
  U2     J29  DDR0_SB_DQ4  SOCKET4677_AZIFS054P001C01   I1

M_A_CPU0_SB_DQ<5>   @S9S_MB_2U_LIB.S9S_MB_2U(SCH_1):M_A_CPU0_SB_DQ<5>
  J1     109  DQ_B5  SCONN288_ADR50001P013C01  I198
  J2     109  DQ_B5  SCONN288_ADR50001P003C01  I177
  U2     K28  DDR0_SB_DQ5  SOCKET4677_AZIFS054P001C01   I1

M_A_CPU0_SB_DQ<6>   @S9S_MB_2U_LIB.S9S_MB_2U(SCH_1):M_A_CPU0_SB_DQ<6>
  J1     252  DQ_B6  SCONN288_ADR50001P013C01  I198
  J2     252  DQ_B6  SCONN288_ADR50001P003C01  I177
  U2     N29  DDR0_SB_DQ6  SOCKET4677_AZIFS054P001C01   I1

M_A_CPU0_SB_DQ<7>   @S9S_MB_2U_LIB.S9S_MB_2U(SCH_1):M_A_CPU0_SB_DQ<7>
  J1     254  DQ_B7  SCONN288_ADR50001P013C01  I198
  J2     254  DQ_B7  SCONN288_ADR50001P003C01  I177
  U2     M28  DDR0_SB_DQ7  SOCKET4677_AZIFS054P001C01   I1

M_A_CPU0_SB_DQ<8>   @S9S_MB_2U_LIB.S9S_MB_2U(SCH_1):M_A_CPU0_SB_DQ<8>
  J1     111  DQ_B8  SCONN288_ADR50001P013C01  I198
  J2     111  DQ_B8  SCONN288_ADR50001P003C01  I177
  U2     C29  DDR0_SB_DQ8  SOCKET4677_AZIFS054P001C01   I1

M_A_CPU0_SB_DQ<9>   @S9S_MB_2U_LIB.S9S_MB_2U(SCH_1):M_A_CPU0_SB_DQ<9>
  J1     113  DQ_B9  SCONN288_ADR50001P013C01  I198
  J2     113  DQ_B9  SCONN288_ADR50001P003C01  I177
  U2     B28  DDR0_SB_DQ9  SOCKET4677_AZIFS054P001C01   I1

M_A_CPU0_SB_DQ<10>   @S9S_MB_2U_LIB.S9S_MB_2U(SCH_1):M_A_CPU0_SB_DQ<10>
  J1     256  DQ_B10  SCONN288_ADR50001P013C01  I198
  J2     256  DQ_B10  SCONN288_ADR50001P003C01  I177
  U2     E29  DDR0_SB_DQ10  SOCKET4677_AZIFS054P001C01   I1

M_A_CPU0_SB_DQ<11>   @S9S_MB_2U_LIB.S9S_MB_2U(SCH_1):M_A_CPU0_SB_DQ<11>
  J1     258  DQ_B11  SCONN288_ADR50001P013C01  I198
  J2     258  DQ_B11  SCONN288_ADR50001P003C01  I177
  U2     F28  DDR0_SB_DQ11  SOCKET4677_AZIFS054P001C01   I1

M_A_CPU0_SB_DQ<12>   @S9S_MB_2U_LIB.S9S_MB_2U(SCH_1):M_A_CPU0_SB_DQ<12>
  J1     118  DQ_B12  SCONN288_ADR50001P013C01  I198
  J2     118  DQ_B12  SCONN288_ADR50001P003C01  I177
  U2     B26  DDR0_SB_DQ12  SOCKET4677_AZIFS054P001C01   I1

M_A_CPU0_SB_DQ<13>   @S9S_MB_2U_LIB.S9S_MB_2U(SCH_1):M_A_CPU0_SB_DQ<13>
  J1     120  DQ_B13  SCONN288_ADR50001P013C01  I198
  J2     120  DQ_B13  SCONN288_ADR50001P003C01  I177
  U2     C25  DDR0_SB_DQ13  SOCKET4677_AZIFS054P001C01   I1

M_A_CPU0_SB_DQ<14>   @S9S_MB_2U_LIB.S9S_MB_2U(SCH_1):M_A_CPU0_SB_DQ<14>
  J1     263  DQ_B14  SCONN288_ADR50001P013C01  I198
  J2     263  DQ_B14  SCONN288_ADR50001P003C01  I177
  U2     F26  DDR0_SB_DQ14  SOCKET4677_AZIFS054P001C01   I1

M_A_CPU0_SB_DQ<15>   @S9S_MB_2U_LIB.S9S_MB_2U(SCH_1):M_A_CPU0_SB_DQ<15>
  J1     265  DQ_B15  SCONN288_ADR50001P013C01  I198
  J2     265  DQ_B15  SCONN288_ADR50001P003C01  I177
  U2     E25  DDR0_SB_DQ15  SOCKET4677_AZIFS054P001C01   I1

M_A_CPU0_SB_DQ<16>   @S9S_MB_2U_LIB.S9S_MB_2U(SCH_1):M_A_CPU0_SB_DQ<16>
  J1     122  DQ_B16  SCONN288_ADR50001P013C01  I198
  J2     122  DQ_B16  SCONN288_ADR50001P003C01  I177
  U2     C23  DDR0_SB_DQ16  SOCKET4677_AZIFS054P001C01   I1

M_A_CPU0_SB_DQ<17>   @S9S_MB_2U_LIB.S9S_MB_2U(SCH_1):M_A_CPU0_SB_DQ<17>
  J1     124  DQ_B17  SCONN288_ADR50001P013C01  I198
  J2     124  DQ_B17  SCONN288_ADR50001P003C01  I177
  U2     B22  DDR0_SB_DQ17  SOCKET4677_AZIFS054P001C01   I1

M_A_CPU0_SB_DQ<18>   @S9S_MB_2U_LIB.S9S_MB_2U(SCH_1):M_A_CPU0_SB_DQ<18>
  J1     267  DQ_B18  SCONN288_ADR50001P013C01  I198
  J2     267  DQ_B18  SCONN288_ADR50001P003C01  I177
  U2     E23  DDR0_SB_DQ18  SOCKET4677_AZIFS054P001C01   I1

M_A_CPU0_SB_DQ<19>   @S9S_MB_2U_LIB.S9S_MB_2U(SCH_1):M_A_CPU0_SB_DQ<19>
  J1     269  DQ_B19  SCONN288_ADR50001P013C01  I198
  J2     269  DQ_B19  SCONN288_ADR50001P003C01  I177
  U2     F22  DDR0_SB_DQ19  SOCKET4677_AZIFS054P001C01   I1

M_A_CPU0_SB_DQ<20>   @S9S_MB_2U_LIB.S9S_MB_2U(SCH_1):M_A_CPU0_SB_DQ<20>
  J1     129  DQ_B20  SCONN288_ADR50001P013C01  I198
  J2     129  DQ_B20  SCONN288_ADR50001P003C01  I177
  U2     B20  DDR0_SB_DQ20  SOCKET4677_AZIFS054P001C01   I1

M_A_CPU0_SB_DQ<21>   @S9S_MB_2U_LIB.S9S_MB_2U(SCH_1):M_A_CPU0_SB_DQ<21>
  J1     131  DQ_B21  SCONN288_ADR50001P013C01  I198
  J2     131  DQ_B21  SCONN288_ADR50001P003C01  I177
  U2     C19  DDR0_SB_DQ21  SOCKET4677_AZIFS054P001C01   I1

M_A_CPU0_SB_DQ<22>   @S9S_MB_2U_LIB.S9S_MB_2U(SCH_1):M_A_CPU0_SB_DQ<22>
  J1     274  DQ_B22  SCONN288_ADR50001P013C01  I198
  J2     274  DQ_B22  SCONN288_ADR50001P003C01  I177
  U2     F20  DDR0_SB_DQ22  SOCKET4677_AZIFS054P001C01   I1

M_A_CPU0_SB_DQ<23>   @S9S_MB_2U_LIB.S9S_MB_2U(SCH_1):M_A_CPU0_SB_DQ<23>
  J1     276  DQ_B23  SCONN288_ADR50001P013C01  I198
  J2     276  DQ_B23  SCONN288_ADR50001P003C01  I177
  U2     E19  DDR0_SB_DQ23  SOCKET4677_AZIFS054P001C01   I1

M_A_CPU0_SB_DQ<24>   @S9S_MB_2U_LIB.S9S_MB_2U(SCH_1):M_A_CPU0_SB_DQ<24>
  J1     133  DQ_B24  SCONN288_ADR50001P013C01  I198
  J2     133  DQ_B24  SCONN288_ADR50001P003C01  I177
  U2     C11  DDR0_SB_DQ24  SOCKET4677_AZIFS054P001C01   I1

M_A_CPU0_SB_DQ<25>   @S9S_MB_2U_LIB.S9S_MB_2U(SCH_1):M_A_CPU0_SB_DQ<25>
  J1     135  DQ_B25  SCONN288_ADR50001P013C01  I198
  J2     135  DQ_B25  SCONN288_ADR50001P003C01  I177
  U2     B10  DDR0_SB_DQ25  SOCKET4677_AZIFS054P001C01   I1

M_A_CPU0_SB_DQ<26>   @S9S_MB_2U_LIB.S9S_MB_2U(SCH_1):M_A_CPU0_SB_DQ<26>
  J1     278  DQ_B26  SCONN288_ADR50001P013C01  I198
  J2     278  DQ_B26  SCONN288_ADR50001P003C01  I177
  U2     E11  DDR0_SB_DQ26  SOCKET4677_AZIFS054P001C01   I1

M_A_CPU0_SB_DQ<27>   @S9S_MB_2U_LIB.S9S_MB_2U(SCH_1):M_A_CPU0_SB_DQ<27>
  J1     280  DQ_B27  SCONN288_ADR50001P013C01  I198
  J2     280  DQ_B27  SCONN288_ADR50001P003C01  I177
  U2     F10  DDR0_SB_DQ27  SOCKET4677_AZIFS054P001C01   I1

M_A_CPU0_SB_DQ<28>   @S9S_MB_2U_LIB.S9S_MB_2U(SCH_1):M_A_CPU0_SB_DQ<28>
  J1     140  DQ_B28  SCONN288_ADR50001P013C01  I198
  J2     140  DQ_B28  SCONN288_ADR50001P003C01  I177
  U2      B8  DDR0_SB_DQ28  SOCKET4677_AZIFS054P001C01   I1

M_A_CPU0_SB_DQ<29>   @S9S_MB_2U_LIB.S9S_MB_2U(SCH_1):M_A_CPU0_SB_DQ<29>
  J1     142  DQ_B29  SCONN288_ADR50001P013C01  I198
  J2     142  DQ_B29  SCONN288_ADR50001P003C01  I177
  U2      C7  DDR0_SB_DQ29  SOCKET4677_AZIFS054P001C01   I1

M_A_CPU0_SB_DQ<30>   @S9S_MB_2U_LIB.S9S_MB_2U(SCH_1):M_A_CPU0_SB_DQ<30>
  J1     285  DQ_B30  SCONN288_ADR50001P013C01  I198
  J2     285  DQ_B30  SCONN288_ADR50001P003C01  I177
  U2      F8  DDR0_SB_DQ30  SOCKET4677_AZIFS054P001C01   I1

M_A_CPU0_SB_DQ<31>   @S9S_MB_2U_LIB.S9S_MB_2U(SCH_1):M_A_CPU0_SB_DQ<31>
  J1     287  DQ_B31  SCONN288_ADR50001P013C01  I198
  J2     287  DQ_B31  SCONN288_ADR50001P003C01  I177
  U2      E7  DDR0_SB_DQ31  SOCKET4677_AZIFS054P001C01   I1

M_A_CPU0_SB_DQS_DN<0>   @S9S_MB_2U_LIB.S9S_MB_2U(SCH_1):M_A_CPU0_SB_DQS_DN<0>
  J1     105  DQS0_B_N  SCONN288_ADR50001P013C01  I199
  J2     105  DQS0_B_N  SCONN288_ADR50001P003C01  I178
  U2     H30  DDR0_SB_DQS_DN0  SOCKET4677_AZIFS054P001C01   I1

M_A_CPU0_SB_DQS_DN<1>   @S9S_MB_2U_LIB.S9S_MB_2U(SCH_1):M_A_CPU0_SB_DQS_DN<1>
  J1     116  DQS1_B_N  SCONN288_ADR50001P013C01  I199
  J2     116  DQS1_B_N  SCONN288_ADR50001P003C01  I178
  U2     A27  DDR0_SB_DQS_DN1  SOCKET4677_AZIFS054P001C01   I1

M_A_CPU0_SB_DQS_DN<2>   @S9S_MB_2U_LIB.S9S_MB_2U(SCH_1):M_A_CPU0_SB_DQS_DN<2>
  J1     127  DQS2_B_N  SCONN288_ADR50001P013C01  I199
  J2     127  DQS2_B_N  SCONN288_ADR50001P003C01  I178
  U2     A21  DDR0_SB_DQS_DN2  SOCKET4677_AZIFS054P001C01   I1

M_A_CPU0_SB_DQS_DN<3>   @S9S_MB_2U_LIB.S9S_MB_2U(SCH_1):M_A_CPU0_SB_DQS_DN<3>
  J1     138  DQS3_B_N  SCONN288_ADR50001P013C01  I199
  J2     138  DQS3_B_N  SCONN288_ADR50001P003C01  I178
  U2      A9  DDR0_SB_DQS_DN3  SOCKET4677_AZIFS054P001C01   I1

M_A_CPU0_SB_DQS_DN<4>   @S9S_MB_2U_LIB.S9S_MB_2U(SCH_1):M_A_CPU0_SB_DQS_DN<4>
  J1     238  DQS4_B_N  SCONN288_ADR50001P013C01  I199
  J2     238  DQS4_B_N  SCONN288_ADR50001P003C01  I178
  U2     G33  DDR0_SB_DQS_DN4  SOCKET4677_AZIFS054P001C01   I1

M_A_CPU0_SB_DQS_DN<5>   @S9S_MB_2U_LIB.S9S_MB_2U(SCH_1):M_A_CPU0_SB_DQS_DN<5>
  J1     249  DQS5_B_N  SCONN288_ADR50001P013C01  I199
  J2     249  DQS5_B_N  SCONN288_ADR50001P003C01  I178
  U2     M30  DDR0_SB_DQS_DN5  SOCKET4677_AZIFS054P001C01   I1

M_A_CPU0_SB_DQS_DN<6>   @S9S_MB_2U_LIB.S9S_MB_2U(SCH_1):M_A_CPU0_SB_DQS_DN<6>
  J1     260  DQS6_B_N  SCONN288_ADR50001P013C01  I199
  J2     260  DQS6_B_N  SCONN288_ADR50001P003C01  I178
  U2     G27  DDR0_SB_DQS_DN6  SOCKET4677_AZIFS054P001C01   I1

M_A_CPU0_SB_DQS_DN<7>   @S9S_MB_2U_LIB.S9S_MB_2U(SCH_1):M_A_CPU0_SB_DQS_DN<7>
  J1     271  DQS7_B_N  SCONN288_ADR50001P013C01  I199
  J2     271  DQS7_B_N  SCONN288_ADR50001P003C01  I178
  U2     G21  DDR0_SB_DQS_DN7  SOCKET4677_AZIFS054P001C01   I1

M_A_CPU0_SB_DQS_DN<8>   @S9S_MB_2U_LIB.S9S_MB_2U(SCH_1):M_A_CPU0_SB_DQS_DN<8>
  J1     282  DQS8_B_N  SCONN288_ADR50001P013C01  I199
  J2     282  DQS8_B_N  SCONN288_ADR50001P003C01  I178
  U2      G9  DDR0_SB_DQS_DN8  SOCKET4677_AZIFS054P001C01   I1

M_A_CPU0_SB_DQS_DN<9>   @S9S_MB_2U_LIB.S9S_MB_2U(SCH_1):M_A_CPU0_SB_DQS_DN<9>
  J1      94  DQS9_B_N  SCONN288_ADR50001P013C01  I199
  J2      94  DQS9_B_N  SCONN288_ADR50001P003C01  I178
  U2     A33  DDR0_SB_DQS_DN9  SOCKET4677_AZIFS054P001C01   I1

M_A_CPU0_SB_DQS_DP<0>   @S9S_MB_2U_LIB.S9S_MB_2U(SCH_1):M_A_CPU0_SB_DQS_DP<0>
  J1     104  DQS0_B_P  SCONN288_ADR50001P013C01  I199
  J2     104  DQS0_B_P  SCONN288_ADR50001P003C01  I178
  U2     K30  DDR0_SB_DQS_DP0  SOCKET4677_AZIFS054P001C01   I1

M_A_CPU0_SB_DQS_DP<1>   @S9S_MB_2U_LIB.S9S_MB_2U(SCH_1):M_A_CPU0_SB_DQS_DP<1>
  J1     115  DQS1_B_P  SCONN288_ADR50001P013C01  I199
  J2     115  DQS1_B_P  SCONN288_ADR50001P003C01  I178
  U2     C27  DDR0_SB_DQS_DP1  SOCKET4677_AZIFS054P001C01   I1

M_A_CPU0_SB_DQS_DP<2>   @S9S_MB_2U_LIB.S9S_MB_2U(SCH_1):M_A_CPU0_SB_DQS_DP<2>
  J1     126  DQS2_B_P  SCONN288_ADR50001P013C01  I199
  J2     126  DQS2_B_P  SCONN288_ADR50001P003C01  I178
  U2     C21  DDR0_SB_DQS_DP2  SOCKET4677_AZIFS054P001C01   I1

M_A_CPU0_SB_DQS_DP<3>   @S9S_MB_2U_LIB.S9S_MB_2U(SCH_1):M_A_CPU0_SB_DQS_DP<3>
  J1     137  DQS3_B_P  SCONN288_ADR50001P013C01  I199
  J2     137  DQS3_B_P  SCONN288_ADR50001P003C01  I178
  U2      C9  DDR0_SB_DQS_DP3  SOCKET4677_AZIFS054P001C01   I1

M_A_CPU0_SB_DQS_DP<4>   @S9S_MB_2U_LIB.S9S_MB_2U(SCH_1):M_A_CPU0_SB_DQS_DP<4>
  J1     239  DQS4_B_P  SCONN288_ADR50001P013C01  I199
  J2     239  DQS4_B_P  SCONN288_ADR50001P003C01  I178
  U2     E33  DDR0_SB_DQS_DP4  SOCKET4677_AZIFS054P001C01   I1

M_A_CPU0_SB_DQS_DP<5>   @S9S_MB_2U_LIB.S9S_MB_2U(SCH_1):M_A_CPU0_SB_DQS_DP<5>
  J1     250  DQS5_B_P  SCONN288_ADR50001P013C01  I199
  J2     250  DQS5_B_P  SCONN288_ADR50001P003C01  I178
  U2     P30  DDR0_SB_DQS_DP5  SOCKET4677_AZIFS054P001C01   I1

M_A_CPU0_SB_DQS_DP<6>   @S9S_MB_2U_LIB.S9S_MB_2U(SCH_1):M_A_CPU0_SB_DQS_DP<6>
  J1     261  DQS6_B_P  SCONN288_ADR50001P013C01  I199
  J2     261  DQS6_B_P  SCONN288_ADR50001P003C01  I178
  U2     E27  DDR0_SB_DQS_DP6  SOCKET4677_AZIFS054P001C01   I1

M_A_CPU0_SB_DQS_DP<7>   @S9S_MB_2U_LIB.S9S_MB_2U(SCH_1):M_A_CPU0_SB_DQS_DP<7>
  J1     272  DQS7_B_P  SCONN288_ADR50001P013C01  I199
  J2     272  DQS7_B_P  SCONN288_ADR50001P003C01  I178
  U2     E21  DDR0_SB_DQS_DP7  SOCKET4677_AZIFS054P001C01   I1

M_A_CPU0_SB_DQS_DP<8>   @S9S_MB_2U_LIB.S9S_MB_2U(SCH_1):M_A_CPU0_SB_DQS_DP<8>
  J1     283  DQS8_B_P  SCONN288_ADR50001P013C01  I199
  J2     283  DQS8_B_P  SCONN288_ADR50001P003C01  I178
  U2      E9  DDR0_SB_DQS_DP8  SOCKET4677_AZIFS054P001C01   I1

M_A_CPU0_SB_DQS_DP<9>   @S9S_MB_2U_LIB.S9S_MB_2U(SCH_1):M_A_CPU0_SB_DQS_DP<9>
  J1      93  DQS9_B_P  SCONN288_ADR50001P013C01  I199
  J2      93  DQS9_B_P  SCONN288_ADR50001P003C01  I178
  U2     C33  DDR0_SB_DQS_DP9  SOCKET4677_AZIFS054P001C01   I1

M_A_CPU0_SB_PAR   @S9S_MB_2U_LIB.S9S_MB_2U(SCH_1):M_A_CPU0_SB_PAR
  J1     227  PAR_B  SCONN288_ADR50001P013C01  I198
  J2     227  PAR_B  SCONN288_ADR50001P003C01  I177
  U2     G39  DDR0_SB_PAR  SOCKET4677_AZIFS054P001C01   I1

M_A_CPU0_SB_RSP<0>   @S9S_MB_2U_LIB.S9S_MB_2U(SCH_1):M_A_CPU0_SB_RSP<0>
  J1      87  LBS||RSP_N_B  SCONN288_ADR50001P013C01  I198
  U2     AV44  DDR0_B_RSP0  SOCKET4677_AZIFS054P001C01   I1

M_A_CPU0_SB_RSP<1>   @S9S_MB_2U_LIB.S9S_MB_2U(SCH_1):M_A_CPU0_SB_RSP<1>
  J2      87  LBS||RSP_N_B  SCONN288_ADR50001P003C01  I177
  U2     AV42  DDR0_B_RSP1  SOCKET4677_AZIFS054P001C01   I1

M_A_CPU1_ALERT_N   @S9S_MB_2U_LIB.S9S_MB_2U(SCH_1):M_A_CPU1_ALERT_N
  J17     62  ALERT_N  SCONN288_ADR50001P013C01  I12
  J18     62  ALERT_N  SCONN288_ADR50001P003C01  I24
  U1     AT49  DDR0_ALERT_N  SOCKET4677_AZIFS054P001C01   I2

M_A_CPU1_CLK_DN<0>   @S9S_MB_2U_LIB.S9S_MB_2U(SCH_1):M_A_CPU1_CLK_DN<0>
  J17    218   CK_N  SCONN288_ADR50001P013C01  I12
  U1     B44  DDR0_CLK_DN0  SOCKET4677_AZIFS054P001C01   I2

M_A_CPU1_CLK_DN<1>   @S9S_MB_2U_LIB.S9S_MB_2U(SCH_1):M_A_CPU1_CLK_DN<1>
  J18    218   CK_N  SCONN288_ADR50001P003C01  I24
  U1     G45  DDR0_CLK_DN1  SOCKET4677_AZIFS054P001C01   I2

M_A_CPU1_CLK_DP<0>   @S9S_MB_2U_LIB.S9S_MB_2U(SCH_1):M_A_CPU1_CLK_DP<0>
  J17    217   CK_P  SCONN288_ADR50001P013C01  I12
  U1     C43  DDR0_CLK_DP0  SOCKET4677_AZIFS054P001C01   I2

M_A_CPU1_CLK_DP<1>   @S9S_MB_2U_LIB.S9S_MB_2U(SCH_1):M_A_CPU1_CLK_DP<1>
  J18    217   CK_P  SCONN288_ADR50001P003C01  I24
  U1     E45  DDR0_CLK_DP1  SOCKET4677_AZIFS054P001C01   I2

M_A_CPU1_SA_CA<0>   @S9S_MB_2U_LIB.S9S_MB_2U(SCH_1):M_A_CPU1_SA_CA<0>
  J17     66  CA0_A  SCONN288_ADR50001P013C01  I12
  J18     66  CA0_A  SCONN288_ADR50001P003C01  I24
  U1     A52  DDR0_SA_CA0  SOCKET4677_AZIFS054P001C01   I2

M_A_CPU1_SA_CA<1>   @S9S_MB_2U_LIB.S9S_MB_2U(SCH_1):M_A_CPU1_SA_CA<1>
  J17    211  CA1_A  SCONN288_ADR50001P013C01  I12
  J18    211  CA1_A  SCONN288_ADR50001P003C01  I24
  U1     G52  DDR0_SA_CA1  SOCKET4677_AZIFS054P001C01   I2

M_A_CPU1_SA_CA<2>   @S9S_MB_2U_LIB.S9S_MB_2U(SCH_1):M_A_CPU1_SA_CA<2>
  J17     68  CA2_A  SCONN288_ADR50001P013C01  I12
  J18     68  CA2_A  SCONN288_ADR50001P003C01  I24
  U1     B51  DDR0_SA_CA2  SOCKET4677_AZIFS054P001C01   I2

M_A_CPU1_SA_CA<3>   @S9S_MB_2U_LIB.S9S_MB_2U(SCH_1):M_A_CPU1_SA_CA<3>
  J17    213  CA3_A  SCONN288_ADR50001P013C01  I12
  J18    213  CA3_A  SCONN288_ADR50001P003C01  I24
  U1     F51  DDR0_SA_CA3  SOCKET4677_AZIFS054P001C01   I2

M_A_CPU1_SA_CA<4>   @S9S_MB_2U_LIB.S9S_MB_2U(SCH_1):M_A_CPU1_SA_CA<4>
  J17     70  CA4_A  SCONN288_ADR50001P013C01  I12
  J18     70  CA4_A  SCONN288_ADR50001P003C01  I24
  U1     C50  DDR0_SA_CA4  SOCKET4677_AZIFS054P001C01   I2

M_A_CPU1_SA_CA<5>   @S9S_MB_2U_LIB.S9S_MB_2U(SCH_1):M_A_CPU1_SA_CA<5>
  J17    215  CA5_A  SCONN288_ADR50001P013C01  I12
  J18    215  CA5_A  SCONN288_ADR50001P003C01  I24
  U1     E50  DDR0_SA_CA5  SOCKET4677_AZIFS054P001C01   I2

M_A_CPU1_SA_CA<6>   @S9S_MB_2U_LIB.S9S_MB_2U(SCH_1):M_A_CPU1_SA_CA<6>
  J17     72  CA6_A  SCONN288_ADR50001P013C01  I12
  J18     72  CA6_A  SCONN288_ADR50001P003C01  I24
  U1     C48  DDR0_SA_CA6  SOCKET4677_AZIFS054P001C01   I2

M_A_CPU1_SA_CB<0>   @S9S_MB_2U_LIB.S9S_MB_2U(SCH_1):M_A_CPU1_SA_CB<0>
  J17     51  CB_A0  SCONN288_ADR50001P013C01  I12
  J18     51  CB_A0  SCONN288_ADR50001P003C01  I24
  U1     C60  DDR0_SA_ECC0  SOCKET4677_AZIFS054P001C01   I2

M_A_CPU1_SA_CB<1>   @S9S_MB_2U_LIB.S9S_MB_2U(SCH_1):M_A_CPU1_SA_CB<1>
  J17     53  CB_A1  SCONN288_ADR50001P013C01  I12
  J18     53  CB_A1  SCONN288_ADR50001P003C01  I24
  U1     B59  DDR0_SA_ECC1  SOCKET4677_AZIFS054P001C01   I2

M_A_CPU1_SA_CB<2>   @S9S_MB_2U_LIB.S9S_MB_2U(SCH_1):M_A_CPU1_SA_CB<2>
  J17    196  CB_A2  SCONN288_ADR50001P013C01  I12
  J18    196  CB_A2  SCONN288_ADR50001P003C01  I24
  U1     E60  DDR0_SA_ECC2  SOCKET4677_AZIFS054P001C01   I2

M_A_CPU1_SA_CB<3>   @S9S_MB_2U_LIB.S9S_MB_2U(SCH_1):M_A_CPU1_SA_CB<3>
  J17    198  CB_A3  SCONN288_ADR50001P013C01  I12
  J18    198  CB_A3  SCONN288_ADR50001P003C01  I24
  U1     F59  DDR0_SA_ECC3  SOCKET4677_AZIFS054P001C01   I2

M_A_CPU1_SA_CB<4>   @S9S_MB_2U_LIB.S9S_MB_2U(SCH_1):M_A_CPU1_SA_CB<4>
  J17     58  CB_A4  SCONN288_ADR50001P013C01  I12
  J18     58  CB_A4  SCONN288_ADR50001P003C01  I24
  U1     B57  DDR0_SA_ECC4  SOCKET4677_AZIFS054P001C01   I2

M_A_CPU1_SA_CB<5>   @S9S_MB_2U_LIB.S9S_MB_2U(SCH_1):M_A_CPU1_SA_CB<5>
  J17     60  CB_A5  SCONN288_ADR50001P013C01  I12
  J18     60  CB_A5  SCONN288_ADR50001P003C01  I24
  U1     C56  DDR0_SA_ECC5  SOCKET4677_AZIFS054P001C01   I2

M_A_CPU1_SA_CB<6>   @S9S_MB_2U_LIB.S9S_MB_2U(SCH_1):M_A_CPU1_SA_CB<6>
  J17    203  CB_A6  SCONN288_ADR50001P013C01  I12
  J18    203  CB_A6  SCONN288_ADR50001P003C01  I24
  U1     F57  DDR0_SA_ECC6  SOCKET4677_AZIFS054P001C01   I2

M_A_CPU1_SA_CB<7>   @S9S_MB_2U_LIB.S9S_MB_2U(SCH_1):M_A_CPU1_SA_CB<7>
  J17    205  CB_A7  SCONN288_ADR50001P013C01  I12
  J18    205  CB_A7  SCONN288_ADR50001P003C01  I24
  U1     E56  DDR0_SA_ECC7  SOCKET4677_AZIFS054P001C01   I2

M_A_CPU1_SA_CS_N<0>   @S9S_MB_2U_LIB.S9S_MB_2U(SCH_1):M_A_CPU1_SA_CS_N<0>
  J17     64  CS0_N_A  SCONN288_ADR50001P013C01  I12
  U1     C54  DDR0_SA_CS0_N  SOCKET4677_AZIFS054P001C01   I2

M_A_CPU1_SA_CS_N<1>   @S9S_MB_2U_LIB.S9S_MB_2U(SCH_1):M_A_CPU1_SA_CS_N<1>
  J17    209  CS1_N_A  SCONN288_ADR50001P013C01  I12
  U1     B53  DDR0_SA_CS1_N  SOCKET4677_AZIFS054P001C01   I2

M_A_CPU1_SA_CS_N<2>   @S9S_MB_2U_LIB.S9S_MB_2U(SCH_1):M_A_CPU1_SA_CS_N<2>
  J18     64  CS0_N_A  SCONN288_ADR50001P003C01  I24
  U1     E54  DDR0_SA_CS2_N  SOCKET4677_AZIFS054P001C01   I2

M_A_CPU1_SA_CS_N<3>   @S9S_MB_2U_LIB.S9S_MB_2U(SCH_1):M_A_CPU1_SA_CS_N<3>
  J18    209  CS1_N_A  SCONN288_ADR50001P003C01  I24
  U1     F53  DDR0_SA_CS3_N  SOCKET4677_AZIFS054P001C01   I2

M_A_CPU1_SA_DQ<0>   @S9S_MB_2U_LIB.S9S_MB_2U(SCH_1):M_A_CPU1_SA_DQ<0>
  J17      7  DQ_A0  SCONN288_ADR50001P013C01  I12
  J18      7  DQ_A0  SCONN288_ADR50001P003C01  I24
  U1     B81  DDR0_SA_DQ0  SOCKET4677_AZIFS054P001C01   I2

M_A_CPU1_SA_DQ<1>   @S9S_MB_2U_LIB.S9S_MB_2U(SCH_1):M_A_CPU1_SA_DQ<1>
  J17      9  DQ_A1  SCONN288_ADR50001P013C01  I12
  J18      9  DQ_A1  SCONN288_ADR50001P003C01  I24
  U1     B79  DDR0_SA_DQ1  SOCKET4677_AZIFS054P001C01   I2

M_A_CPU1_SA_DQ<2>   @S9S_MB_2U_LIB.S9S_MB_2U(SCH_1):M_A_CPU1_SA_DQ<2>
  J17    152  DQ_A2  SCONN288_ADR50001P013C01  I12
  J18    152  DQ_A2  SCONN288_ADR50001P003C01  I24
  U1     M77  DDR0_SA_DQ2  SOCKET4677_AZIFS054P001C01   I2

M_A_CPU1_SA_DQ<3>   @S9S_MB_2U_LIB.S9S_MB_2U(SCH_1):M_A_CPU1_SA_DQ<3>
  J17    154  DQ_A3  SCONN288_ADR50001P013C01  I12
  J18    154  DQ_A3  SCONN288_ADR50001P003C01  I24
  U1     G78  DDR0_SA_DQ3  SOCKET4677_AZIFS054P001C01   I2

M_A_CPU1_SA_DQ<4>   @S9S_MB_2U_LIB.S9S_MB_2U(SCH_1):M_A_CPU1_SA_DQ<4>
  J17     14  DQ_A4  SCONN288_ADR50001P013C01  I12
  J18     14  DQ_A4  SCONN288_ADR50001P003C01  I24
  U1     C76  DDR0_SA_DQ4  SOCKET4677_AZIFS054P001C01   I2

M_A_CPU1_SA_DQ<5>   @S9S_MB_2U_LIB.S9S_MB_2U(SCH_1):M_A_CPU1_SA_DQ<5>
  J17     16  DQ_A5  SCONN288_ADR50001P013C01  I12
  J18     16  DQ_A5  SCONN288_ADR50001P003C01  I24
  U1     D75  DDR0_SA_DQ5  SOCKET4677_AZIFS054P001C01   I2

M_A_CPU1_SA_DQ<6>   @S9S_MB_2U_LIB.S9S_MB_2U(SCH_1):M_A_CPU1_SA_DQ<6>
  J17    159  DQ_A6  SCONN288_ADR50001P013C01  I12
  J18    159  DQ_A6  SCONN288_ADR50001P003C01  I24
  U1     G76  DDR0_SA_DQ6  SOCKET4677_AZIFS054P001C01   I2

M_A_CPU1_SA_DQ<7>   @S9S_MB_2U_LIB.S9S_MB_2U(SCH_1):M_A_CPU1_SA_DQ<7>
  J17    161  DQ_A7  SCONN288_ADR50001P013C01  I12
  J18    161  DQ_A7  SCONN288_ADR50001P003C01  I24
  U1     F75  DDR0_SA_DQ7  SOCKET4677_AZIFS054P001C01   I2

M_A_CPU1_SA_DQ<8>   @S9S_MB_2U_LIB.S9S_MB_2U(SCH_1):M_A_CPU1_SA_DQ<8>
  J17     18  DQ_A8  SCONN288_ADR50001P013C01  I12
  J18     18  DQ_A8  SCONN288_ADR50001P003C01  I24
  U1     K69  DDR0_SA_DQ8  SOCKET4677_AZIFS054P001C01   I2

M_A_CPU1_SA_DQ<9>   @S9S_MB_2U_LIB.S9S_MB_2U(SCH_1):M_A_CPU1_SA_DQ<9>
  J17     20  DQ_A9  SCONN288_ADR50001P013C01  I12
  J18     20  DQ_A9  SCONN288_ADR50001P003C01  I24
  U1     J68  DDR0_SA_DQ9  SOCKET4677_AZIFS054P001C01   I2

M_A_CPU1_SA_DQ<10>   @S9S_MB_2U_LIB.S9S_MB_2U(SCH_1):M_A_CPU1_SA_DQ<10>
  J17    163  DQ_A10  SCONN288_ADR50001P013C01  I12
  J18    163  DQ_A10  SCONN288_ADR50001P003C01  I24
  U1     M69  DDR0_SA_DQ10  SOCKET4677_AZIFS054P001C01   I2

M_A_CPU1_SA_DQ<11>   @S9S_MB_2U_LIB.S9S_MB_2U(SCH_1):M_A_CPU1_SA_DQ<11>
  J17    165  DQ_A11  SCONN288_ADR50001P013C01  I12
  J18    165  DQ_A11  SCONN288_ADR50001P003C01  I24
  U1     N68  DDR0_SA_DQ11  SOCKET4677_AZIFS054P001C01   I2

M_A_CPU1_SA_DQ<12>   @S9S_MB_2U_LIB.S9S_MB_2U(SCH_1):M_A_CPU1_SA_DQ<12>
  J17     25  DQ_A12  SCONN288_ADR50001P013C01  I12
  J18     25  DQ_A12  SCONN288_ADR50001P003C01  I24
  U1     J66  DDR0_SA_DQ12  SOCKET4677_AZIFS054P001C01   I2

M_A_CPU1_SA_DQ<13>   @S9S_MB_2U_LIB.S9S_MB_2U(SCH_1):M_A_CPU1_SA_DQ<13>
  J17     27  DQ_A13  SCONN288_ADR50001P013C01  I12
  J18     27  DQ_A13  SCONN288_ADR50001P003C01  I24
  U1     K65  DDR0_SA_DQ13  SOCKET4677_AZIFS054P001C01   I2

M_A_CPU1_SA_DQ<14>   @S9S_MB_2U_LIB.S9S_MB_2U(SCH_1):M_A_CPU1_SA_DQ<14>
  J17    170  DQ_A14  SCONN288_ADR50001P013C01  I12
  J18    170  DQ_A14  SCONN288_ADR50001P003C01  I24
  U1     N66  DDR0_SA_DQ14  SOCKET4677_AZIFS054P001C01   I2

M_A_CPU1_SA_DQ<15>   @S9S_MB_2U_LIB.S9S_MB_2U(SCH_1):M_A_CPU1_SA_DQ<15>
  J17    172  DQ_A15  SCONN288_ADR50001P013C01  I12
  J18    172  DQ_A15  SCONN288_ADR50001P003C01  I24
  U1     M65  DDR0_SA_DQ15  SOCKET4677_AZIFS054P001C01   I2

M_A_CPU1_SA_DQ<16>   @S9S_MB_2U_LIB.S9S_MB_2U(SCH_1):M_A_CPU1_SA_DQ<16>
  J17     29  DQ_A16  SCONN288_ADR50001P013C01  I12
  J18     29  DQ_A16  SCONN288_ADR50001P003C01  I24
  U1     B73  DDR0_SA_DQ16  SOCKET4677_AZIFS054P001C01   I2

M_A_CPU1_SA_DQ<17>   @S9S_MB_2U_LIB.S9S_MB_2U(SCH_1):M_A_CPU1_SA_DQ<17>
  J17     31  DQ_A17  SCONN288_ADR50001P013C01  I12
  J18     31  DQ_A17  SCONN288_ADR50001P003C01  I24
  U1     E72  DDR0_SA_DQ17  SOCKET4677_AZIFS054P001C01   I2

M_A_CPU1_SA_DQ<18>   @S9S_MB_2U_LIB.S9S_MB_2U(SCH_1):M_A_CPU1_SA_DQ<18>
  J17    174  DQ_A18  SCONN288_ADR50001P013C01  I12
  J18    174  DQ_A18  SCONN288_ADR50001P003C01  I24
  U1     D73  DDR0_SA_DQ18  SOCKET4677_AZIFS054P001C01   I2

M_A_CPU1_SA_DQ<19>   @S9S_MB_2U_LIB.S9S_MB_2U(SCH_1):M_A_CPU1_SA_DQ<19>
  J17    176  DQ_A19  SCONN288_ADR50001P013C01  I12
  J18    176  DQ_A19  SCONN288_ADR50001P003C01  I24
  U1     F71  DDR0_SA_DQ19  SOCKET4677_AZIFS054P001C01   I2

M_A_CPU1_SA_DQ<20>   @S9S_MB_2U_LIB.S9S_MB_2U(SCH_1):M_A_CPU1_SA_DQ<20>
  J17     36  DQ_A20  SCONN288_ADR50001P013C01  I12
  J18     36  DQ_A20  SCONN288_ADR50001P003C01  I24
  U1     B69  DDR0_SA_DQ20  SOCKET4677_AZIFS054P001C01   I2

M_A_CPU1_SA_DQ<21>   @S9S_MB_2U_LIB.S9S_MB_2U(SCH_1):M_A_CPU1_SA_DQ<21>
  J17     38  DQ_A21  SCONN288_ADR50001P013C01  I12
  J18     38  DQ_A21  SCONN288_ADR50001P003C01  I24
  U1     C68  DDR0_SA_DQ21  SOCKET4677_AZIFS054P001C01   I2

M_A_CPU1_SA_DQ<22>   @S9S_MB_2U_LIB.S9S_MB_2U(SCH_1):M_A_CPU1_SA_DQ<22>
  J17    181  DQ_A22  SCONN288_ADR50001P013C01  I12
  J18    181  DQ_A22  SCONN288_ADR50001P003C01  I24
  U1     F69  DDR0_SA_DQ22  SOCKET4677_AZIFS054P001C01   I2

M_A_CPU1_SA_DQ<23>   @S9S_MB_2U_LIB.S9S_MB_2U(SCH_1):M_A_CPU1_SA_DQ<23>
  J17    183  DQ_A23  SCONN288_ADR50001P013C01  I12
  J18    183  DQ_A23  SCONN288_ADR50001P003C01  I24
  U1     E68  DDR0_SA_DQ23  SOCKET4677_AZIFS054P001C01   I2

M_A_CPU1_SA_DQ<24>   @S9S_MB_2U_LIB.S9S_MB_2U(SCH_1):M_A_CPU1_SA_DQ<24>
  J17     40  DQ_A24  SCONN288_ADR50001P013C01  I12
  J18     40  DQ_A24  SCONN288_ADR50001P003C01  I24
  U1     C66  DDR0_SA_DQ24  SOCKET4677_AZIFS054P001C01   I2

M_A_CPU1_SA_DQ<25>   @S9S_MB_2U_LIB.S9S_MB_2U(SCH_1):M_A_CPU1_SA_DQ<25>
  J17     42  DQ_A25  SCONN288_ADR50001P013C01  I12
  J18     42  DQ_A25  SCONN288_ADR50001P003C01  I24
  U1     B65  DDR0_SA_DQ25  SOCKET4677_AZIFS054P001C01   I2

M_A_CPU1_SA_DQ<26>   @S9S_MB_2U_LIB.S9S_MB_2U(SCH_1):M_A_CPU1_SA_DQ<26>
  J17    185  DQ_A26  SCONN288_ADR50001P013C01  I12
  J18    185  DQ_A26  SCONN288_ADR50001P003C01  I24
  U1     E66  DDR0_SA_DQ26  SOCKET4677_AZIFS054P001C01   I2

M_A_CPU1_SA_DQ<27>   @S9S_MB_2U_LIB.S9S_MB_2U(SCH_1):M_A_CPU1_SA_DQ<27>
  J17    187  DQ_A27  SCONN288_ADR50001P013C01  I12
  J18    187  DQ_A27  SCONN288_ADR50001P003C01  I24
  U1     F65  DDR0_SA_DQ27  SOCKET4677_AZIFS054P001C01   I2

M_A_CPU1_SA_DQ<28>   @S9S_MB_2U_LIB.S9S_MB_2U(SCH_1):M_A_CPU1_SA_DQ<28>
  J17     47  DQ_A28  SCONN288_ADR50001P013C01  I12
  J18     47  DQ_A28  SCONN288_ADR50001P003C01  I24
  U1     B63  DDR0_SA_DQ28  SOCKET4677_AZIFS054P001C01   I2

M_A_CPU1_SA_DQ<29>   @S9S_MB_2U_LIB.S9S_MB_2U(SCH_1):M_A_CPU1_SA_DQ<29>
  J17     49  DQ_A29  SCONN288_ADR50001P013C01  I12
  J18     49  DQ_A29  SCONN288_ADR50001P003C01  I24
  U1     C62  DDR0_SA_DQ29  SOCKET4677_AZIFS054P001C01   I2

M_A_CPU1_SA_DQ<30>   @S9S_MB_2U_LIB.S9S_MB_2U(SCH_1):M_A_CPU1_SA_DQ<30>
  J17    192  DQ_A30  SCONN288_ADR50001P013C01  I12
  J18    192  DQ_A30  SCONN288_ADR50001P003C01  I24
  U1     F63  DDR0_SA_DQ30  SOCKET4677_AZIFS054P001C01   I2

M_A_CPU1_SA_DQ<31>   @S9S_MB_2U_LIB.S9S_MB_2U(SCH_1):M_A_CPU1_SA_DQ<31>
  J17    194  DQ_A31  SCONN288_ADR50001P013C01  I12
  J18    194  DQ_A31  SCONN288_ADR50001P003C01  I24
  U1     E62  DDR0_SA_DQ31  SOCKET4677_AZIFS054P001C01   I2

M_A_CPU1_SA_DQS_DN<0>   @S9S_MB_2U_LIB.S9S_MB_2U(SCH_1):M_A_CPU1_SA_DQS_DN<0>
  J17     12  DQS0_A_N  SCONN288_ADR50001P013C01  I126
  J18     12  DQS0_A_N  SCONN288_ADR50001P003C01  I125
  U1     B77  DDR0_SA_DQS_DN0  SOCKET4677_AZIFS054P001C01   I2

M_A_CPU1_SA_DQS_DN<1>   @S9S_MB_2U_LIB.S9S_MB_2U(SCH_1):M_A_CPU1_SA_DQS_DN<1>
  J17     23  DQS1_A_N  SCONN288_ADR50001P013C01  I126
  J18     23  DQS1_A_N  SCONN288_ADR50001P003C01  I125
  U1     H67  DDR0_SA_DQS_DN1  SOCKET4677_AZIFS054P001C01   I2

M_A_CPU1_SA_DQS_DN<2>   @S9S_MB_2U_LIB.S9S_MB_2U(SCH_1):M_A_CPU1_SA_DQS_DN<2>
  J17     34  DQS2_A_N  SCONN288_ADR50001P013C01  I126
  J18     34  DQS2_A_N  SCONN288_ADR50001P003C01  I125
  U1     B71  DDR0_SA_DQS_DN2  SOCKET4677_AZIFS054P001C01   I2

M_A_CPU1_SA_DQS_DN<3>   @S9S_MB_2U_LIB.S9S_MB_2U(SCH_1):M_A_CPU1_SA_DQS_DN<3>
  J17     45  DQS3_A_N  SCONN288_ADR50001P013C01  I126
  J18     45  DQS3_A_N  SCONN288_ADR50001P003C01  I125
  U1     A64  DDR0_SA_DQS_DN3  SOCKET4677_AZIFS054P001C01   I2

M_A_CPU1_SA_DQS_DN<4>   @S9S_MB_2U_LIB.S9S_MB_2U(SCH_1):M_A_CPU1_SA_DQS_DN<4>
  J17     56  DQS4_A_N  SCONN288_ADR50001P013C01  I126
  J18     56  DQS4_A_N  SCONN288_ADR50001P003C01  I125
  U1     A58  DDR0_SA_DQS_DN4  SOCKET4677_AZIFS054P001C01   I2

M_A_CPU1_SA_DQS_DN<5>   @S9S_MB_2U_LIB.S9S_MB_2U(SCH_1):M_A_CPU1_SA_DQS_DN<5>
  J17    156  DQS5_A_N  SCONN288_ADR50001P013C01  I126
  J18    156  DQS5_A_N  SCONN288_ADR50001P003C01  I125
  U1     H77  DDR0_SA_DQS_DN5  SOCKET4677_AZIFS054P001C01   I2

M_A_CPU1_SA_DQS_DN<6>   @S9S_MB_2U_LIB.S9S_MB_2U(SCH_1):M_A_CPU1_SA_DQS_DN<6>
  J17    167  DQS6_A_N  SCONN288_ADR50001P013C01  I126
  J18    167  DQS6_A_N  SCONN288_ADR50001P003C01  I125
  U1     P67  DDR0_SA_DQS_DN6  SOCKET4677_AZIFS054P001C01   I2

M_A_CPU1_SA_DQS_DN<7>   @S9S_MB_2U_LIB.S9S_MB_2U(SCH_1):M_A_CPU1_SA_DQS_DN<7>
  J17    178  DQS7_A_N  SCONN288_ADR50001P013C01  I126
  J18    178  DQS7_A_N  SCONN288_ADR50001P003C01  I125
  U1     G70  DDR0_SA_DQS_DN7  SOCKET4677_AZIFS054P001C01   I2

M_A_CPU1_SA_DQS_DN<8>   @S9S_MB_2U_LIB.S9S_MB_2U(SCH_1):M_A_CPU1_SA_DQS_DN<8>
  J17    189  DQS8_A_N  SCONN288_ADR50001P013C01  I126
  J18    189  DQS8_A_N  SCONN288_ADR50001P003C01  I125
  U1     G64  DDR0_SA_DQS_DN8  SOCKET4677_AZIFS054P001C01   I2

M_A_CPU1_SA_DQS_DN<9>   @S9S_MB_2U_LIB.S9S_MB_2U(SCH_1):M_A_CPU1_SA_DQS_DN<9>
  J17    200  DQS9_A_N  SCONN288_ADR50001P013C01  I126
  J18    200  DQS9_A_N  SCONN288_ADR50001P003C01  I125
  U1     G58  DDR0_SA_DQS_DN9  SOCKET4677_AZIFS054P001C01   I2

M_A_CPU1_SA_DQS_DP<0>   @S9S_MB_2U_LIB.S9S_MB_2U(SCH_1):M_A_CPU1_SA_DQS_DP<0>
  J17     11  DQS0_A_P  SCONN288_ADR50001P013C01  I126
  J18     11  DQS0_A_P  SCONN288_ADR50001P003C01  I125
  U1     D77  DDR0_SA_DQS_DP0  SOCKET4677_AZIFS054P001C01   I2

M_A_CPU1_SA_DQS_DP<1>   @S9S_MB_2U_LIB.S9S_MB_2U(SCH_1):M_A_CPU1_SA_DQS_DP<1>
  J17     22  DQS1_A_P  SCONN288_ADR50001P013C01  I126
  J18     22  DQS1_A_P  SCONN288_ADR50001P003C01  I125
  U1     K67  DDR0_SA_DQS_DP1  SOCKET4677_AZIFS054P001C01   I2

M_A_CPU1_SA_DQS_DP<2>   @S9S_MB_2U_LIB.S9S_MB_2U(SCH_1):M_A_CPU1_SA_DQS_DP<2>
  J17     33  DQS2_A_P  SCONN288_ADR50001P013C01  I126
  J18     33  DQS2_A_P  SCONN288_ADR50001P003C01  I125
  U1     C70  DDR0_SA_DQS_DP2  SOCKET4677_AZIFS054P001C01   I2

M_A_CPU1_SA_DQS_DP<3>   @S9S_MB_2U_LIB.S9S_MB_2U(SCH_1):M_A_CPU1_SA_DQS_DP<3>
  J17     44  DQS3_A_P  SCONN288_ADR50001P013C01  I126
  J18     44  DQS3_A_P  SCONN288_ADR50001P003C01  I125
  U1     C64  DDR0_SA_DQS_DP3  SOCKET4677_AZIFS054P001C01   I2

M_A_CPU1_SA_DQS_DP<4>   @S9S_MB_2U_LIB.S9S_MB_2U(SCH_1):M_A_CPU1_SA_DQS_DP<4>
  J17     55  DQS4_A_P  SCONN288_ADR50001P013C01  I126
  J18     55  DQS4_A_P  SCONN288_ADR50001P003C01  I125
  U1     C58  DDR0_SA_DQS_DP4  SOCKET4677_AZIFS054P001C01   I2

M_A_CPU1_SA_DQS_DP<5>   @S9S_MB_2U_LIB.S9S_MB_2U(SCH_1):M_A_CPU1_SA_DQS_DP<5>
  J17    157  DQS5_A_P  SCONN288_ADR50001P013C01  I126
  J18    157  DQS5_A_P  SCONN288_ADR50001P003C01  I125
  U1     F77  DDR0_SA_DQS_DP5  SOCKET4677_AZIFS054P001C01   I2

M_A_CPU1_SA_DQS_DP<6>   @S9S_MB_2U_LIB.S9S_MB_2U(SCH_1):M_A_CPU1_SA_DQS_DP<6>
  J17    168  DQS6_A_P  SCONN288_ADR50001P013C01  I126
  J18    168  DQS6_A_P  SCONN288_ADR50001P003C01  I125
  U1     M67  DDR0_SA_DQS_DP6  SOCKET4677_AZIFS054P001C01   I2

M_A_CPU1_SA_DQS_DP<7>   @S9S_MB_2U_LIB.S9S_MB_2U(SCH_1):M_A_CPU1_SA_DQS_DP<7>
  J17    179  DQS7_A_P  SCONN288_ADR50001P013C01  I126
  J18    179  DQS7_A_P  SCONN288_ADR50001P003C01  I125
  U1     E70  DDR0_SA_DQS_DP7  SOCKET4677_AZIFS054P001C01   I2

M_A_CPU1_SA_DQS_DP<8>   @S9S_MB_2U_LIB.S9S_MB_2U(SCH_1):M_A_CPU1_SA_DQS_DP<8>
  J17    190  DQS8_A_P  SCONN288_ADR50001P013C01  I126
  J18    190  DQS8_A_P  SCONN288_ADR50001P003C01  I125
  U1     E64  DDR0_SA_DQS_DP8  SOCKET4677_AZIFS054P001C01   I2

M_A_CPU1_SA_DQS_DP<9>   @S9S_MB_2U_LIB.S9S_MB_2U(SCH_1):M_A_CPU1_SA_DQS_DP<9>
  J17    201  DQS9_A_P  SCONN288_ADR50001P013C01  I126
  J18    201  DQS9_A_P  SCONN288_ADR50001P003C01  I125
  U1     E58  DDR0_SA_DQS_DP9  SOCKET4677_AZIFS054P001C01   I2

M_A_CPU1_SA_PAR   @S9S_MB_2U_LIB.S9S_MB_2U(SCH_1):M_A_CPU1_SA_PAR
  J17     74  PAR_A  SCONN288_ADR50001P013C01  I12
  J18     74  PAR_A  SCONN288_ADR50001P003C01  I24
  U1     E48  DDR0_SA_PAR  SOCKET4677_AZIFS054P001C01   I2

M_A_CPU1_SA_RSP<0>   @S9S_MB_2U_LIB.S9S_MB_2U(SCH_1):M_A_CPU1_SA_RSP<0>
  J17     86  LBD||RSP_N_A  SCONN288_ADR50001P013C01  I12
  U1     AT42  DDR0_A_RSP0  SOCKET4677_AZIFS054P001C01   I2

M_A_CPU1_SA_RSP<1>   @S9S_MB_2U_LIB.S9S_MB_2U(SCH_1):M_A_CPU1_SA_RSP<1>
  J18     86  LBD||RSP_N_A  SCONN288_ADR50001P003C01  I24
  U1     AU43  DDR0_A_RSP1  SOCKET4677_AZIFS054P001C01   I2

M_A_CPU1_SB_CA<0>   @S9S_MB_2U_LIB.S9S_MB_2U(SCH_1):M_A_CPU1_SB_CA<0>
  J17     76  CA0_B  SCONN288_ADR50001P013C01  I12
  J18     76  CA0_B  SCONN288_ADR50001P003C01  I24
  U1     E43  DDR0_SB_CA0  SOCKET4677_AZIFS054P001C01   I2

M_A_CPU1_SB_CA<1>   @S9S_MB_2U_LIB.S9S_MB_2U(SCH_1):M_A_CPU1_SB_CA<1>
  J17    221  CA1_B  SCONN288_ADR50001P013C01  I12
  J18    221  CA1_B  SCONN288_ADR50001P003C01  I24
  U1     F44  DDR0_SB_CA1  SOCKET4677_AZIFS054P001C01   I2

M_A_CPU1_SB_CA<2>   @S9S_MB_2U_LIB.S9S_MB_2U(SCH_1):M_A_CPU1_SB_CA<2>
  J17     78  CA2_B  SCONN288_ADR50001P013C01  I12
  J18     78  CA2_B  SCONN288_ADR50001P003C01  I24
  U1     C41  DDR0_SB_CA2  SOCKET4677_AZIFS054P001C01   I2

M_A_CPU1_SB_CA<3>   @S9S_MB_2U_LIB.S9S_MB_2U(SCH_1):M_A_CPU1_SB_CA<3>
  J17    223  CA3_B  SCONN288_ADR50001P013C01  I12
  J18    223  CA3_B  SCONN288_ADR50001P003C01  I24
  U1     E41  DDR0_SB_CA3  SOCKET4677_AZIFS054P001C01   I2

M_A_CPU1_SB_CA<4>   @S9S_MB_2U_LIB.S9S_MB_2U(SCH_1):M_A_CPU1_SB_CA<4>
  J17     80  CA4_B  SCONN288_ADR50001P013C01  I12
  J18     80  CA4_B  SCONN288_ADR50001P003C01  I24
  U1     B40  DDR0_SB_CA4  SOCKET4677_AZIFS054P001C01   I2

M_A_CPU1_SB_CA<5>   @S9S_MB_2U_LIB.S9S_MB_2U(SCH_1):M_A_CPU1_SB_CA<5>
  J17    225  CA5_B  SCONN288_ADR50001P013C01  I12
  J18    225  CA5_B  SCONN288_ADR50001P003C01  I24
  U1     F40  DDR0_SB_CA5  SOCKET4677_AZIFS054P001C01   I2

M_A_CPU1_SB_CA<6>   @S9S_MB_2U_LIB.S9S_MB_2U(SCH_1):M_A_CPU1_SB_CA<6>
  J17     82  CA6_B  SCONN288_ADR50001P013C01  I12
  J18     82  CA6_B  SCONN288_ADR50001P003C01  I24
  U1     A39  DDR0_SB_CA6  SOCKET4677_AZIFS054P001C01   I2

M_A_CPU1_SB_CB<0>   @S9S_MB_2U_LIB.S9S_MB_2U(SCH_1):M_A_CPU1_SB_CB<0>
  J17     96  CB_B0  SCONN288_ADR50001P013C01  I12
  J18     96  CB_B0  SCONN288_ADR50001P003C01  I24
  U1     B32  DDR0_SB_ECC0  SOCKET4677_AZIFS054P001C01   I2

M_A_CPU1_SB_CB<1>   @S9S_MB_2U_LIB.S9S_MB_2U(SCH_1):M_A_CPU1_SB_CB<1>
  J17     98  CB_B1  SCONN288_ADR50001P013C01  I12
  J18     98  CB_B1  SCONN288_ADR50001P003C01  I24
  U1     C31  DDR0_SB_ECC1  SOCKET4677_AZIFS054P001C01   I2

M_A_CPU1_SB_CB<2>   @S9S_MB_2U_LIB.S9S_MB_2U(SCH_1):M_A_CPU1_SB_CB<2>
  J17    241  CB_B2  SCONN288_ADR50001P013C01  I12
  J18    241  CB_B2  SCONN288_ADR50001P003C01  I24
  U1     F32  DDR0_SB_ECC2  SOCKET4677_AZIFS054P001C01   I2

M_A_CPU1_SB_CB<3>   @S9S_MB_2U_LIB.S9S_MB_2U(SCH_1):M_A_CPU1_SB_CB<3>
  J17    243  CB_B3  SCONN288_ADR50001P013C01  I12
  J18    243  CB_B3  SCONN288_ADR50001P003C01  I24
  U1     E31  DDR0_SB_ECC3  SOCKET4677_AZIFS054P001C01   I2

M_A_CPU1_SB_CB<4>   @S9S_MB_2U_LIB.S9S_MB_2U(SCH_1):M_A_CPU1_SB_CB<4>
  J17     89  CB_B4  SCONN288_ADR50001P013C01  I12
  J18     89  CB_B4  SCONN288_ADR50001P003C01  I24
  U1     C35  DDR0_SB_ECC4  SOCKET4677_AZIFS054P001C01   I2

M_A_CPU1_SB_CB<5>   @S9S_MB_2U_LIB.S9S_MB_2U(SCH_1):M_A_CPU1_SB_CB<5>
  J17     91  CB_B5  SCONN288_ADR50001P013C01  I12
  J18     91  CB_B5  SCONN288_ADR50001P003C01  I24
  U1     B34  DDR0_SB_ECC5  SOCKET4677_AZIFS054P001C01   I2

M_A_CPU1_SB_CB<6>   @S9S_MB_2U_LIB.S9S_MB_2U(SCH_1):M_A_CPU1_SB_CB<6>
  J17    234  CB_B6  SCONN288_ADR50001P013C01  I12
  J18    234  CB_B6  SCONN288_ADR50001P003C01  I24
  U1     E35  DDR0_SB_ECC6  SOCKET4677_AZIFS054P001C01   I2

M_A_CPU1_SB_CB<7>   @S9S_MB_2U_LIB.S9S_MB_2U(SCH_1):M_A_CPU1_SB_CB<7>
  J17    236  CB_B7  SCONN288_ADR50001P013C01  I12
  J18    236  CB_B7  SCONN288_ADR50001P003C01  I24
  U1     F34  DDR0_SB_ECC7  SOCKET4677_AZIFS054P001C01   I2

M_A_CPU1_SB_CS_N<0>   @S9S_MB_2U_LIB.S9S_MB_2U(SCH_1):M_A_CPU1_SB_CS_N<0>
  J17     84  CS0_N_B  SCONN288_ADR50001P013C01  I12
  U1     B38  DDR0_SB_CS0_N  SOCKET4677_AZIFS054P001C01   I2

M_A_CPU1_SB_CS_N<1>   @S9S_MB_2U_LIB.S9S_MB_2U(SCH_1):M_A_CPU1_SB_CS_N<1>
  J17    229  CS1_N_B  SCONN288_ADR50001P013C01  I12
  U1     C37  DDR0_SB_CS1_N  SOCKET4677_AZIFS054P001C01   I2

M_A_CPU1_SB_CS_N<2>   @S9S_MB_2U_LIB.S9S_MB_2U(SCH_1):M_A_CPU1_SB_CS_N<2>
  J18     84  CS0_N_B  SCONN288_ADR50001P003C01  I24
  U1     F38  DDR0_SB_CS2_N  SOCKET4677_AZIFS054P001C01   I2

M_A_CPU1_SB_CS_N<3>   @S9S_MB_2U_LIB.S9S_MB_2U(SCH_1):M_A_CPU1_SB_CS_N<3>
  J18    229  CS1_N_B  SCONN288_ADR50001P003C01  I24
  U1     E37  DDR0_SB_CS3_N  SOCKET4677_AZIFS054P001C01   I2

M_A_CPU1_SB_DQ<0>   @S9S_MB_2U_LIB.S9S_MB_2U(SCH_1):M_A_CPU1_SB_DQ<0>
  J17    100  DQ_B0  SCONN288_ADR50001P013C01  I12
  J18    100  DQ_B0  SCONN288_ADR50001P003C01  I24
  U1     K32  DDR0_SB_DQ0  SOCKET4677_AZIFS054P001C01   I2

M_A_CPU1_SB_DQ<1>   @S9S_MB_2U_LIB.S9S_MB_2U(SCH_1):M_A_CPU1_SB_DQ<1>
  J17    102  DQ_B1  SCONN288_ADR50001P013C01  I12
  J18    102  DQ_B1  SCONN288_ADR50001P003C01  I24
  U1     J31  DDR0_SB_DQ1  SOCKET4677_AZIFS054P001C01   I2

M_A_CPU1_SB_DQ<2>   @S9S_MB_2U_LIB.S9S_MB_2U(SCH_1):M_A_CPU1_SB_DQ<2>
  J17    245  DQ_B2  SCONN288_ADR50001P013C01  I12
  J18    245  DQ_B2  SCONN288_ADR50001P003C01  I24
  U1     M32  DDR0_SB_DQ2  SOCKET4677_AZIFS054P001C01   I2

M_A_CPU1_SB_DQ<3>   @S9S_MB_2U_LIB.S9S_MB_2U(SCH_1):M_A_CPU1_SB_DQ<3>
  J17    247  DQ_B3  SCONN288_ADR50001P013C01  I12
  J18    247  DQ_B3  SCONN288_ADR50001P003C01  I24
  U1     N31  DDR0_SB_DQ3  SOCKET4677_AZIFS054P001C01   I2

M_A_CPU1_SB_DQ<4>   @S9S_MB_2U_LIB.S9S_MB_2U(SCH_1):M_A_CPU1_SB_DQ<4>
  J17    107  DQ_B4  SCONN288_ADR50001P013C01  I12
  J18    107  DQ_B4  SCONN288_ADR50001P003C01  I24
  U1     J29  DDR0_SB_DQ4  SOCKET4677_AZIFS054P001C01   I2

M_A_CPU1_SB_DQ<5>   @S9S_MB_2U_LIB.S9S_MB_2U(SCH_1):M_A_CPU1_SB_DQ<5>
  J17    109  DQ_B5  SCONN288_ADR50001P013C01  I12
  J18    109  DQ_B5  SCONN288_ADR50001P003C01  I24
  U1     K28  DDR0_SB_DQ5  SOCKET4677_AZIFS054P001C01   I2

M_A_CPU1_SB_DQ<6>   @S9S_MB_2U_LIB.S9S_MB_2U(SCH_1):M_A_CPU1_SB_DQ<6>
  J17    252  DQ_B6  SCONN288_ADR50001P013C01  I12
  J18    252  DQ_B6  SCONN288_ADR50001P003C01  I24
  U1     N29  DDR0_SB_DQ6  SOCKET4677_AZIFS054P001C01   I2

M_A_CPU1_SB_DQ<7>   @S9S_MB_2U_LIB.S9S_MB_2U(SCH_1):M_A_CPU1_SB_DQ<7>
  J17    254  DQ_B7  SCONN288_ADR50001P013C01  I12
  J18    254  DQ_B7  SCONN288_ADR50001P003C01  I24
  U1     M28  DDR0_SB_DQ7  SOCKET4677_AZIFS054P001C01   I2

M_A_CPU1_SB_DQ<8>   @S9S_MB_2U_LIB.S9S_MB_2U(SCH_1):M_A_CPU1_SB_DQ<8>
  J17    111  DQ_B8  SCONN288_ADR50001P013C01  I12
  J18    111  DQ_B8  SCONN288_ADR50001P003C01  I24
  U1     C29  DDR0_SB_DQ8  SOCKET4677_AZIFS054P001C01   I2

M_A_CPU1_SB_DQ<9>   @S9S_MB_2U_LIB.S9S_MB_2U(SCH_1):M_A_CPU1_SB_DQ<9>
  J17    113  DQ_B9  SCONN288_ADR50001P013C01  I12
  J18    113  DQ_B9  SCONN288_ADR50001P003C01  I24
  U1     B28  DDR0_SB_DQ9  SOCKET4677_AZIFS054P001C01   I2

M_A_CPU1_SB_DQ<10>   @S9S_MB_2U_LIB.S9S_MB_2U(SCH_1):M_A_CPU1_SB_DQ<10>
  J17    256  DQ_B10  SCONN288_ADR50001P013C01  I12
  J18    256  DQ_B10  SCONN288_ADR50001P003C01  I24
  U1     E29  DDR0_SB_DQ10  SOCKET4677_AZIFS054P001C01   I2

M_A_CPU1_SB_DQ<11>   @S9S_MB_2U_LIB.S9S_MB_2U(SCH_1):M_A_CPU1_SB_DQ<11>
  J17    258  DQ_B11  SCONN288_ADR50001P013C01  I12
  J18    258  DQ_B11  SCONN288_ADR50001P003C01  I24
  U1     F28  DDR0_SB_DQ11  SOCKET4677_AZIFS054P001C01   I2

M_A_CPU1_SB_DQ<12>   @S9S_MB_2U_LIB.S9S_MB_2U(SCH_1):M_A_CPU1_SB_DQ<12>
  J17    118  DQ_B12  SCONN288_ADR50001P013C01  I12
  J18    118  DQ_B12  SCONN288_ADR50001P003C01  I24
  U1     B26  DDR0_SB_DQ12  SOCKET4677_AZIFS054P001C01   I2

M_A_CPU1_SB_DQ<13>   @S9S_MB_2U_LIB.S9S_MB_2U(SCH_1):M_A_CPU1_SB_DQ<13>
  J17    120  DQ_B13  SCONN288_ADR50001P013C01  I12
  J18    120  DQ_B13  SCONN288_ADR50001P003C01  I24
  U1     C25  DDR0_SB_DQ13  SOCKET4677_AZIFS054P001C01   I2

M_A_CPU1_SB_DQ<14>   @S9S_MB_2U_LIB.S9S_MB_2U(SCH_1):M_A_CPU1_SB_DQ<14>
  J17    263  DQ_B14  SCONN288_ADR50001P013C01  I12
  J18    263  DQ_B14  SCONN288_ADR50001P003C01  I24
  U1     F26  DDR0_SB_DQ14  SOCKET4677_AZIFS054P001C01   I2

M_A_CPU1_SB_DQ<15>   @S9S_MB_2U_LIB.S9S_MB_2U(SCH_1):M_A_CPU1_SB_DQ<15>
  J17    265  DQ_B15  SCONN288_ADR50001P013C01  I12
  J18    265  DQ_B15  SCONN288_ADR50001P003C01  I24
  U1     E25  DDR0_SB_DQ15  SOCKET4677_AZIFS054P001C01   I2

M_A_CPU1_SB_DQ<16>   @S9S_MB_2U_LIB.S9S_MB_2U(SCH_1):M_A_CPU1_SB_DQ<16>
  J17    122  DQ_B16  SCONN288_ADR50001P013C01  I12
  J18    122  DQ_B16  SCONN288_ADR50001P003C01  I24
  U1     C23  DDR0_SB_DQ16  SOCKET4677_AZIFS054P001C01   I2

M_A_CPU1_SB_DQ<17>   @S9S_MB_2U_LIB.S9S_MB_2U(SCH_1):M_A_CPU1_SB_DQ<17>
  J17    124  DQ_B17  SCONN288_ADR50001P013C01  I12
  J18    124  DQ_B17  SCONN288_ADR50001P003C01  I24
  U1     B22  DDR0_SB_DQ17  SOCKET4677_AZIFS054P001C01   I2

M_A_CPU1_SB_DQ<18>   @S9S_MB_2U_LIB.S9S_MB_2U(SCH_1):M_A_CPU1_SB_DQ<18>
  J17    267  DQ_B18  SCONN288_ADR50001P013C01  I12
  J18    267  DQ_B18  SCONN288_ADR50001P003C01  I24
  U1     E23  DDR0_SB_DQ18  SOCKET4677_AZIFS054P001C01   I2

M_A_CPU1_SB_DQ<19>   @S9S_MB_2U_LIB.S9S_MB_2U(SCH_1):M_A_CPU1_SB_DQ<19>
  J17    269  DQ_B19  SCONN288_ADR50001P013C01  I12
  J18    269  DQ_B19  SCONN288_ADR50001P003C01  I24
  U1     F22  DDR0_SB_DQ19  SOCKET4677_AZIFS054P001C01   I2

M_A_CPU1_SB_DQ<20>   @S9S_MB_2U_LIB.S9S_MB_2U(SCH_1):M_A_CPU1_SB_DQ<20>
  J17    129  DQ_B20  SCONN288_ADR50001P013C01  I12
  J18    129  DQ_B20  SCONN288_ADR50001P003C01  I24
  U1     B20  DDR0_SB_DQ20  SOCKET4677_AZIFS054P001C01   I2

M_A_CPU1_SB_DQ<21>   @S9S_MB_2U_LIB.S9S_MB_2U(SCH_1):M_A_CPU1_SB_DQ<21>
  J17    131  DQ_B21  SCONN288_ADR50001P013C01  I12
  J18    131  DQ_B21  SCONN288_ADR50001P003C01  I24
  U1     C19  DDR0_SB_DQ21  SOCKET4677_AZIFS054P001C01   I2

M_A_CPU1_SB_DQ<22>   @S9S_MB_2U_LIB.S9S_MB_2U(SCH_1):M_A_CPU1_SB_DQ<22>
  J17    274  DQ_B22  SCONN288_ADR50001P013C01  I12
  J18    274  DQ_B22  SCONN288_ADR50001P003C01  I24
  U1     F20  DDR0_SB_DQ22  SOCKET4677_AZIFS054P001C01   I2

M_A_CPU1_SB_DQ<23>   @S9S_MB_2U_LIB.S9S_MB_2U(SCH_1):M_A_CPU1_SB_DQ<23>
  J17    276  DQ_B23  SCONN288_ADR50001P013C01  I12
  J18    276  DQ_B23  SCONN288_ADR50001P003C01  I24
  U1     E19  DDR0_SB_DQ23  SOCKET4677_AZIFS054P001C01   I2

M_A_CPU1_SB_DQ<24>   @S9S_MB_2U_LIB.S9S_MB_2U(SCH_1):M_A_CPU1_SB_DQ<24>
  J17    133  DQ_B24  SCONN288_ADR50001P013C01  I12
  J18    133  DQ_B24  SCONN288_ADR50001P003C01  I24
  U1     C11  DDR0_SB_DQ24  SOCKET4677_AZIFS054P001C01   I2

M_A_CPU1_SB_DQ<25>   @S9S_MB_2U_LIB.S9S_MB_2U(SCH_1):M_A_CPU1_SB_DQ<25>
  J17    135  DQ_B25  SCONN288_ADR50001P013C01  I12
  J18    135  DQ_B25  SCONN288_ADR50001P003C01  I24
  U1     B10  DDR0_SB_DQ25  SOCKET4677_AZIFS054P001C01   I2

M_A_CPU1_SB_DQ<26>   @S9S_MB_2U_LIB.S9S_MB_2U(SCH_1):M_A_CPU1_SB_DQ<26>
  J17    278  DQ_B26  SCONN288_ADR50001P013C01  I12
  J18    278  DQ_B26  SCONN288_ADR50001P003C01  I24
  U1     E11  DDR0_SB_DQ26  SOCKET4677_AZIFS054P001C01   I2

M_A_CPU1_SB_DQ<27>   @S9S_MB_2U_LIB.S9S_MB_2U(SCH_1):M_A_CPU1_SB_DQ<27>
  J17    280  DQ_B27  SCONN288_ADR50001P013C01  I12
  J18    280  DQ_B27  SCONN288_ADR50001P003C01  I24
  U1     F10  DDR0_SB_DQ27  SOCKET4677_AZIFS054P001C01   I2

M_A_CPU1_SB_DQ<28>   @S9S_MB_2U_LIB.S9S_MB_2U(SCH_1):M_A_CPU1_SB_DQ<28>
  J17    140  DQ_B28  SCONN288_ADR50001P013C01  I12
  J18    140  DQ_B28  SCONN288_ADR50001P003C01  I24
  U1      B8  DDR0_SB_DQ28  SOCKET4677_AZIFS054P001C01   I2

M_A_CPU1_SB_DQ<29>   @S9S_MB_2U_LIB.S9S_MB_2U(SCH_1):M_A_CPU1_SB_DQ<29>
  J17    142  DQ_B29  SCONN288_ADR50001P013C01  I12
  J18    142  DQ_B29  SCONN288_ADR50001P003C01  I24
  U1      C7  DDR0_SB_DQ29  SOCKET4677_AZIFS054P001C01   I2

M_A_CPU1_SB_DQ<30>   @S9S_MB_2U_LIB.S9S_MB_2U(SCH_1):M_A_CPU1_SB_DQ<30>
  J17    285  DQ_B30  SCONN288_ADR50001P013C01  I12
  J18    285  DQ_B30  SCONN288_ADR50001P003C01  I24
  U1      F8  DDR0_SB_DQ30  SOCKET4677_AZIFS054P001C01   I2

M_A_CPU1_SB_DQ<31>   @S9S_MB_2U_LIB.S9S_MB_2U(SCH_1):M_A_CPU1_SB_DQ<31>
  J17    287  DQ_B31  SCONN288_ADR50001P013C01  I12
  J18    287  DQ_B31  SCONN288_ADR50001P003C01  I24
  U1      E7  DDR0_SB_DQ31  SOCKET4677_AZIFS054P001C01   I2

M_A_CPU1_SB_DQS_DN<0>   @S9S_MB_2U_LIB.S9S_MB_2U(SCH_1):M_A_CPU1_SB_DQS_DN<0>
  J17    105  DQS0_B_N  SCONN288_ADR50001P013C01  I126
  J18    105  DQS0_B_N  SCONN288_ADR50001P003C01  I125
  U1     H30  DDR0_SB_DQS_DN0  SOCKET4677_AZIFS054P001C01   I2

M_A_CPU1_SB_DQS_DN<1>   @S9S_MB_2U_LIB.S9S_MB_2U(SCH_1):M_A_CPU1_SB_DQS_DN<1>
  J17    116  DQS1_B_N  SCONN288_ADR50001P013C01  I126
  J18    116  DQS1_B_N  SCONN288_ADR50001P003C01  I125
  U1     A27  DDR0_SB_DQS_DN1  SOCKET4677_AZIFS054P001C01   I2

M_A_CPU1_SB_DQS_DN<2>   @S9S_MB_2U_LIB.S9S_MB_2U(SCH_1):M_A_CPU1_SB_DQS_DN<2>
  J17    127  DQS2_B_N  SCONN288_ADR50001P013C01  I126
  J18    127  DQS2_B_N  SCONN288_ADR50001P003C01  I125
  U1     A21  DDR0_SB_DQS_DN2  SOCKET4677_AZIFS054P001C01   I2

M_A_CPU1_SB_DQS_DN<3>   @S9S_MB_2U_LIB.S9S_MB_2U(SCH_1):M_A_CPU1_SB_DQS_DN<3>
  J17    138  DQS3_B_N  SCONN288_ADR50001P013C01  I126
  J18    138  DQS3_B_N  SCONN288_ADR50001P003C01  I125
  U1      A9  DDR0_SB_DQS_DN3  SOCKET4677_AZIFS054P001C01   I2

M_A_CPU1_SB_DQS_DN<4>   @S9S_MB_2U_LIB.S9S_MB_2U(SCH_1):M_A_CPU1_SB_DQS_DN<4>
  J17    238  DQS4_B_N  SCONN288_ADR50001P013C01  I126
  J18    238  DQS4_B_N  SCONN288_ADR50001P003C01  I125
  U1     G33  DDR0_SB_DQS_DN4  SOCKET4677_AZIFS054P001C01   I2

M_A_CPU1_SB_DQS_DN<5>   @S9S_MB_2U_LIB.S9S_MB_2U(SCH_1):M_A_CPU1_SB_DQS_DN<5>
  J17    249  DQS5_B_N  SCONN288_ADR50001P013C01  I126
  J18    249  DQS5_B_N  SCONN288_ADR50001P003C01  I125
  U1     M30  DDR0_SB_DQS_DN5  SOCKET4677_AZIFS054P001C01   I2

M_A_CPU1_SB_DQS_DN<6>   @S9S_MB_2U_LIB.S9S_MB_2U(SCH_1):M_A_CPU1_SB_DQS_DN<6>
  J17    260  DQS6_B_N  SCONN288_ADR50001P013C01  I126
  J18    260  DQS6_B_N  SCONN288_ADR50001P003C01  I125
  U1     G27  DDR0_SB_DQS_DN6  SOCKET4677_AZIFS054P001C01   I2

M_A_CPU1_SB_DQS_DN<7>   @S9S_MB_2U_LIB.S9S_MB_2U(SCH_1):M_A_CPU1_SB_DQS_DN<7>
  J17    271  DQS7_B_N  SCONN288_ADR50001P013C01  I126
  J18    271  DQS7_B_N  SCONN288_ADR50001P003C01  I125
  U1     G21  DDR0_SB_DQS_DN7  SOCKET4677_AZIFS054P001C01   I2

M_A_CPU1_SB_DQS_DN<8>   @S9S_MB_2U_LIB.S9S_MB_2U(SCH_1):M_A_CPU1_SB_DQS_DN<8>
  J17    282  DQS8_B_N  SCONN288_ADR50001P013C01  I126
  J18    282  DQS8_B_N  SCONN288_ADR50001P003C01  I125
  U1      G9  DDR0_SB_DQS_DN8  SOCKET4677_AZIFS054P001C01   I2

M_A_CPU1_SB_DQS_DN<9>   @S9S_MB_2U_LIB.S9S_MB_2U(SCH_1):M_A_CPU1_SB_DQS_DN<9>
  J17     94  DQS9_B_N  SCONN288_ADR50001P013C01  I126
  J18     94  DQS9_B_N  SCONN288_ADR50001P003C01  I125
  U1     A33  DDR0_SB_DQS_DN9  SOCKET4677_AZIFS054P001C01   I2

M_A_CPU1_SB_DQS_DP<0>   @S9S_MB_2U_LIB.S9S_MB_2U(SCH_1):M_A_CPU1_SB_DQS_DP<0>
  J17    104  DQS0_B_P  SCONN288_ADR50001P013C01  I126
  J18    104  DQS0_B_P  SCONN288_ADR50001P003C01  I125
  U1     K30  DDR0_SB_DQS_DP0  SOCKET4677_AZIFS054P001C01   I2

M_A_CPU1_SB_DQS_DP<1>   @S9S_MB_2U_LIB.S9S_MB_2U(SCH_1):M_A_CPU1_SB_DQS_DP<1>
  J17    115  DQS1_B_P  SCONN288_ADR50001P013C01  I126
  J18    115  DQS1_B_P  SCONN288_ADR50001P003C01  I125
  U1     C27  DDR0_SB_DQS_DP1  SOCKET4677_AZIFS054P001C01   I2

M_A_CPU1_SB_DQS_DP<2>   @S9S_MB_2U_LIB.S9S_MB_2U(SCH_1):M_A_CPU1_SB_DQS_DP<2>
  J17    126  DQS2_B_P  SCONN288_ADR50001P013C01  I126
  J18    126  DQS2_B_P  SCONN288_ADR50001P003C01  I125
  U1     C21  DDR0_SB_DQS_DP2  SOCKET4677_AZIFS054P001C01   I2

M_A_CPU1_SB_DQS_DP<3>   @S9S_MB_2U_LIB.S9S_MB_2U(SCH_1):M_A_CPU1_SB_DQS_DP<3>
  J17    137  DQS3_B_P  SCONN288_ADR50001P013C01  I126
  J18    137  DQS3_B_P  SCONN288_ADR50001P003C01  I125
  U1      C9  DDR0_SB_DQS_DP3  SOCKET4677_AZIFS054P001C01   I2

M_A_CPU1_SB_DQS_DP<4>   @S9S_MB_2U_LIB.S9S_MB_2U(SCH_1):M_A_CPU1_SB_DQS_DP<4>
  J17    239  DQS4_B_P  SCONN288_ADR50001P013C01  I126
  J18    239  DQS4_B_P  SCONN288_ADR50001P003C01  I125
  U1     E33  DDR0_SB_DQS_DP4  SOCKET4677_AZIFS054P001C01   I2

M_A_CPU1_SB_DQS_DP<5>   @S9S_MB_2U_LIB.S9S_MB_2U(SCH_1):M_A_CPU1_SB_DQS_DP<5>
  J17    250  DQS5_B_P  SCONN288_ADR50001P013C01  I126
  J18    250  DQS5_B_P  SCONN288_ADR50001P003C01  I125
  U1     P30  DDR0_SB_DQS_DP5  SOCKET4677_AZIFS054P001C01   I2

M_A_CPU1_SB_DQS_DP<6>   @S9S_MB_2U_LIB.S9S_MB_2U(SCH_1):M_A_CPU1_SB_DQS_DP<6>
  J17    261  DQS6_B_P  SCONN288_ADR50001P013C01  I126
  J18    261  DQS6_B_P  SCONN288_ADR50001P003C01  I125
  U1     E27  DDR0_SB_DQS_DP6  SOCKET4677_AZIFS054P001C01   I2

M_A_CPU1_SB_DQS_DP<7>   @S9S_MB_2U_LIB.S9S_MB_2U(SCH_1):M_A_CPU1_SB_DQS_DP<7>
  J17    272  DQS7_B_P  SCONN288_ADR50001P013C01  I126
  J18    272  DQS7_B_P  SCONN288_ADR50001P003C01  I125
  U1     E21  DDR0_SB_DQS_DP7  SOCKET4677_AZIFS054P001C01   I2

M_A_CPU1_SB_DQS_DP<8>   @S9S_MB_2U_LIB.S9S_MB_2U(SCH_1):M_A_CPU1_SB_DQS_DP<8>
  J17    283  DQS8_B_P  SCONN288_ADR50001P013C01  I126
  J18    283  DQS8_B_P  SCONN288_ADR50001P003C01  I125
  U1      E9  DDR0_SB_DQS_DP8  SOCKET4677_AZIFS054P001C01   I2

M_A_CPU1_SB_DQS_DP<9>   @S9S_MB_2U_LIB.S9S_MB_2U(SCH_1):M_A_CPU1_SB_DQS_DP<9>
  J17     93  DQS9_B_P  SCONN288_ADR50001P013C01  I126
  J18     93  DQS9_B_P  SCONN288_ADR50001P003C01  I125
  U1     C33  DDR0_SB_DQS_DP9  SOCKET4677_AZIFS054P001C01   I2

M_A_CPU1_SB_PAR   @S9S_MB_2U_LIB.S9S_MB_2U(SCH_1):M_A_CPU1_SB_PAR
  J17    227  PAR_B  SCONN288_ADR50001P013C01  I12
  J18    227  PAR_B  SCONN288_ADR50001P003C01  I24
  U1     G39  DDR0_SB_PAR  SOCKET4677_AZIFS054P001C01   I2

M_A_CPU1_SB_RSP<0>   @S9S_MB_2U_LIB.S9S_MB_2U(SCH_1):M_A_CPU1_SB_RSP<0>
  J17     87  LBS||RSP_N_B  SCONN288_ADR50001P013C01  I12
  U1     AV44  DDR0_B_RSP0  SOCKET4677_AZIFS054P001C01   I2

M_A_CPU1_SB_RSP<1>   @S9S_MB_2U_LIB.S9S_MB_2U(SCH_1):M_A_CPU1_SB_RSP<1>
  J18     87  LBS||RSP_N_B  SCONN288_ADR50001P003C01  I24
  U1     AV42  DDR0_B_RSP1  SOCKET4677_AZIFS054P001C01   I2

M_B_CPU0_ALERT_N   @S9S_MB_2U_LIB.S9S_MB_2U(SCH_1):M_B_CPU0_ALERT_N
  J3      62  ALERT_N  SCONN288_ADR50001P013C01  I11
  J4      62  ALERT_N  SCONN288_ADR50001P003C01  I23
  U2     AV49  DDR1_ALERT_N  SOCKET4677_AZIFS054P001C01  I169

M_B_CPU0_CLK_DN<0>   @S9S_MB_2U_LIB.S9S_MB_2U(SCH_1):M_B_CPU0_CLK_DN<0>
  J3     218   CK_N  SCONN288_ADR50001P013C01  I11
  U2     R45  DDR1_CLK_DN0  SOCKET4677_AZIFS054P001C01  I169

M_B_CPU0_CLK_DN<1>   @S9S_MB_2U_LIB.S9S_MB_2U(SCH_1):M_B_CPU0_CLK_DN<1>
  J4     218   CK_N  SCONN288_ADR50001P003C01  I23
  U2     W45  DDR1_CLK_DN1  SOCKET4677_AZIFS054P001C01  I169

M_B_CPU0_CLK_DP<0>   @S9S_MB_2U_LIB.S9S_MB_2U(SCH_1):M_B_CPU0_CLK_DP<0>
  J3     217   CK_P  SCONN288_ADR50001P013C01  I11
  U2     U45  DDR1_CLK_DP0  SOCKET4677_AZIFS054P001C01  I169

M_B_CPU0_CLK_DP<1>   @S9S_MB_2U_LIB.S9S_MB_2U(SCH_1):M_B_CPU0_CLK_DP<1>
  J4     217   CK_P  SCONN288_ADR50001P003C01  I23
  U2     AA45  DDR1_CLK_DP1  SOCKET4677_AZIFS054P001C01  I169

M_B_CPU0_SA_CA<0>   @S9S_MB_2U_LIB.S9S_MB_2U(SCH_1):M_B_CPU0_SA_CA<0>
  J3      66  CA0_A  SCONN288_ADR50001P013C01  I11
  J4      66  CA0_A  SCONN288_ADR50001P003C01  I23
  U2     H49  DDR1_SA_CA0  SOCKET4677_AZIFS054P001C01  I169

M_B_CPU0_SA_CA<1>   @S9S_MB_2U_LIB.S9S_MB_2U(SCH_1):M_B_CPU0_SA_CA<1>
  J3     211  CA1_A  SCONN288_ADR50001P013C01  I11
  J4     211  CA1_A  SCONN288_ADR50001P003C01  I23
  U2     P49  DDR1_SA_CA1  SOCKET4677_AZIFS054P001C01  I169

M_B_CPU0_SA_CA<2>   @S9S_MB_2U_LIB.S9S_MB_2U(SCH_1):M_B_CPU0_SA_CA<2>
  J3      68  CA2_A  SCONN288_ADR50001P013C01  I11
  J4      68  CA2_A  SCONN288_ADR50001P003C01  I23
  U2     J48  DDR1_SA_CA2  SOCKET4677_AZIFS054P001C01  I169

M_B_CPU0_SA_CA<3>   @S9S_MB_2U_LIB.S9S_MB_2U(SCH_1):M_B_CPU0_SA_CA<3>
  J3     213  CA3_A  SCONN288_ADR50001P013C01  I11
  J4     213  CA3_A  SCONN288_ADR50001P003C01  I23
  U2     N48  DDR1_SA_CA3  SOCKET4677_AZIFS054P001C01  I169

M_B_CPU0_SA_CA<4>   @S9S_MB_2U_LIB.S9S_MB_2U(SCH_1):M_B_CPU0_SA_CA<4>
  J3      70  CA4_A  SCONN288_ADR50001P013C01  I11
  J4      70  CA4_A  SCONN288_ADR50001P003C01  I23
  U2     K47  DDR1_SA_CA4  SOCKET4677_AZIFS054P001C01  I169

M_B_CPU0_SA_CA<5>   @S9S_MB_2U_LIB.S9S_MB_2U(SCH_1):M_B_CPU0_SA_CA<5>
  J3     215  CA5_A  SCONN288_ADR50001P013C01  I11
  J4     215  CA5_A  SCONN288_ADR50001P003C01  I23
  U2     M47  DDR1_SA_CA5  SOCKET4677_AZIFS054P001C01  I169

M_B_CPU0_SA_CA<6>   @S9S_MB_2U_LIB.S9S_MB_2U(SCH_1):M_B_CPU0_SA_CA<6>
  J3      72  CA6_A  SCONN288_ADR50001P013C01  I11
  J4      72  CA6_A  SCONN288_ADR50001P003C01  I23
  U2     Y44  DDR1_SA_CA6  SOCKET4677_AZIFS054P001C01  I169

M_B_CPU0_SA_CB<0>   @S9S_MB_2U_LIB.S9S_MB_2U(SCH_1):M_B_CPU0_SA_CB<0>
  J3      51  CB_A0  SCONN288_ADR50001P013C01  I11
  J4      51  CB_A0  SCONN288_ADR50001P003C01  I23
  U2     K57  DDR1_SA_ECC0  SOCKET4677_AZIFS054P001C01  I169

M_B_CPU0_SA_CB<1>   @S9S_MB_2U_LIB.S9S_MB_2U(SCH_1):M_B_CPU0_SA_CB<1>
  J3      53  CB_A1  SCONN288_ADR50001P013C01  I11
  J4      53  CB_A1  SCONN288_ADR50001P003C01  I23
  U2     J56  DDR1_SA_ECC1  SOCKET4677_AZIFS054P001C01  I169

M_B_CPU0_SA_CB<2>   @S9S_MB_2U_LIB.S9S_MB_2U(SCH_1):M_B_CPU0_SA_CB<2>
  J3     196  CB_A2  SCONN288_ADR50001P013C01  I11
  J4     196  CB_A2  SCONN288_ADR50001P003C01  I23
  U2     M57  DDR1_SA_ECC2  SOCKET4677_AZIFS054P001C01  I169

M_B_CPU0_SA_CB<3>   @S9S_MB_2U_LIB.S9S_MB_2U(SCH_1):M_B_CPU0_SA_CB<3>
  J3     198  CB_A3  SCONN288_ADR50001P013C01  I11
  J4     198  CB_A3  SCONN288_ADR50001P003C01  I23
  U2     N56  DDR1_SA_ECC3  SOCKET4677_AZIFS054P001C01  I169

M_B_CPU0_SA_CB<4>   @S9S_MB_2U_LIB.S9S_MB_2U(SCH_1):M_B_CPU0_SA_CB<4>
  J3      58  CB_A4  SCONN288_ADR50001P013C01  I11
  J4      58  CB_A4  SCONN288_ADR50001P003C01  I23
  U2     J54  DDR1_SA_ECC4  SOCKET4677_AZIFS054P001C01  I169

M_B_CPU0_SA_CB<5>   @S9S_MB_2U_LIB.S9S_MB_2U(SCH_1):M_B_CPU0_SA_CB<5>
  J3      60  CB_A5  SCONN288_ADR50001P013C01  I11
  J4      60  CB_A5  SCONN288_ADR50001P003C01  I23
  U2     K53  DDR1_SA_ECC5  SOCKET4677_AZIFS054P001C01  I169

M_B_CPU0_SA_CB<6>   @S9S_MB_2U_LIB.S9S_MB_2U(SCH_1):M_B_CPU0_SA_CB<6>
  J3     203  CB_A6  SCONN288_ADR50001P013C01  I11
  J4     203  CB_A6  SCONN288_ADR50001P003C01  I23
  U2     N54  DDR1_SA_ECC6  SOCKET4677_AZIFS054P001C01  I169

M_B_CPU0_SA_CB<7>   @S9S_MB_2U_LIB.S9S_MB_2U(SCH_1):M_B_CPU0_SA_CB<7>
  J3     205  CB_A7  SCONN288_ADR50001P013C01  I11
  J4     205  CB_A7  SCONN288_ADR50001P003C01  I23
  U2     M53  DDR1_SA_ECC7  SOCKET4677_AZIFS054P001C01  I169

M_B_CPU0_SA_CS_N<0>   @S9S_MB_2U_LIB.S9S_MB_2U(SCH_1):M_B_CPU0_SA_CS_N<0>
  J3      64  CS0_N_A  SCONN288_ADR50001P013C01  I11
  U2     K51  DDR1_SA_CS0_N  SOCKET4677_AZIFS054P001C01  I169

M_B_CPU0_SA_CS_N<1>   @S9S_MB_2U_LIB.S9S_MB_2U(SCH_1):M_B_CPU0_SA_CS_N<1>
  J3     209  CS1_N_A  SCONN288_ADR50001P013C01  I11
  U2     J50  DDR1_SA_CS1_N  SOCKET4677_AZIFS054P001C01  I169

M_B_CPU0_SA_CS_N<2>   @S9S_MB_2U_LIB.S9S_MB_2U(SCH_1):M_B_CPU0_SA_CS_N<2>
  J4      64  CS0_N_A  SCONN288_ADR50001P003C01  I23
  U2     M51  DDR1_SA_CS2_N  SOCKET4677_AZIFS054P001C01  I169

M_B_CPU0_SA_CS_N<3>   @S9S_MB_2U_LIB.S9S_MB_2U(SCH_1):M_B_CPU0_SA_CS_N<3>
  J4     209  CS1_N_A  SCONN288_ADR50001P003C01  I23
  U2     N50  DDR1_SA_CS3_N  SOCKET4677_AZIFS054P001C01  I169

M_B_CPU0_SA_DQ<0>   @S9S_MB_2U_LIB.S9S_MB_2U(SCH_1):M_B_CPU0_SA_DQ<0>
  J3       7  DQ_A0  SCONN288_ADR50001P013C01  I11
  J4       7  DQ_A0  SCONN288_ADR50001P003C01  I23
  U2     K75  DDR1_SA_DQ0  SOCKET4677_AZIFS054P001C01  I169

M_B_CPU0_SA_DQ<1>   @S9S_MB_2U_LIB.S9S_MB_2U(SCH_1):M_B_CPU0_SA_DQ<1>
  J3       9  DQ_A1  SCONN288_ADR50001P013C01  I11
  J4       9  DQ_A1  SCONN288_ADR50001P003C01  I23
  U2     J74  DDR1_SA_DQ1  SOCKET4677_AZIFS054P001C01  I169

M_B_CPU0_SA_DQ<2>   @S9S_MB_2U_LIB.S9S_MB_2U(SCH_1):M_B_CPU0_SA_DQ<2>
  J3     152  DQ_A2  SCONN288_ADR50001P013C01  I11
  J4     152  DQ_A2  SCONN288_ADR50001P003C01  I23
  U2     M75  DDR1_SA_DQ2  SOCKET4677_AZIFS054P001C01  I169

M_B_CPU0_SA_DQ<3>   @S9S_MB_2U_LIB.S9S_MB_2U(SCH_1):M_B_CPU0_SA_DQ<3>
  J3     154  DQ_A3  SCONN288_ADR50001P013C01  I11
  J4     154  DQ_A3  SCONN288_ADR50001P003C01  I23
  U2     N74  DDR1_SA_DQ3  SOCKET4677_AZIFS054P001C01  I169

M_B_CPU0_SA_DQ<4>   @S9S_MB_2U_LIB.S9S_MB_2U(SCH_1):M_B_CPU0_SA_DQ<4>
  J3      14  DQ_A4  SCONN288_ADR50001P013C01  I11
  J4      14  DQ_A4  SCONN288_ADR50001P003C01  I23
  U2     J72  DDR1_SA_DQ4  SOCKET4677_AZIFS054P001C01  I169

M_B_CPU0_SA_DQ<5>   @S9S_MB_2U_LIB.S9S_MB_2U(SCH_1):M_B_CPU0_SA_DQ<5>
  J3      16  DQ_A5  SCONN288_ADR50001P013C01  I11
  J4      16  DQ_A5  SCONN288_ADR50001P003C01  I23
  U2     K71  DDR1_SA_DQ5  SOCKET4677_AZIFS054P001C01  I169

M_B_CPU0_SA_DQ<6>   @S9S_MB_2U_LIB.S9S_MB_2U(SCH_1):M_B_CPU0_SA_DQ<6>
  J3     159  DQ_A6  SCONN288_ADR50001P013C01  I11
  J4     159  DQ_A6  SCONN288_ADR50001P003C01  I23
  U2     N72  DDR1_SA_DQ6  SOCKET4677_AZIFS054P001C01  I169

M_B_CPU0_SA_DQ<7>   @S9S_MB_2U_LIB.S9S_MB_2U(SCH_1):M_B_CPU0_SA_DQ<7>
  J3     161  DQ_A7  SCONN288_ADR50001P013C01  I11
  J4     161  DQ_A7  SCONN288_ADR50001P003C01  I23
  U2     M71  DDR1_SA_DQ7  SOCKET4677_AZIFS054P001C01  I169

M_B_CPU0_SA_DQ<8>   @S9S_MB_2U_LIB.S9S_MB_2U(SCH_1):M_B_CPU0_SA_DQ<8>
  J3      18  DQ_A8  SCONN288_ADR50001P013C01  I11
  J4      18  DQ_A8  SCONN288_ADR50001P003C01  I23
  U2     U72  DDR1_SA_DQ8  SOCKET4677_AZIFS054P001C01  I169

M_B_CPU0_SA_DQ<9>   @S9S_MB_2U_LIB.S9S_MB_2U(SCH_1):M_B_CPU0_SA_DQ<9>
  J3      20  DQ_A9  SCONN288_ADR50001P013C01  I11
  J4      20  DQ_A9  SCONN288_ADR50001P003C01  I23
  U2     T71  DDR1_SA_DQ9  SOCKET4677_AZIFS054P001C01  I169

M_B_CPU0_SA_DQ<10>   @S9S_MB_2U_LIB.S9S_MB_2U(SCH_1):M_B_CPU0_SA_DQ<10>
  J3     163  DQ_A10  SCONN288_ADR50001P013C01  I11
  J4     163  DQ_A10  SCONN288_ADR50001P003C01  I23
  U2     W72  DDR1_SA_DQ10  SOCKET4677_AZIFS054P001C01  I169

M_B_CPU0_SA_DQ<11>   @S9S_MB_2U_LIB.S9S_MB_2U(SCH_1):M_B_CPU0_SA_DQ<11>
  J3     165  DQ_A11  SCONN288_ADR50001P013C01  I11
  J4     165  DQ_A11  SCONN288_ADR50001P003C01  I23
  U2     Y71  DDR1_SA_DQ11  SOCKET4677_AZIFS054P001C01  I169

M_B_CPU0_SA_DQ<12>   @S9S_MB_2U_LIB.S9S_MB_2U(SCH_1):M_B_CPU0_SA_DQ<12>
  J3      25  DQ_A12  SCONN288_ADR50001P013C01  I11
  J4      25  DQ_A12  SCONN288_ADR50001P003C01  I23
  U2     T69  DDR1_SA_DQ12  SOCKET4677_AZIFS054P001C01  I169

M_B_CPU0_SA_DQ<13>   @S9S_MB_2U_LIB.S9S_MB_2U(SCH_1):M_B_CPU0_SA_DQ<13>
  J3      27  DQ_A13  SCONN288_ADR50001P013C01  I11
  J4      27  DQ_A13  SCONN288_ADR50001P003C01  I23
  U2     U68  DDR1_SA_DQ13  SOCKET4677_AZIFS054P001C01  I169

M_B_CPU0_SA_DQ<14>   @S9S_MB_2U_LIB.S9S_MB_2U(SCH_1):M_B_CPU0_SA_DQ<14>
  J3     170  DQ_A14  SCONN288_ADR50001P013C01  I11
  J4     170  DQ_A14  SCONN288_ADR50001P003C01  I23
  U2     Y69  DDR1_SA_DQ14  SOCKET4677_AZIFS054P001C01  I169

M_B_CPU0_SA_DQ<15>   @S9S_MB_2U_LIB.S9S_MB_2U(SCH_1):M_B_CPU0_SA_DQ<15>
  J3     172  DQ_A15  SCONN288_ADR50001P013C01  I11
  J4     172  DQ_A15  SCONN288_ADR50001P003C01  I23
  U2     W68  DDR1_SA_DQ15  SOCKET4677_AZIFS054P001C01  I169

M_B_CPU0_SA_DQ<16>   @S9S_MB_2U_LIB.S9S_MB_2U(SCH_1):M_B_CPU0_SA_DQ<16>
  J3      29  DQ_A16  SCONN288_ADR50001P013C01  I11
  J4      29  DQ_A16  SCONN288_ADR50001P003C01  I23
  U2     K63  DDR1_SA_DQ16  SOCKET4677_AZIFS054P001C01  I169

M_B_CPU0_SA_DQ<17>   @S9S_MB_2U_LIB.S9S_MB_2U(SCH_1):M_B_CPU0_SA_DQ<17>
  J3      31  DQ_A17  SCONN288_ADR50001P013C01  I11
  J4      31  DQ_A17  SCONN288_ADR50001P003C01  I23
  U2     J62  DDR1_SA_DQ17  SOCKET4677_AZIFS054P001C01  I169

M_B_CPU0_SA_DQ<18>   @S9S_MB_2U_LIB.S9S_MB_2U(SCH_1):M_B_CPU0_SA_DQ<18>
  J3     174  DQ_A18  SCONN288_ADR50001P013C01  I11
  J4     174  DQ_A18  SCONN288_ADR50001P003C01  I23
  U2     M63  DDR1_SA_DQ18  SOCKET4677_AZIFS054P001C01  I169

M_B_CPU0_SA_DQ<19>   @S9S_MB_2U_LIB.S9S_MB_2U(SCH_1):M_B_CPU0_SA_DQ<19>
  J3     176  DQ_A19  SCONN288_ADR50001P013C01  I11
  J4     176  DQ_A19  SCONN288_ADR50001P003C01  I23
  U2     N62  DDR1_SA_DQ19  SOCKET4677_AZIFS054P001C01  I169

M_B_CPU0_SA_DQ<20>   @S9S_MB_2U_LIB.S9S_MB_2U(SCH_1):M_B_CPU0_SA_DQ<20>
  J3      36  DQ_A20  SCONN288_ADR50001P013C01  I11
  J4      36  DQ_A20  SCONN288_ADR50001P003C01  I23
  U2     J60  DDR1_SA_DQ20  SOCKET4677_AZIFS054P001C01  I169

M_B_CPU0_SA_DQ<21>   @S9S_MB_2U_LIB.S9S_MB_2U(SCH_1):M_B_CPU0_SA_DQ<21>
  J3      38  DQ_A21  SCONN288_ADR50001P013C01  I11
  J4      38  DQ_A21  SCONN288_ADR50001P003C01  I23
  U2     K59  DDR1_SA_DQ21  SOCKET4677_AZIFS054P001C01  I169

M_B_CPU0_SA_DQ<22>   @S9S_MB_2U_LIB.S9S_MB_2U(SCH_1):M_B_CPU0_SA_DQ<22>
  J3     181  DQ_A22  SCONN288_ADR50001P013C01  I11
  J4     181  DQ_A22  SCONN288_ADR50001P003C01  I23
  U2     N60  DDR1_SA_DQ22  SOCKET4677_AZIFS054P001C01  I169

M_B_CPU0_SA_DQ<23>   @S9S_MB_2U_LIB.S9S_MB_2U(SCH_1):M_B_CPU0_SA_DQ<23>
  J3     183  DQ_A23  SCONN288_ADR50001P013C01  I11
  J4     183  DQ_A23  SCONN288_ADR50001P003C01  I23
  U2     M59  DDR1_SA_DQ23  SOCKET4677_AZIFS054P001C01  I169

M_B_CPU0_SA_DQ<24>   @S9S_MB_2U_LIB.S9S_MB_2U(SCH_1):M_B_CPU0_SA_DQ<24>
  J3      40  DQ_A24  SCONN288_ADR50001P013C01  I11
  J4      40  DQ_A24  SCONN288_ADR50001P003C01  I23
  U2     U60  DDR1_SA_DQ24  SOCKET4677_AZIFS054P001C01  I169

M_B_CPU0_SA_DQ<25>   @S9S_MB_2U_LIB.S9S_MB_2U(SCH_1):M_B_CPU0_SA_DQ<25>
  J3      42  DQ_A25  SCONN288_ADR50001P013C01  I11
  J4      42  DQ_A25  SCONN288_ADR50001P003C01  I23
  U2     T59  DDR1_SA_DQ25  SOCKET4677_AZIFS054P001C01  I169

M_B_CPU0_SA_DQ<26>   @S9S_MB_2U_LIB.S9S_MB_2U(SCH_1):M_B_CPU0_SA_DQ<26>
  J3     185  DQ_A26  SCONN288_ADR50001P013C01  I11
  J4     185  DQ_A26  SCONN288_ADR50001P003C01  I23
  U2     W60  DDR1_SA_DQ26  SOCKET4677_AZIFS054P001C01  I169

M_B_CPU0_SA_DQ<27>   @S9S_MB_2U_LIB.S9S_MB_2U(SCH_1):M_B_CPU0_SA_DQ<27>
  J3     187  DQ_A27  SCONN288_ADR50001P013C01  I11
  J4     187  DQ_A27  SCONN288_ADR50001P003C01  I23
  U2     Y59  DDR1_SA_DQ27  SOCKET4677_AZIFS054P001C01  I169

M_B_CPU0_SA_DQ<28>   @S9S_MB_2U_LIB.S9S_MB_2U(SCH_1):M_B_CPU0_SA_DQ<28>
  J3      47  DQ_A28  SCONN288_ADR50001P013C01  I11
  J4      47  DQ_A28  SCONN288_ADR50001P003C01  I23
  U2     T57  DDR1_SA_DQ28  SOCKET4677_AZIFS054P001C01  I169

M_B_CPU0_SA_DQ<29>   @S9S_MB_2U_LIB.S9S_MB_2U(SCH_1):M_B_CPU0_SA_DQ<29>
  J3      49  DQ_A29  SCONN288_ADR50001P013C01  I11
  J4      49  DQ_A29  SCONN288_ADR50001P003C01  I23
  U2     U56  DDR1_SA_DQ29  SOCKET4677_AZIFS054P001C01  I169

M_B_CPU0_SA_DQ<30>   @S9S_MB_2U_LIB.S9S_MB_2U(SCH_1):M_B_CPU0_SA_DQ<30>
  J3     192  DQ_A30  SCONN288_ADR50001P013C01  I11
  J4     192  DQ_A30  SCONN288_ADR50001P003C01  I23
  U2     Y57  DDR1_SA_DQ30  SOCKET4677_AZIFS054P001C01  I169

M_B_CPU0_SA_DQ<31>   @S9S_MB_2U_LIB.S9S_MB_2U(SCH_1):M_B_CPU0_SA_DQ<31>
  J3     194  DQ_A31  SCONN288_ADR50001P013C01  I11
  J4     194  DQ_A31  SCONN288_ADR50001P003C01  I23
  U2     W56  DDR1_SA_DQ31  SOCKET4677_AZIFS054P001C01  I169

M_B_CPU0_SA_DQS_DN<0>   @S9S_MB_2U_LIB.S9S_MB_2U(SCH_1):M_B_CPU0_SA_DQS_DN<0>
  J3      12  DQS0_A_N  SCONN288_ADR50001P013C01  I125
  J4      12  DQS0_A_N  SCONN288_ADR50001P003C01  I124
  U2     H73  DDR1_SA_DQS_DN0  SOCKET4677_AZIFS054P001C01  I169

M_B_CPU0_SA_DQS_DN<1>   @S9S_MB_2U_LIB.S9S_MB_2U(SCH_1):M_B_CPU0_SA_DQS_DN<1>
  J3      23  DQS1_A_N  SCONN288_ADR50001P013C01  I125
  J4      23  DQS1_A_N  SCONN288_ADR50001P003C01  I124
  U2     R70  DDR1_SA_DQS_DN1  SOCKET4677_AZIFS054P001C01  I169

M_B_CPU0_SA_DQS_DN<2>   @S9S_MB_2U_LIB.S9S_MB_2U(SCH_1):M_B_CPU0_SA_DQS_DN<2>
  J3      34  DQS2_A_N  SCONN288_ADR50001P013C01  I125
  J4      34  DQS2_A_N  SCONN288_ADR50001P003C01  I124
  U2     H61  DDR1_SA_DQS_DN2  SOCKET4677_AZIFS054P001C01  I169

M_B_CPU0_SA_DQS_DN<3>   @S9S_MB_2U_LIB.S9S_MB_2U(SCH_1):M_B_CPU0_SA_DQS_DN<3>
  J3      45  DQS3_A_N  SCONN288_ADR50001P013C01  I125
  J4      45  DQS3_A_N  SCONN288_ADR50001P003C01  I124
  U2     R58  DDR1_SA_DQS_DN3  SOCKET4677_AZIFS054P001C01  I169

M_B_CPU0_SA_DQS_DN<4>   @S9S_MB_2U_LIB.S9S_MB_2U(SCH_1):M_B_CPU0_SA_DQS_DN<4>
  J3      56  DQS4_A_N  SCONN288_ADR50001P013C01  I125
  J4      56  DQS4_A_N  SCONN288_ADR50001P003C01  I124
  U2     H55  DDR1_SA_DQS_DN4  SOCKET4677_AZIFS054P001C01  I169

M_B_CPU0_SA_DQS_DN<5>   @S9S_MB_2U_LIB.S9S_MB_2U(SCH_1):M_B_CPU0_SA_DQS_DN<5>
  J3     156  DQS5_A_N  SCONN288_ADR50001P013C01  I125
  J4     156  DQS5_A_N  SCONN288_ADR50001P003C01  I124
  U2     M73  DDR1_SA_DQS_DN5  SOCKET4677_AZIFS054P001C01  I169

M_B_CPU0_SA_DQS_DN<6>   @S9S_MB_2U_LIB.S9S_MB_2U(SCH_1):M_B_CPU0_SA_DQS_DN<6>
  J3     167  DQS6_A_N  SCONN288_ADR50001P013C01  I125
  J4     167  DQS6_A_N  SCONN288_ADR50001P003C01  I124
  U2     AA70  DDR1_SA_DQS_DN6  SOCKET4677_AZIFS054P001C01  I169

M_B_CPU0_SA_DQS_DN<7>   @S9S_MB_2U_LIB.S9S_MB_2U(SCH_1):M_B_CPU0_SA_DQS_DN<7>
  J3     178  DQS7_A_N  SCONN288_ADR50001P013C01  I125
  J4     178  DQS7_A_N  SCONN288_ADR50001P003C01  I124
  U2     M61  DDR1_SA_DQS_DN7  SOCKET4677_AZIFS054P001C01  I169

M_B_CPU0_SA_DQS_DN<8>   @S9S_MB_2U_LIB.S9S_MB_2U(SCH_1):M_B_CPU0_SA_DQS_DN<8>
  J3     189  DQS8_A_N  SCONN288_ADR50001P013C01  I125
  J4     189  DQS8_A_N  SCONN288_ADR50001P003C01  I124
  U2     AA58  DDR1_SA_DQS_DN8  SOCKET4677_AZIFS054P001C01  I169

M_B_CPU0_SA_DQS_DN<9>   @S9S_MB_2U_LIB.S9S_MB_2U(SCH_1):M_B_CPU0_SA_DQS_DN<9>
  J3     200  DQS9_A_N  SCONN288_ADR50001P013C01  I125
  J4     200  DQS9_A_N  SCONN288_ADR50001P003C01  I124
  U2     M55  DDR1_SA_DQS_DN9  SOCKET4677_AZIFS054P001C01  I169

M_B_CPU0_SA_DQS_DP<0>   @S9S_MB_2U_LIB.S9S_MB_2U(SCH_1):M_B_CPU0_SA_DQS_DP<0>
  J3      11  DQS0_A_P  SCONN288_ADR50001P013C01  I125
  J4      11  DQS0_A_P  SCONN288_ADR50001P003C01  I124
  U2     K73  DDR1_SA_DQS_DP0  SOCKET4677_AZIFS054P001C01  I169

M_B_CPU0_SA_DQS_DP<1>   @S9S_MB_2U_LIB.S9S_MB_2U(SCH_1):M_B_CPU0_SA_DQS_DP<1>
  J3      22  DQS1_A_P  SCONN288_ADR50001P013C01  I125
  J4      22  DQS1_A_P  SCONN288_ADR50001P003C01  I124
  U2     U70  DDR1_SA_DQS_DP1  SOCKET4677_AZIFS054P001C01  I169

M_B_CPU0_SA_DQS_DP<2>   @S9S_MB_2U_LIB.S9S_MB_2U(SCH_1):M_B_CPU0_SA_DQS_DP<2>
  J3      33  DQS2_A_P  SCONN288_ADR50001P013C01  I125
  J4      33  DQS2_A_P  SCONN288_ADR50001P003C01  I124
  U2     K61  DDR1_SA_DQS_DP2  SOCKET4677_AZIFS054P001C01  I169

M_B_CPU0_SA_DQS_DP<3>   @S9S_MB_2U_LIB.S9S_MB_2U(SCH_1):M_B_CPU0_SA_DQS_DP<3>
  J3      44  DQS3_A_P  SCONN288_ADR50001P013C01  I125
  J4      44  DQS3_A_P  SCONN288_ADR50001P003C01  I124
  U2     U58  DDR1_SA_DQS_DP3  SOCKET4677_AZIFS054P001C01  I169

M_B_CPU0_SA_DQS_DP<4>   @S9S_MB_2U_LIB.S9S_MB_2U(SCH_1):M_B_CPU0_SA_DQS_DP<4>
  J3      55  DQS4_A_P  SCONN288_ADR50001P013C01  I125
  J4      55  DQS4_A_P  SCONN288_ADR50001P003C01  I124
  U2     K55  DDR1_SA_DQS_DP4  SOCKET4677_AZIFS054P001C01  I169

M_B_CPU0_SA_DQS_DP<5>   @S9S_MB_2U_LIB.S9S_MB_2U(SCH_1):M_B_CPU0_SA_DQS_DP<5>
  J3     157  DQS5_A_P  SCONN288_ADR50001P013C01  I125
  J4     157  DQS5_A_P  SCONN288_ADR50001P003C01  I124
  U2     P73  DDR1_SA_DQS_DP5  SOCKET4677_AZIFS054P001C01  I169

M_B_CPU0_SA_DQS_DP<6>   @S9S_MB_2U_LIB.S9S_MB_2U(SCH_1):M_B_CPU0_SA_DQS_DP<6>
  J3     168  DQS6_A_P  SCONN288_ADR50001P013C01  I125
  J4     168  DQS6_A_P  SCONN288_ADR50001P003C01  I124
  U2     W70  DDR1_SA_DQS_DP6  SOCKET4677_AZIFS054P001C01  I169

M_B_CPU0_SA_DQS_DP<7>   @S9S_MB_2U_LIB.S9S_MB_2U(SCH_1):M_B_CPU0_SA_DQS_DP<7>
  J3     179  DQS7_A_P  SCONN288_ADR50001P013C01  I125
  J4     179  DQS7_A_P  SCONN288_ADR50001P003C01  I124
  U2     P61  DDR1_SA_DQS_DP7  SOCKET4677_AZIFS054P001C01  I169

M_B_CPU0_SA_DQS_DP<8>   @S9S_MB_2U_LIB.S9S_MB_2U(SCH_1):M_B_CPU0_SA_DQS_DP<8>
  J3     190  DQS8_A_P  SCONN288_ADR50001P013C01  I125
  J4     190  DQS8_A_P  SCONN288_ADR50001P003C01  I124
  U2     W58  DDR1_SA_DQS_DP8  SOCKET4677_AZIFS054P001C01  I169

M_B_CPU0_SA_DQS_DP<9>   @S9S_MB_2U_LIB.S9S_MB_2U(SCH_1):M_B_CPU0_SA_DQS_DP<9>
  J3     201  DQS9_A_P  SCONN288_ADR50001P013C01  I125
  J4     201  DQS9_A_P  SCONN288_ADR50001P003C01  I124
  U2     P55  DDR1_SA_DQS_DP9  SOCKET4677_AZIFS054P001C01  I169

M_B_CPU0_SA_PAR   @S9S_MB_2U_LIB.S9S_MB_2U(SCH_1):M_B_CPU0_SA_PAR
  J3      74  PAR_A  SCONN288_ADR50001P013C01  I11
  J4      74  PAR_A  SCONN288_ADR50001P003C01  I23
  U2     W43  DDR1_SA_PAR  SOCKET4677_AZIFS054P001C01  I169

M_B_CPU0_SA_RSP<0>   @S9S_MB_2U_LIB.S9S_MB_2U(SCH_1):M_B_CPU0_SA_RSP<0>
  J3      86  LBD||RSP_N_A  SCONN288_ADR50001P013C01  I11
  U2     AL48  DDR1_A_RSP0  SOCKET4677_AZIFS054P001C01  I169

M_B_CPU0_SA_RSP<1>   @S9S_MB_2U_LIB.S9S_MB_2U(SCH_1):M_B_CPU0_SA_RSP<1>
  J4      86  LBD||RSP_N_A  SCONN288_ADR50001P003C01  I23
  U2     AK47  DDR1_A_RSP1  SOCKET4677_AZIFS054P001C01  I169

M_B_CPU0_SB_CA<0>   @S9S_MB_2U_LIB.S9S_MB_2U(SCH_1):M_B_CPU0_SB_CA<0>
  J3      76  CA0_B  SCONN288_ADR50001P013C01  I11
  J4      76  CA0_B  SCONN288_ADR50001P003C01  I23
  U2     T44  DDR1_SB_CA0  SOCKET4677_AZIFS054P001C01  I169

M_B_CPU0_SB_CA<1>   @S9S_MB_2U_LIB.S9S_MB_2U(SCH_1):M_B_CPU0_SB_CA<1>
  J3     221  CA1_B  SCONN288_ADR50001P013C01  I11
  J4     221  CA1_B  SCONN288_ADR50001P003C01  I23
  U2     U43  DDR1_SB_CA1  SOCKET4677_AZIFS054P001C01  I169

M_B_CPU0_SB_CA<2>   @S9S_MB_2U_LIB.S9S_MB_2U(SCH_1):M_B_CPU0_SB_CA<2>
  J3      78  CA2_B  SCONN288_ADR50001P013C01  I11
  J4      78  CA2_B  SCONN288_ADR50001P003C01  I23
  U2     K44  DDR1_SB_CA2  SOCKET4677_AZIFS054P001C01  I169

M_B_CPU0_SB_CA<3>   @S9S_MB_2U_LIB.S9S_MB_2U(SCH_1):M_B_CPU0_SB_CA<3>
  J3     223  CA3_B  SCONN288_ADR50001P013C01  I11
  J4     223  CA3_B  SCONN288_ADR50001P003C01  I23
  U2     M44  DDR1_SB_CA3  SOCKET4677_AZIFS054P001C01  I169

M_B_CPU0_SB_CA<4>   @S9S_MB_2U_LIB.S9S_MB_2U(SCH_1):M_B_CPU0_SB_CA<4>
  J3      80  CA4_B  SCONN288_ADR50001P013C01  I11
  J4      80  CA4_B  SCONN288_ADR50001P003C01  I23
  U2     J43  DDR1_SB_CA4  SOCKET4677_AZIFS054P001C01  I169

M_B_CPU0_SB_CA<5>   @S9S_MB_2U_LIB.S9S_MB_2U(SCH_1):M_B_CPU0_SB_CA<5>
  J3     225  CA5_B  SCONN288_ADR50001P013C01  I11
  J4     225  CA5_B  SCONN288_ADR50001P003C01  I23
  U2     N43  DDR1_SB_CA5  SOCKET4677_AZIFS054P001C01  I169

M_B_CPU0_SB_CA<6>   @S9S_MB_2U_LIB.S9S_MB_2U(SCH_1):M_B_CPU0_SB_CA<6>
  J3      82  CA6_B  SCONN288_ADR50001P013C01  I11
  J4      82  CA6_B  SCONN288_ADR50001P003C01  I23
  U2     H42  DDR1_SB_CA6  SOCKET4677_AZIFS054P001C01  I169

M_B_CPU0_SB_CB<0>   @S9S_MB_2U_LIB.S9S_MB_2U(SCH_1):M_B_CPU0_SB_CB<0>
  J3      96  CB_B0  SCONN288_ADR50001P013C01  I11
  J4      96  CB_B0  SCONN288_ADR50001P003C01  I23
  U2     J35  DDR1_SB_ECC0  SOCKET4677_AZIFS054P001C01  I169

M_B_CPU0_SB_CB<1>   @S9S_MB_2U_LIB.S9S_MB_2U(SCH_1):M_B_CPU0_SB_CB<1>
  J3      98  CB_B1  SCONN288_ADR50001P013C01  I11
  J4      98  CB_B1  SCONN288_ADR50001P003C01  I23
  U2     K34  DDR1_SB_ECC1  SOCKET4677_AZIFS054P001C01  I169

M_B_CPU0_SB_CB<2>   @S9S_MB_2U_LIB.S9S_MB_2U(SCH_1):M_B_CPU0_SB_CB<2>
  J3     241  CB_B2  SCONN288_ADR50001P013C01  I11
  J4     241  CB_B2  SCONN288_ADR50001P003C01  I23
  U2     N35  DDR1_SB_ECC2  SOCKET4677_AZIFS054P001C01  I169

M_B_CPU0_SB_CB<3>   @S9S_MB_2U_LIB.S9S_MB_2U(SCH_1):M_B_CPU0_SB_CB<3>
  J3     243  CB_B3  SCONN288_ADR50001P013C01  I11
  J4     243  CB_B3  SCONN288_ADR50001P003C01  I23
  U2     M34  DDR1_SB_ECC3  SOCKET4677_AZIFS054P001C01  I169

M_B_CPU0_SB_CB<4>   @S9S_MB_2U_LIB.S9S_MB_2U(SCH_1):M_B_CPU0_SB_CB<4>
  J3      89  CB_B4  SCONN288_ADR50001P013C01  I11
  J4      89  CB_B4  SCONN288_ADR50001P003C01  I23
  U2     K38  DDR1_SB_ECC4  SOCKET4677_AZIFS054P001C01  I169

M_B_CPU0_SB_CB<5>   @S9S_MB_2U_LIB.S9S_MB_2U(SCH_1):M_B_CPU0_SB_CB<5>
  J3      91  CB_B5  SCONN288_ADR50001P013C01  I11
  J4      91  CB_B5  SCONN288_ADR50001P003C01  I23
  U2     J37  DDR1_SB_ECC5  SOCKET4677_AZIFS054P001C01  I169

M_B_CPU0_SB_CB<6>   @S9S_MB_2U_LIB.S9S_MB_2U(SCH_1):M_B_CPU0_SB_CB<6>
  J3     234  CB_B6  SCONN288_ADR50001P013C01  I11
  J4     234  CB_B6  SCONN288_ADR50001P003C01  I23
  U2     M38  DDR1_SB_ECC6  SOCKET4677_AZIFS054P001C01  I169

M_B_CPU0_SB_CB<7>   @S9S_MB_2U_LIB.S9S_MB_2U(SCH_1):M_B_CPU0_SB_CB<7>
  J3     236  CB_B7  SCONN288_ADR50001P013C01  I11
  J4     236  CB_B7  SCONN288_ADR50001P003C01  I23
  U2     N37  DDR1_SB_ECC7  SOCKET4677_AZIFS054P001C01  I169

M_B_CPU0_SB_CS_N<0>   @S9S_MB_2U_LIB.S9S_MB_2U(SCH_1):M_B_CPU0_SB_CS_N<0>
  J3      84  CS0_N_B  SCONN288_ADR50001P013C01  I11
  U2     J41  DDR1_SB_CS0_N  SOCKET4677_AZIFS054P001C01  I169

M_B_CPU0_SB_CS_N<1>   @S9S_MB_2U_LIB.S9S_MB_2U(SCH_1):M_B_CPU0_SB_CS_N<1>
  J3     229  CS1_N_B  SCONN288_ADR50001P013C01  I11
  U2     K40  DDR1_SB_CS1_N  SOCKET4677_AZIFS054P001C01  I169

M_B_CPU0_SB_CS_N<2>   @S9S_MB_2U_LIB.S9S_MB_2U(SCH_1):M_B_CPU0_SB_CS_N<2>
  J4      84  CS0_N_B  SCONN288_ADR50001P003C01  I23
  U2     N41  DDR1_SB_CS2_N  SOCKET4677_AZIFS054P001C01  I169

M_B_CPU0_SB_CS_N<3>   @S9S_MB_2U_LIB.S9S_MB_2U(SCH_1):M_B_CPU0_SB_CS_N<3>
  J4     229  CS1_N_B  SCONN288_ADR50001P003C01  I23
  U2     M40  DDR1_SB_CS3_N  SOCKET4677_AZIFS054P001C01  I169

M_B_CPU0_SB_DQ<0>   @S9S_MB_2U_LIB.S9S_MB_2U(SCH_1):M_B_CPU0_SB_DQ<0>
  J3     100  DQ_B0  SCONN288_ADR50001P013C01  I11
  J4     100  DQ_B0  SCONN288_ADR50001P003C01  I23
  U2     U29  DDR1_SB_DQ0  SOCKET4677_AZIFS054P001C01  I169

M_B_CPU0_SB_DQ<1>   @S9S_MB_2U_LIB.S9S_MB_2U(SCH_1):M_B_CPU0_SB_DQ<1>
  J3     102  DQ_B1  SCONN288_ADR50001P013C01  I11
  J4     102  DQ_B1  SCONN288_ADR50001P003C01  I23
  U2     T28  DDR1_SB_DQ1  SOCKET4677_AZIFS054P001C01  I169

M_B_CPU0_SB_DQ<2>   @S9S_MB_2U_LIB.S9S_MB_2U(SCH_1):M_B_CPU0_SB_DQ<2>
  J3     245  DQ_B2  SCONN288_ADR50001P013C01  I11
  J4     245  DQ_B2  SCONN288_ADR50001P003C01  I23
  U2     W29  DDR1_SB_DQ2  SOCKET4677_AZIFS054P001C01  I169

M_B_CPU0_SB_DQ<3>   @S9S_MB_2U_LIB.S9S_MB_2U(SCH_1):M_B_CPU0_SB_DQ<3>
  J3     247  DQ_B3  SCONN288_ADR50001P013C01  I11
  J4     247  DQ_B3  SCONN288_ADR50001P003C01  I23
  U2     Y28  DDR1_SB_DQ3  SOCKET4677_AZIFS054P001C01  I169

M_B_CPU0_SB_DQ<4>   @S9S_MB_2U_LIB.S9S_MB_2U(SCH_1):M_B_CPU0_SB_DQ<4>
  J3     107  DQ_B4  SCONN288_ADR50001P013C01  I11
  J4     107  DQ_B4  SCONN288_ADR50001P003C01  I23
  U2     T26  DDR1_SB_DQ4  SOCKET4677_AZIFS054P001C01  I169

M_B_CPU0_SB_DQ<5>   @S9S_MB_2U_LIB.S9S_MB_2U(SCH_1):M_B_CPU0_SB_DQ<5>
  J3     109  DQ_B5  SCONN288_ADR50001P013C01  I11
  J4     109  DQ_B5  SCONN288_ADR50001P003C01  I23
  U2     U25  DDR1_SB_DQ5  SOCKET4677_AZIFS054P001C01  I169

M_B_CPU0_SB_DQ<6>   @S9S_MB_2U_LIB.S9S_MB_2U(SCH_1):M_B_CPU0_SB_DQ<6>
  J3     252  DQ_B6  SCONN288_ADR50001P013C01  I11
  J4     252  DQ_B6  SCONN288_ADR50001P003C01  I23
  U2     Y26  DDR1_SB_DQ6  SOCKET4677_AZIFS054P001C01  I169

M_B_CPU0_SB_DQ<7>   @S9S_MB_2U_LIB.S9S_MB_2U(SCH_1):M_B_CPU0_SB_DQ<7>
  J3     254  DQ_B7  SCONN288_ADR50001P013C01  I11
  J4     254  DQ_B7  SCONN288_ADR50001P003C01  I23
  U2     W25  DDR1_SB_DQ7  SOCKET4677_AZIFS054P001C01  I169

M_B_CPU0_SB_DQ<8>   @S9S_MB_2U_LIB.S9S_MB_2U(SCH_1):M_B_CPU0_SB_DQ<8>
  J3     111  DQ_B8  SCONN288_ADR50001P013C01  I11
  J4     111  DQ_B8  SCONN288_ADR50001P003C01  I23
  U2     K26  DDR1_SB_DQ8  SOCKET4677_AZIFS054P001C01  I169

M_B_CPU0_SB_DQ<9>   @S9S_MB_2U_LIB.S9S_MB_2U(SCH_1):M_B_CPU0_SB_DQ<9>
  J3     113  DQ_B9  SCONN288_ADR50001P013C01  I11
  J4     113  DQ_B9  SCONN288_ADR50001P003C01  I23
  U2     J25  DDR1_SB_DQ9  SOCKET4677_AZIFS054P001C01  I169

M_B_CPU0_SB_DQ<10>   @S9S_MB_2U_LIB.S9S_MB_2U(SCH_1):M_B_CPU0_SB_DQ<10>
  J3     256  DQ_B10  SCONN288_ADR50001P013C01  I11
  J4     256  DQ_B10  SCONN288_ADR50001P003C01  I23
  U2     M26  DDR1_SB_DQ10  SOCKET4677_AZIFS054P001C01  I169

M_B_CPU0_SB_DQ<11>   @S9S_MB_2U_LIB.S9S_MB_2U(SCH_1):M_B_CPU0_SB_DQ<11>
  J3     258  DQ_B11  SCONN288_ADR50001P013C01  I11
  J4     258  DQ_B11  SCONN288_ADR50001P003C01  I23
  U2     N25  DDR1_SB_DQ11  SOCKET4677_AZIFS054P001C01  I169

M_B_CPU0_SB_DQ<12>   @S9S_MB_2U_LIB.S9S_MB_2U(SCH_1):M_B_CPU0_SB_DQ<12>
  J3     118  DQ_B12  SCONN288_ADR50001P013C01  I11
  J4     118  DQ_B12  SCONN288_ADR50001P003C01  I23
  U2     J23  DDR1_SB_DQ12  SOCKET4677_AZIFS054P001C01  I169

M_B_CPU0_SB_DQ<13>   @S9S_MB_2U_LIB.S9S_MB_2U(SCH_1):M_B_CPU0_SB_DQ<13>
  J3     120  DQ_B13  SCONN288_ADR50001P013C01  I11
  J4     120  DQ_B13  SCONN288_ADR50001P003C01  I23
  U2     K22  DDR1_SB_DQ13  SOCKET4677_AZIFS054P001C01  I169

M_B_CPU0_SB_DQ<14>   @S9S_MB_2U_LIB.S9S_MB_2U(SCH_1):M_B_CPU0_SB_DQ<14>
  J3     263  DQ_B14  SCONN288_ADR50001P013C01  I11
  J4     263  DQ_B14  SCONN288_ADR50001P003C01  I23
  U2     N23  DDR1_SB_DQ14  SOCKET4677_AZIFS054P001C01  I169

M_B_CPU0_SB_DQ<15>   @S9S_MB_2U_LIB.S9S_MB_2U(SCH_1):M_B_CPU0_SB_DQ<15>
  J3     265  DQ_B15  SCONN288_ADR50001P013C01  I11
  J4     265  DQ_B15  SCONN288_ADR50001P003C01  I23
  U2     M22  DDR1_SB_DQ15  SOCKET4677_AZIFS054P001C01  I169

M_B_CPU0_SB_DQ<16>   @S9S_MB_2U_LIB.S9S_MB_2U(SCH_1):M_B_CPU0_SB_DQ<16>
  J3     122  DQ_B16  SCONN288_ADR50001P013C01  I11
  J4     122  DQ_B16  SCONN288_ADR50001P003C01  I23
  U2     K20  DDR1_SB_DQ16  SOCKET4677_AZIFS054P001C01  I169

M_B_CPU0_SB_DQ<17>   @S9S_MB_2U_LIB.S9S_MB_2U(SCH_1):M_B_CPU0_SB_DQ<17>
  J3     124  DQ_B17  SCONN288_ADR50001P013C01  I11
  J4     124  DQ_B17  SCONN288_ADR50001P003C01  I23
  U2     J19  DDR1_SB_DQ17  SOCKET4677_AZIFS054P001C01  I169

M_B_CPU0_SB_DQ<18>   @S9S_MB_2U_LIB.S9S_MB_2U(SCH_1):M_B_CPU0_SB_DQ<18>
  J3     267  DQ_B18  SCONN288_ADR50001P013C01  I11
  J4     267  DQ_B18  SCONN288_ADR50001P003C01  I23
  U2     M20  DDR1_SB_DQ18  SOCKET4677_AZIFS054P001C01  I169

M_B_CPU0_SB_DQ<19>   @S9S_MB_2U_LIB.S9S_MB_2U(SCH_1):M_B_CPU0_SB_DQ<19>
  J3     269  DQ_B19  SCONN288_ADR50001P013C01  I11
  J4     269  DQ_B19  SCONN288_ADR50001P003C01  I23
  U2     N19  DDR1_SB_DQ19  SOCKET4677_AZIFS054P001C01  I169

M_B_CPU0_SB_DQ<20>   @S9S_MB_2U_LIB.S9S_MB_2U(SCH_1):M_B_CPU0_SB_DQ<20>
  J3     129  DQ_B20  SCONN288_ADR50001P013C01  I11
  J4     129  DQ_B20  SCONN288_ADR50001P003C01  I23
  U2     J17  DDR1_SB_DQ20  SOCKET4677_AZIFS054P001C01  I169

M_B_CPU0_SB_DQ<21>   @S9S_MB_2U_LIB.S9S_MB_2U(SCH_1):M_B_CPU0_SB_DQ<21>
  J3     131  DQ_B21  SCONN288_ADR50001P013C01  I11
  J4     131  DQ_B21  SCONN288_ADR50001P003C01  I23
  U2     K16  DDR1_SB_DQ21  SOCKET4677_AZIFS054P001C01  I169

M_B_CPU0_SB_DQ<22>   @S9S_MB_2U_LIB.S9S_MB_2U(SCH_1):M_B_CPU0_SB_DQ<22>
  J3     274  DQ_B22  SCONN288_ADR50001P013C01  I11
  J4     274  DQ_B22  SCONN288_ADR50001P003C01  I23
  U2     N17  DDR1_SB_DQ22  SOCKET4677_AZIFS054P001C01  I169

M_B_CPU0_SB_DQ<23>   @S9S_MB_2U_LIB.S9S_MB_2U(SCH_1):M_B_CPU0_SB_DQ<23>
  J3     276  DQ_B23  SCONN288_ADR50001P013C01  I11
  J4     276  DQ_B23  SCONN288_ADR50001P003C01  I23
  U2     M16  DDR1_SB_DQ23  SOCKET4677_AZIFS054P001C01  I169

M_B_CPU0_SB_DQ<24>   @S9S_MB_2U_LIB.S9S_MB_2U(SCH_1):M_B_CPU0_SB_DQ<24>
  J3     133  DQ_B24  SCONN288_ADR50001P013C01  I11
  J4     133  DQ_B24  SCONN288_ADR50001P003C01  I23
  U2     C17  DDR1_SB_DQ24  SOCKET4677_AZIFS054P001C01  I169

M_B_CPU0_SB_DQ<25>   @S9S_MB_2U_LIB.S9S_MB_2U(SCH_1):M_B_CPU0_SB_DQ<25>
  J3     135  DQ_B25  SCONN288_ADR50001P013C01  I11
  J4     135  DQ_B25  SCONN288_ADR50001P003C01  I23
  U2     B16  DDR1_SB_DQ25  SOCKET4677_AZIFS054P001C01  I169

M_B_CPU0_SB_DQ<26>   @S9S_MB_2U_LIB.S9S_MB_2U(SCH_1):M_B_CPU0_SB_DQ<26>
  J3     278  DQ_B26  SCONN288_ADR50001P013C01  I11
  J4     278  DQ_B26  SCONN288_ADR50001P003C01  I23
  U2     E17  DDR1_SB_DQ26  SOCKET4677_AZIFS054P001C01  I169

M_B_CPU0_SB_DQ<27>   @S9S_MB_2U_LIB.S9S_MB_2U(SCH_1):M_B_CPU0_SB_DQ<27>
  J3     280  DQ_B27  SCONN288_ADR50001P013C01  I11
  J4     280  DQ_B27  SCONN288_ADR50001P003C01  I23
  U2     F16  DDR1_SB_DQ27  SOCKET4677_AZIFS054P001C01  I169

M_B_CPU0_SB_DQ<28>   @S9S_MB_2U_LIB.S9S_MB_2U(SCH_1):M_B_CPU0_SB_DQ<28>
  J3     140  DQ_B28  SCONN288_ADR50001P013C01  I11
  J4     140  DQ_B28  SCONN288_ADR50001P003C01  I23
  U2     C13  DDR1_SB_DQ28  SOCKET4677_AZIFS054P001C01  I169

M_B_CPU0_SB_DQ<29>   @S9S_MB_2U_LIB.S9S_MB_2U(SCH_1):M_B_CPU0_SB_DQ<29>
  J3     142  DQ_B29  SCONN288_ADR50001P013C01  I11
  J4     142  DQ_B29  SCONN288_ADR50001P003C01  I23
  U2     E13  DDR1_SB_DQ29  SOCKET4677_AZIFS054P001C01  I169

M_B_CPU0_SB_DQ<30>   @S9S_MB_2U_LIB.S9S_MB_2U(SCH_1):M_B_CPU0_SB_DQ<30>
  J3     285  DQ_B30  SCONN288_ADR50001P013C01  I11
  J4     285  DQ_B30  SCONN288_ADR50001P003C01  I23
  U2     B14  DDR1_SB_DQ30  SOCKET4677_AZIFS054P001C01  I169

M_B_CPU0_SB_DQ<31>   @S9S_MB_2U_LIB.S9S_MB_2U(SCH_1):M_B_CPU0_SB_DQ<31>
  J3     287  DQ_B31  SCONN288_ADR50001P013C01  I11
  J4     287  DQ_B31  SCONN288_ADR50001P003C01  I23
  U2     F14  DDR1_SB_DQ31  SOCKET4677_AZIFS054P001C01  I169

M_B_CPU0_SB_DQS_DN<0>   @S9S_MB_2U_LIB.S9S_MB_2U(SCH_1):M_B_CPU0_SB_DQS_DN<0>
  J3     105  DQS0_B_N  SCONN288_ADR50001P013C01  I125
  J4     105  DQS0_B_N  SCONN288_ADR50001P003C01  I124
  U2     R27  DDR1_SB_DQS_DN0  SOCKET4677_AZIFS054P001C01  I169

M_B_CPU0_SB_DQS_DN<1>   @S9S_MB_2U_LIB.S9S_MB_2U(SCH_1):M_B_CPU0_SB_DQS_DN<1>
  J3     116  DQS1_B_N  SCONN288_ADR50001P013C01  I125
  J4     116  DQS1_B_N  SCONN288_ADR50001P003C01  I124
  U2     H24  DDR1_SB_DQS_DN1  SOCKET4677_AZIFS054P001C01  I169

M_B_CPU0_SB_DQS_DN<2>   @S9S_MB_2U_LIB.S9S_MB_2U(SCH_1):M_B_CPU0_SB_DQS_DN<2>
  J3     127  DQS2_B_N  SCONN288_ADR50001P013C01  I125
  J4     127  DQS2_B_N  SCONN288_ADR50001P003C01  I124
  U2     H18  DDR1_SB_DQS_DN2  SOCKET4677_AZIFS054P001C01  I169

M_B_CPU0_SB_DQS_DN<3>   @S9S_MB_2U_LIB.S9S_MB_2U(SCH_1):M_B_CPU0_SB_DQS_DN<3>
  J3     138  DQS3_B_N  SCONN288_ADR50001P013C01  I125
  J4     138  DQS3_B_N  SCONN288_ADR50001P003C01  I124
  U2     A15  DDR1_SB_DQS_DN3  SOCKET4677_AZIFS054P001C01  I169

M_B_CPU0_SB_DQS_DN<4>   @S9S_MB_2U_LIB.S9S_MB_2U(SCH_1):M_B_CPU0_SB_DQS_DN<4>
  J3     238  DQS4_B_N  SCONN288_ADR50001P013C01  I125
  J4     238  DQS4_B_N  SCONN288_ADR50001P003C01  I124
  U2     P36  DDR1_SB_DQS_DN4  SOCKET4677_AZIFS054P001C01  I169

M_B_CPU0_SB_DQS_DN<5>   @S9S_MB_2U_LIB.S9S_MB_2U(SCH_1):M_B_CPU0_SB_DQS_DN<5>
  J3     249  DQS5_B_N  SCONN288_ADR50001P013C01  I125
  J4     249  DQS5_B_N  SCONN288_ADR50001P003C01  I124
  U2     W27  DDR1_SB_DQS_DN5  SOCKET4677_AZIFS054P001C01  I169

M_B_CPU0_SB_DQS_DN<6>   @S9S_MB_2U_LIB.S9S_MB_2U(SCH_1):M_B_CPU0_SB_DQS_DN<6>
  J3     260  DQS6_B_N  SCONN288_ADR50001P013C01  I125
  J4     260  DQS6_B_N  SCONN288_ADR50001P003C01  I124
  U2     M24  DDR1_SB_DQS_DN6  SOCKET4677_AZIFS054P001C01  I169

M_B_CPU0_SB_DQS_DN<7>   @S9S_MB_2U_LIB.S9S_MB_2U(SCH_1):M_B_CPU0_SB_DQS_DN<7>
  J3     271  DQS7_B_N  SCONN288_ADR50001P013C01  I125
  J4     271  DQS7_B_N  SCONN288_ADR50001P003C01  I124
  U2     M18  DDR1_SB_DQS_DN7  SOCKET4677_AZIFS054P001C01  I169

M_B_CPU0_SB_DQS_DN<8>   @S9S_MB_2U_LIB.S9S_MB_2U(SCH_1):M_B_CPU0_SB_DQS_DN<8>
  J3     282  DQS8_B_N  SCONN288_ADR50001P013C01  I125
  J4     282  DQS8_B_N  SCONN288_ADR50001P003C01  I124
  U2     E15  DDR1_SB_DQS_DN8  SOCKET4677_AZIFS054P001C01  I169

M_B_CPU0_SB_DQS_DN<9>   @S9S_MB_2U_LIB.S9S_MB_2U(SCH_1):M_B_CPU0_SB_DQS_DN<9>
  J3      94  DQS9_B_N  SCONN288_ADR50001P013C01  I125
  J4      94  DQS9_B_N  SCONN288_ADR50001P003C01  I124
  U2     K36  DDR1_SB_DQS_DN9  SOCKET4677_AZIFS054P001C01  I169

M_B_CPU0_SB_DQS_DP<0>   @S9S_MB_2U_LIB.S9S_MB_2U(SCH_1):M_B_CPU0_SB_DQS_DP<0>
  J3     104  DQS0_B_P  SCONN288_ADR50001P013C01  I125
  J4     104  DQS0_B_P  SCONN288_ADR50001P003C01  I124
  U2     U27  DDR1_SB_DQS_DP0  SOCKET4677_AZIFS054P001C01  I169

M_B_CPU0_SB_DQS_DP<1>   @S9S_MB_2U_LIB.S9S_MB_2U(SCH_1):M_B_CPU0_SB_DQS_DP<1>
  J3     115  DQS1_B_P  SCONN288_ADR50001P013C01  I125
  J4     115  DQS1_B_P  SCONN288_ADR50001P003C01  I124
  U2     K24  DDR1_SB_DQS_DP1  SOCKET4677_AZIFS054P001C01  I169

M_B_CPU0_SB_DQS_DP<2>   @S9S_MB_2U_LIB.S9S_MB_2U(SCH_1):M_B_CPU0_SB_DQS_DP<2>
  J3     126  DQS2_B_P  SCONN288_ADR50001P013C01  I125
  J4     126  DQS2_B_P  SCONN288_ADR50001P003C01  I124
  U2     K18  DDR1_SB_DQS_DP2  SOCKET4677_AZIFS054P001C01  I169

M_B_CPU0_SB_DQS_DP<3>   @S9S_MB_2U_LIB.S9S_MB_2U(SCH_1):M_B_CPU0_SB_DQS_DP<3>
  J3     137  DQS3_B_P  SCONN288_ADR50001P013C01  I125
  J4     137  DQS3_B_P  SCONN288_ADR50001P003C01  I124
  U2     C15  DDR1_SB_DQS_DP3  SOCKET4677_AZIFS054P001C01  I169

M_B_CPU0_SB_DQS_DP<4>   @S9S_MB_2U_LIB.S9S_MB_2U(SCH_1):M_B_CPU0_SB_DQS_DP<4>
  J3     239  DQS4_B_P  SCONN288_ADR50001P013C01  I125
  J4     239  DQS4_B_P  SCONN288_ADR50001P003C01  I124
  U2     M36  DDR1_SB_DQS_DP4  SOCKET4677_AZIFS054P001C01  I169

M_B_CPU0_SB_DQS_DP<5>   @S9S_MB_2U_LIB.S9S_MB_2U(SCH_1):M_B_CPU0_SB_DQS_DP<5>
  J3     250  DQS5_B_P  SCONN288_ADR50001P013C01  I125
  J4     250  DQS5_B_P  SCONN288_ADR50001P003C01  I124
  U2     AA27  DDR1_SB_DQS_DP5  SOCKET4677_AZIFS054P001C01  I169

M_B_CPU0_SB_DQS_DP<6>   @S9S_MB_2U_LIB.S9S_MB_2U(SCH_1):M_B_CPU0_SB_DQS_DP<6>
  J3     261  DQS6_B_P  SCONN288_ADR50001P013C01  I125
  J4     261  DQS6_B_P  SCONN288_ADR50001P003C01  I124
  U2     P24  DDR1_SB_DQS_DP6  SOCKET4677_AZIFS054P001C01  I169

M_B_CPU0_SB_DQS_DP<7>   @S9S_MB_2U_LIB.S9S_MB_2U(SCH_1):M_B_CPU0_SB_DQS_DP<7>
  J3     272  DQS7_B_P  SCONN288_ADR50001P013C01  I125
  J4     272  DQS7_B_P  SCONN288_ADR50001P003C01  I124
  U2     P18  DDR1_SB_DQS_DP7  SOCKET4677_AZIFS054P001C01  I169

M_B_CPU0_SB_DQS_DP<8>   @S9S_MB_2U_LIB.S9S_MB_2U(SCH_1):M_B_CPU0_SB_DQS_DP<8>
  J3     283  DQS8_B_P  SCONN288_ADR50001P013C01  I125
  J4     283  DQS8_B_P  SCONN288_ADR50001P003C01  I124
  U2     G15  DDR1_SB_DQS_DP8  SOCKET4677_AZIFS054P001C01  I169

M_B_CPU0_SB_DQS_DP<9>   @S9S_MB_2U_LIB.S9S_MB_2U(SCH_1):M_B_CPU0_SB_DQS_DP<9>
  J3      93  DQS9_B_P  SCONN288_ADR50001P013C01  I125
  J4      93  DQS9_B_P  SCONN288_ADR50001P003C01  I124
  U2     H36  DDR1_SB_DQS_DP9  SOCKET4677_AZIFS054P001C01  I169

M_B_CPU0_SB_PAR   @S9S_MB_2U_LIB.S9S_MB_2U(SCH_1):M_B_CPU0_SB_PAR
  J3     227  PAR_B  SCONN288_ADR50001P013C01  I11
  J4     227  PAR_B  SCONN288_ADR50001P003C01  I23
  U2     P42  DDR1_SB_PAR  SOCKET4677_AZIFS054P001C01  I169

M_B_CPU0_SB_RSP<0>   @S9S_MB_2U_LIB.S9S_MB_2U(SCH_1):M_B_CPU0_SB_RSP<0>
  J3      87  LBS||RSP_N_B  SCONN288_ADR50001P013C01  I11
  U2     AN48  DDR1_B_RSP0  SOCKET4677_AZIFS054P001C01  I169

M_B_CPU0_SB_RSP<1>   @S9S_MB_2U_LIB.S9S_MB_2U(SCH_1):M_B_CPU0_SB_RSP<1>
  J4      87  LBS||RSP_N_B  SCONN288_ADR50001P003C01  I23
  U2     AP47  DDR1_B_RSP1  SOCKET4677_AZIFS054P001C01  I169

M_B_CPU1_ALERT_N   @S9S_MB_2U_LIB.S9S_MB_2U(SCH_1):M_B_CPU1_ALERT_N
  J19     62  ALERT_N  SCONN288_ADR50001P013C01  I25
  J20     62  ALERT_N  SCONN288_ADR50001P003C01  I47
  U1     AV49  DDR1_ALERT_N  SOCKET4677_AZIFS054P001C01  I91

M_B_CPU1_CLK_DN<0>   @S9S_MB_2U_LIB.S9S_MB_2U(SCH_1):M_B_CPU1_CLK_DN<0>
  J19    218   CK_N  SCONN288_ADR50001P013C01  I25
  U1     R45  DDR1_CLK_DN0  SOCKET4677_AZIFS054P001C01  I91

M_B_CPU1_CLK_DN<1>   @S9S_MB_2U_LIB.S9S_MB_2U(SCH_1):M_B_CPU1_CLK_DN<1>
  J20    218   CK_N  SCONN288_ADR50001P003C01  I47
  U1     W45  DDR1_CLK_DN1  SOCKET4677_AZIFS054P001C01  I91

M_B_CPU1_CLK_DP<0>   @S9S_MB_2U_LIB.S9S_MB_2U(SCH_1):M_B_CPU1_CLK_DP<0>
  J19    217   CK_P  SCONN288_ADR50001P013C01  I25
  U1     U45  DDR1_CLK_DP0  SOCKET4677_AZIFS054P001C01  I91

M_B_CPU1_CLK_DP<1>   @S9S_MB_2U_LIB.S9S_MB_2U(SCH_1):M_B_CPU1_CLK_DP<1>
  J20    217   CK_P  SCONN288_ADR50001P003C01  I47
  U1     AA45  DDR1_CLK_DP1  SOCKET4677_AZIFS054P001C01  I91

M_B_CPU1_SA_CA<0>   @S9S_MB_2U_LIB.S9S_MB_2U(SCH_1):M_B_CPU1_SA_CA<0>
  J19     66  CA0_A  SCONN288_ADR50001P013C01  I25
  J20     66  CA0_A  SCONN288_ADR50001P003C01  I47
  U1     H49  DDR1_SA_CA0  SOCKET4677_AZIFS054P001C01  I91

M_B_CPU1_SA_CA<1>   @S9S_MB_2U_LIB.S9S_MB_2U(SCH_1):M_B_CPU1_SA_CA<1>
  J19    211  CA1_A  SCONN288_ADR50001P013C01  I25
  J20    211  CA1_A  SCONN288_ADR50001P003C01  I47
  U1     P49  DDR1_SA_CA1  SOCKET4677_AZIFS054P001C01  I91

M_B_CPU1_SA_CA<2>   @S9S_MB_2U_LIB.S9S_MB_2U(SCH_1):M_B_CPU1_SA_CA<2>
  J19     68  CA2_A  SCONN288_ADR50001P013C01  I25
  J20     68  CA2_A  SCONN288_ADR50001P003C01  I47
  U1     J48  DDR1_SA_CA2  SOCKET4677_AZIFS054P001C01  I91

M_B_CPU1_SA_CA<3>   @S9S_MB_2U_LIB.S9S_MB_2U(SCH_1):M_B_CPU1_SA_CA<3>
  J19    213  CA3_A  SCONN288_ADR50001P013C01  I25
  J20    213  CA3_A  SCONN288_ADR50001P003C01  I47
  U1     N48  DDR1_SA_CA3  SOCKET4677_AZIFS054P001C01  I91

M_B_CPU1_SA_CA<4>   @S9S_MB_2U_LIB.S9S_MB_2U(SCH_1):M_B_CPU1_SA_CA<4>
  J19     70  CA4_A  SCONN288_ADR50001P013C01  I25
  J20     70  CA4_A  SCONN288_ADR50001P003C01  I47
  U1     K47  DDR1_SA_CA4  SOCKET4677_AZIFS054P001C01  I91

M_B_CPU1_SA_CA<5>   @S9S_MB_2U_LIB.S9S_MB_2U(SCH_1):M_B_CPU1_SA_CA<5>
  J19    215  CA5_A  SCONN288_ADR50001P013C01  I25
  J20    215  CA5_A  SCONN288_ADR50001P003C01  I47
  U1     M47  DDR1_SA_CA5  SOCKET4677_AZIFS054P001C01  I91

M_B_CPU1_SA_CA<6>   @S9S_MB_2U_LIB.S9S_MB_2U(SCH_1):M_B_CPU1_SA_CA<6>
  J19     72  CA6_A  SCONN288_ADR50001P013C01  I25
  J20     72  CA6_A  SCONN288_ADR50001P003C01  I47
  U1     Y44  DDR1_SA_CA6  SOCKET4677_AZIFS054P001C01  I91

M_B_CPU1_SA_CB<0>   @S9S_MB_2U_LIB.S9S_MB_2U(SCH_1):M_B_CPU1_SA_CB<0>
  J19     51  CB_A0  SCONN288_ADR50001P013C01  I25
  J20     51  CB_A0  SCONN288_ADR50001P003C01  I47
  U1     K57  DDR1_SA_ECC0  SOCKET4677_AZIFS054P001C01  I91

M_B_CPU1_SA_CB<1>   @S9S_MB_2U_LIB.S9S_MB_2U(SCH_1):M_B_CPU1_SA_CB<1>
  J19     53  CB_A1  SCONN288_ADR50001P013C01  I25
  J20     53  CB_A1  SCONN288_ADR50001P003C01  I47
  U1     J56  DDR1_SA_ECC1  SOCKET4677_AZIFS054P001C01  I91

M_B_CPU1_SA_CB<2>   @S9S_MB_2U_LIB.S9S_MB_2U(SCH_1):M_B_CPU1_SA_CB<2>
  J19    196  CB_A2  SCONN288_ADR50001P013C01  I25
  J20    196  CB_A2  SCONN288_ADR50001P003C01  I47
  U1     M57  DDR1_SA_ECC2  SOCKET4677_AZIFS054P001C01  I91

M_B_CPU1_SA_CB<3>   @S9S_MB_2U_LIB.S9S_MB_2U(SCH_1):M_B_CPU1_SA_CB<3>
  J19    198  CB_A3  SCONN288_ADR50001P013C01  I25
  J20    198  CB_A3  SCONN288_ADR50001P003C01  I47
  U1     N56  DDR1_SA_ECC3  SOCKET4677_AZIFS054P001C01  I91

M_B_CPU1_SA_CB<4>   @S9S_MB_2U_LIB.S9S_MB_2U(SCH_1):M_B_CPU1_SA_CB<4>
  J19     58  CB_A4  SCONN288_ADR50001P013C01  I25
  J20     58  CB_A4  SCONN288_ADR50001P003C01  I47
  U1     J54  DDR1_SA_ECC4  SOCKET4677_AZIFS054P001C01  I91

M_B_CPU1_SA_CB<5>   @S9S_MB_2U_LIB.S9S_MB_2U(SCH_1):M_B_CPU1_SA_CB<5>
  J19     60  CB_A5  SCONN288_ADR50001P013C01  I25
  J20     60  CB_A5  SCONN288_ADR50001P003C01  I47
  U1     K53  DDR1_SA_ECC5  SOCKET4677_AZIFS054P001C01  I91

M_B_CPU1_SA_CB<6>   @S9S_MB_2U_LIB.S9S_MB_2U(SCH_1):M_B_CPU1_SA_CB<6>
  J19    203  CB_A6  SCONN288_ADR50001P013C01  I25
  J20    203  CB_A6  SCONN288_ADR50001P003C01  I47
  U1     N54  DDR1_SA_ECC6  SOCKET4677_AZIFS054P001C01  I91

M_B_CPU1_SA_CB<7>   @S9S_MB_2U_LIB.S9S_MB_2U(SCH_1):M_B_CPU1_SA_CB<7>
  J19    205  CB_A7  SCONN288_ADR50001P013C01  I25
  J20    205  CB_A7  SCONN288_ADR50001P003C01  I47
  U1     M53  DDR1_SA_ECC7  SOCKET4677_AZIFS054P001C01  I91

M_B_CPU1_SA_CS_N<0>   @S9S_MB_2U_LIB.S9S_MB_2U(SCH_1):M_B_CPU1_SA_CS_N<0>
  J19     64  CS0_N_A  SCONN288_ADR50001P013C01  I25
  U1     K51  DDR1_SA_CS0_N  SOCKET4677_AZIFS054P001C01  I91

M_B_CPU1_SA_CS_N<1>   @S9S_MB_2U_LIB.S9S_MB_2U(SCH_1):M_B_CPU1_SA_CS_N<1>
  J19    209  CS1_N_A  SCONN288_ADR50001P013C01  I25
  U1     J50  DDR1_SA_CS1_N  SOCKET4677_AZIFS054P001C01  I91

M_B_CPU1_SA_CS_N<2>   @S9S_MB_2U_LIB.S9S_MB_2U(SCH_1):M_B_CPU1_SA_CS_N<2>
  J20     64  CS0_N_A  SCONN288_ADR50001P003C01  I47
  U1     M51  DDR1_SA_CS2_N  SOCKET4677_AZIFS054P001C01  I91

M_B_CPU1_SA_CS_N<3>   @S9S_MB_2U_LIB.S9S_MB_2U(SCH_1):M_B_CPU1_SA_CS_N<3>
  J20    209  CS1_N_A  SCONN288_ADR50001P003C01  I47
  U1     N50  DDR1_SA_CS3_N  SOCKET4677_AZIFS054P001C01  I91

M_B_CPU1_SA_DQ<0>   @S9S_MB_2U_LIB.S9S_MB_2U(SCH_1):M_B_CPU1_SA_DQ<0>
  J19      7  DQ_A0  SCONN288_ADR50001P013C01  I25
  J20      7  DQ_A0  SCONN288_ADR50001P003C01  I47
  U1     K75  DDR1_SA_DQ0  SOCKET4677_AZIFS054P001C01  I91

M_B_CPU1_SA_DQ<1>   @S9S_MB_2U_LIB.S9S_MB_2U(SCH_1):M_B_CPU1_SA_DQ<1>
  J19      9  DQ_A1  SCONN288_ADR50001P013C01  I25
  J20      9  DQ_A1  SCONN288_ADR50001P003C01  I47
  U1     J74  DDR1_SA_DQ1  SOCKET4677_AZIFS054P001C01  I91

M_B_CPU1_SA_DQ<2>   @S9S_MB_2U_LIB.S9S_MB_2U(SCH_1):M_B_CPU1_SA_DQ<2>
  J19    152  DQ_A2  SCONN288_ADR50001P013C01  I25
  J20    152  DQ_A2  SCONN288_ADR50001P003C01  I47
  U1     M75  DDR1_SA_DQ2  SOCKET4677_AZIFS054P001C01  I91

M_B_CPU1_SA_DQ<3>   @S9S_MB_2U_LIB.S9S_MB_2U(SCH_1):M_B_CPU1_SA_DQ<3>
  J19    154  DQ_A3  SCONN288_ADR50001P013C01  I25
  J20    154  DQ_A3  SCONN288_ADR50001P003C01  I47
  U1     N74  DDR1_SA_DQ3  SOCKET4677_AZIFS054P001C01  I91

M_B_CPU1_SA_DQ<4>   @S9S_MB_2U_LIB.S9S_MB_2U(SCH_1):M_B_CPU1_SA_DQ<4>
  J19     14  DQ_A4  SCONN288_ADR50001P013C01  I25
  J20     14  DQ_A4  SCONN288_ADR50001P003C01  I47
  U1     J72  DDR1_SA_DQ4  SOCKET4677_AZIFS054P001C01  I91

M_B_CPU1_SA_DQ<5>   @S9S_MB_2U_LIB.S9S_MB_2U(SCH_1):M_B_CPU1_SA_DQ<5>
  J19     16  DQ_A5  SCONN288_ADR50001P013C01  I25
  J20     16  DQ_A5  SCONN288_ADR50001P003C01  I47
  U1     K71  DDR1_SA_DQ5  SOCKET4677_AZIFS054P001C01  I91

M_B_CPU1_SA_DQ<6>   @S9S_MB_2U_LIB.S9S_MB_2U(SCH_1):M_B_CPU1_SA_DQ<6>
  J19    159  DQ_A6  SCONN288_ADR50001P013C01  I25
  J20    159  DQ_A6  SCONN288_ADR50001P003C01  I47
  U1     N72  DDR1_SA_DQ6  SOCKET4677_AZIFS054P001C01  I91

M_B_CPU1_SA_DQ<7>   @S9S_MB_2U_LIB.S9S_MB_2U(SCH_1):M_B_CPU1_SA_DQ<7>
  J19    161  DQ_A7  SCONN288_ADR50001P013C01  I25
  J20    161  DQ_A7  SCONN288_ADR50001P003C01  I47
  U1     M71  DDR1_SA_DQ7  SOCKET4677_AZIFS054P001C01  I91

M_B_CPU1_SA_DQ<8>   @S9S_MB_2U_LIB.S9S_MB_2U(SCH_1):M_B_CPU1_SA_DQ<8>
  J19     18  DQ_A8  SCONN288_ADR50001P013C01  I25
  J20     18  DQ_A8  SCONN288_ADR50001P003C01  I47
  U1     U72  DDR1_SA_DQ8  SOCKET4677_AZIFS054P001C01  I91

M_B_CPU1_SA_DQ<9>   @S9S_MB_2U_LIB.S9S_MB_2U(SCH_1):M_B_CPU1_SA_DQ<9>
  J19     20  DQ_A9  SCONN288_ADR50001P013C01  I25
  J20     20  DQ_A9  SCONN288_ADR50001P003C01  I47
  U1     T71  DDR1_SA_DQ9  SOCKET4677_AZIFS054P001C01  I91

M_B_CPU1_SA_DQ<10>   @S9S_MB_2U_LIB.S9S_MB_2U(SCH_1):M_B_CPU1_SA_DQ<10>
  J19    163  DQ_A10  SCONN288_ADR50001P013C01  I25
  J20    163  DQ_A10  SCONN288_ADR50001P003C01  I47
  U1     W72  DDR1_SA_DQ10  SOCKET4677_AZIFS054P001C01  I91

M_B_CPU1_SA_DQ<11>   @S9S_MB_2U_LIB.S9S_MB_2U(SCH_1):M_B_CPU1_SA_DQ<11>
  J19    165  DQ_A11  SCONN288_ADR50001P013C01  I25
  J20    165  DQ_A11  SCONN288_ADR50001P003C01  I47
  U1     Y71  DDR1_SA_DQ11  SOCKET4677_AZIFS054P001C01  I91

M_B_CPU1_SA_DQ<12>   @S9S_MB_2U_LIB.S9S_MB_2U(SCH_1):M_B_CPU1_SA_DQ<12>
  J19     25  DQ_A12  SCONN288_ADR50001P013C01  I25
  J20     25  DQ_A12  SCONN288_ADR50001P003C01  I47
  U1     T69  DDR1_SA_DQ12  SOCKET4677_AZIFS054P001C01  I91

M_B_CPU1_SA_DQ<13>   @S9S_MB_2U_LIB.S9S_MB_2U(SCH_1):M_B_CPU1_SA_DQ<13>
  J19     27  DQ_A13  SCONN288_ADR50001P013C01  I25
  J20     27  DQ_A13  SCONN288_ADR50001P003C01  I47
  U1     U68  DDR1_SA_DQ13  SOCKET4677_AZIFS054P001C01  I91

M_B_CPU1_SA_DQ<14>   @S9S_MB_2U_LIB.S9S_MB_2U(SCH_1):M_B_CPU1_SA_DQ<14>
  J19    170  DQ_A14  SCONN288_ADR50001P013C01  I25
  J20    170  DQ_A14  SCONN288_ADR50001P003C01  I47
  U1     Y69  DDR1_SA_DQ14  SOCKET4677_AZIFS054P001C01  I91

M_B_CPU1_SA_DQ<15>   @S9S_MB_2U_LIB.S9S_MB_2U(SCH_1):M_B_CPU1_SA_DQ<15>
  J19    172  DQ_A15  SCONN288_ADR50001P013C01  I25
  J20    172  DQ_A15  SCONN288_ADR50001P003C01  I47
  U1     W68  DDR1_SA_DQ15  SOCKET4677_AZIFS054P001C01  I91

M_B_CPU1_SA_DQ<16>   @S9S_MB_2U_LIB.S9S_MB_2U(SCH_1):M_B_CPU1_SA_DQ<16>
  J19     29  DQ_A16  SCONN288_ADR50001P013C01  I25
  J20     29  DQ_A16  SCONN288_ADR50001P003C01  I47
  U1     K63  DDR1_SA_DQ16  SOCKET4677_AZIFS054P001C01  I91

M_B_CPU1_SA_DQ<17>   @S9S_MB_2U_LIB.S9S_MB_2U(SCH_1):M_B_CPU1_SA_DQ<17>
  J19     31  DQ_A17  SCONN288_ADR50001P013C01  I25
  J20     31  DQ_A17  SCONN288_ADR50001P003C01  I47
  U1     J62  DDR1_SA_DQ17  SOCKET4677_AZIFS054P001C01  I91

M_B_CPU1_SA_DQ<18>   @S9S_MB_2U_LIB.S9S_MB_2U(SCH_1):M_B_CPU1_SA_DQ<18>
  J19    174  DQ_A18  SCONN288_ADR50001P013C01  I25
  J20    174  DQ_A18  SCONN288_ADR50001P003C01  I47
  U1     M63  DDR1_SA_DQ18  SOCKET4677_AZIFS054P001C01  I91

M_B_CPU1_SA_DQ<19>   @S9S_MB_2U_LIB.S9S_MB_2U(SCH_1):M_B_CPU1_SA_DQ<19>
  J19    176  DQ_A19  SCONN288_ADR50001P013C01  I25
  J20    176  DQ_A19  SCONN288_ADR50001P003C01  I47
  U1     N62  DDR1_SA_DQ19  SOCKET4677_AZIFS054P001C01  I91

M_B_CPU1_SA_DQ<20>   @S9S_MB_2U_LIB.S9S_MB_2U(SCH_1):M_B_CPU1_SA_DQ<20>
  J19     36  DQ_A20  SCONN288_ADR50001P013C01  I25
  J20     36  DQ_A20  SCONN288_ADR50001P003C01  I47
  U1     J60  DDR1_SA_DQ20  SOCKET4677_AZIFS054P001C01  I91

M_B_CPU1_SA_DQ<21>   @S9S_MB_2U_LIB.S9S_MB_2U(SCH_1):M_B_CPU1_SA_DQ<21>
  J19     38  DQ_A21  SCONN288_ADR50001P013C01  I25
  J20     38  DQ_A21  SCONN288_ADR50001P003C01  I47
  U1     K59  DDR1_SA_DQ21  SOCKET4677_AZIFS054P001C01  I91

M_B_CPU1_SA_DQ<22>   @S9S_MB_2U_LIB.S9S_MB_2U(SCH_1):M_B_CPU1_SA_DQ<22>
  J19    181  DQ_A22  SCONN288_ADR50001P013C01  I25
  J20    181  DQ_A22  SCONN288_ADR50001P003C01  I47
  U1     N60  DDR1_SA_DQ22  SOCKET4677_AZIFS054P001C01  I91

M_B_CPU1_SA_DQ<23>   @S9S_MB_2U_LIB.S9S_MB_2U(SCH_1):M_B_CPU1_SA_DQ<23>
  J19    183  DQ_A23  SCONN288_ADR50001P013C01  I25
  J20    183  DQ_A23  SCONN288_ADR50001P003C01  I47
  U1     M59  DDR1_SA_DQ23  SOCKET4677_AZIFS054P001C01  I91

M_B_CPU1_SA_DQ<24>   @S9S_MB_2U_LIB.S9S_MB_2U(SCH_1):M_B_CPU1_SA_DQ<24>
  J19     40  DQ_A24  SCONN288_ADR50001P013C01  I25
  J20     40  DQ_A24  SCONN288_ADR50001P003C01  I47
  U1     U60  DDR1_SA_DQ24  SOCKET4677_AZIFS054P001C01  I91

M_B_CPU1_SA_DQ<25>   @S9S_MB_2U_LIB.S9S_MB_2U(SCH_1):M_B_CPU1_SA_DQ<25>
  J19     42  DQ_A25  SCONN288_ADR50001P013C01  I25
  J20     42  DQ_A25  SCONN288_ADR50001P003C01  I47
  U1     T59  DDR1_SA_DQ25  SOCKET4677_AZIFS054P001C01  I91

M_B_CPU1_SA_DQ<26>   @S9S_MB_2U_LIB.S9S_MB_2U(SCH_1):M_B_CPU1_SA_DQ<26>
  J19    185  DQ_A26  SCONN288_ADR50001P013C01  I25
  J20    185  DQ_A26  SCONN288_ADR50001P003C01  I47
  U1     W60  DDR1_SA_DQ26  SOCKET4677_AZIFS054P001C01  I91

M_B_CPU1_SA_DQ<27>   @S9S_MB_2U_LIB.S9S_MB_2U(SCH_1):M_B_CPU1_SA_DQ<27>
  J19    187  DQ_A27  SCONN288_ADR50001P013C01  I25
  J20    187  DQ_A27  SCONN288_ADR50001P003C01  I47
  U1     Y59  DDR1_SA_DQ27  SOCKET4677_AZIFS054P001C01  I91

M_B_CPU1_SA_DQ<28>   @S9S_MB_2U_LIB.S9S_MB_2U(SCH_1):M_B_CPU1_SA_DQ<28>
  J19     47  DQ_A28  SCONN288_ADR50001P013C01  I25
  J20     47  DQ_A28  SCONN288_ADR50001P003C01  I47
  U1     T57  DDR1_SA_DQ28  SOCKET4677_AZIFS054P001C01  I91

M_B_CPU1_SA_DQ<29>   @S9S_MB_2U_LIB.S9S_MB_2U(SCH_1):M_B_CPU1_SA_DQ<29>
  J19     49  DQ_A29  SCONN288_ADR50001P013C01  I25
  J20     49  DQ_A29  SCONN288_ADR50001P003C01  I47
  U1     U56  DDR1_SA_DQ29  SOCKET4677_AZIFS054P001C01  I91

M_B_CPU1_SA_DQ<30>   @S9S_MB_2U_LIB.S9S_MB_2U(SCH_1):M_B_CPU1_SA_DQ<30>
  J19    192  DQ_A30  SCONN288_ADR50001P013C01  I25
  J20    192  DQ_A30  SCONN288_ADR50001P003C01  I47
  U1     Y57  DDR1_SA_DQ30  SOCKET4677_AZIFS054P001C01  I91

M_B_CPU1_SA_DQ<31>   @S9S_MB_2U_LIB.S9S_MB_2U(SCH_1):M_B_CPU1_SA_DQ<31>
  J19    194  DQ_A31  SCONN288_ADR50001P013C01  I25
  J20    194  DQ_A31  SCONN288_ADR50001P003C01  I47
  U1     W56  DDR1_SA_DQ31  SOCKET4677_AZIFS054P001C01  I91

M_B_CPU1_SA_DQS_DN<0>   @S9S_MB_2U_LIB.S9S_MB_2U(SCH_1):M_B_CPU1_SA_DQS_DN<0>
  J19     12  DQS0_A_N  SCONN288_ADR50001P013C01  I126
  J20     12  DQS0_A_N  SCONN288_ADR50001P003C01  I124
  U1     H73  DDR1_SA_DQS_DN0  SOCKET4677_AZIFS054P001C01  I91

M_B_CPU1_SA_DQS_DN<1>   @S9S_MB_2U_LIB.S9S_MB_2U(SCH_1):M_B_CPU1_SA_DQS_DN<1>
  J19     23  DQS1_A_N  SCONN288_ADR50001P013C01  I126
  J20     23  DQS1_A_N  SCONN288_ADR50001P003C01  I124
  U1     R70  DDR1_SA_DQS_DN1  SOCKET4677_AZIFS054P001C01  I91

M_B_CPU1_SA_DQS_DN<2>   @S9S_MB_2U_LIB.S9S_MB_2U(SCH_1):M_B_CPU1_SA_DQS_DN<2>
  J19     34  DQS2_A_N  SCONN288_ADR50001P013C01  I126
  J20     34  DQS2_A_N  SCONN288_ADR50001P003C01  I124
  U1     H61  DDR1_SA_DQS_DN2  SOCKET4677_AZIFS054P001C01  I91

M_B_CPU1_SA_DQS_DN<3>   @S9S_MB_2U_LIB.S9S_MB_2U(SCH_1):M_B_CPU1_SA_DQS_DN<3>
  J19     45  DQS3_A_N  SCONN288_ADR50001P013C01  I126
  J20     45  DQS3_A_N  SCONN288_ADR50001P003C01  I124
  U1     R58  DDR1_SA_DQS_DN3  SOCKET4677_AZIFS054P001C01  I91

M_B_CPU1_SA_DQS_DN<4>   @S9S_MB_2U_LIB.S9S_MB_2U(SCH_1):M_B_CPU1_SA_DQS_DN<4>
  J19     56  DQS4_A_N  SCONN288_ADR50001P013C01  I126
  J20     56  DQS4_A_N  SCONN288_ADR50001P003C01  I124
  U1     H55  DDR1_SA_DQS_DN4  SOCKET4677_AZIFS054P001C01  I91

M_B_CPU1_SA_DQS_DN<5>   @S9S_MB_2U_LIB.S9S_MB_2U(SCH_1):M_B_CPU1_SA_DQS_DN<5>
  J19    156  DQS5_A_N  SCONN288_ADR50001P013C01  I126
  J20    156  DQS5_A_N  SCONN288_ADR50001P003C01  I124
  U1     M73  DDR1_SA_DQS_DN5  SOCKET4677_AZIFS054P001C01  I91

M_B_CPU1_SA_DQS_DN<6>   @S9S_MB_2U_LIB.S9S_MB_2U(SCH_1):M_B_CPU1_SA_DQS_DN<6>
  J19    167  DQS6_A_N  SCONN288_ADR50001P013C01  I126
  J20    167  DQS6_A_N  SCONN288_ADR50001P003C01  I124
  U1     AA70  DDR1_SA_DQS_DN6  SOCKET4677_AZIFS054P001C01  I91

M_B_CPU1_SA_DQS_DN<7>   @S9S_MB_2U_LIB.S9S_MB_2U(SCH_1):M_B_CPU1_SA_DQS_DN<7>
  J19    178  DQS7_A_N  SCONN288_ADR50001P013C01  I126
  J20    178  DQS7_A_N  SCONN288_ADR50001P003C01  I124
  U1     M61  DDR1_SA_DQS_DN7  SOCKET4677_AZIFS054P001C01  I91

M_B_CPU1_SA_DQS_DN<8>   @S9S_MB_2U_LIB.S9S_MB_2U(SCH_1):M_B_CPU1_SA_DQS_DN<8>
  J19    189  DQS8_A_N  SCONN288_ADR50001P013C01  I126
  J20    189  DQS8_A_N  SCONN288_ADR50001P003C01  I124
  U1     AA58  DDR1_SA_DQS_DN8  SOCKET4677_AZIFS054P001C01  I91

M_B_CPU1_SA_DQS_DN<9>   @S9S_MB_2U_LIB.S9S_MB_2U(SCH_1):M_B_CPU1_SA_DQS_DN<9>
  J19    200  DQS9_A_N  SCONN288_ADR50001P013C01  I126
  J20    200  DQS9_A_N  SCONN288_ADR50001P003C01  I124
  U1     M55  DDR1_SA_DQS_DN9  SOCKET4677_AZIFS054P001C01  I91

M_B_CPU1_SA_DQS_DP<0>   @S9S_MB_2U_LIB.S9S_MB_2U(SCH_1):M_B_CPU1_SA_DQS_DP<0>
  J19     11  DQS0_A_P  SCONN288_ADR50001P013C01  I126
  J20     11  DQS0_A_P  SCONN288_ADR50001P003C01  I124
  U1     K73  DDR1_SA_DQS_DP0  SOCKET4677_AZIFS054P001C01  I91

M_B_CPU1_SA_DQS_DP<1>   @S9S_MB_2U_LIB.S9S_MB_2U(SCH_1):M_B_CPU1_SA_DQS_DP<1>
  J19     22  DQS1_A_P  SCONN288_ADR50001P013C01  I126
  J20     22  DQS1_A_P  SCONN288_ADR50001P003C01  I124
  U1     U70  DDR1_SA_DQS_DP1  SOCKET4677_AZIFS054P001C01  I91

M_B_CPU1_SA_DQS_DP<2>   @S9S_MB_2U_LIB.S9S_MB_2U(SCH_1):M_B_CPU1_SA_DQS_DP<2>
  J19     33  DQS2_A_P  SCONN288_ADR50001P013C01  I126
  J20     33  DQS2_A_P  SCONN288_ADR50001P003C01  I124
  U1     K61  DDR1_SA_DQS_DP2  SOCKET4677_AZIFS054P001C01  I91

M_B_CPU1_SA_DQS_DP<3>   @S9S_MB_2U_LIB.S9S_MB_2U(SCH_1):M_B_CPU1_SA_DQS_DP<3>
  J19     44  DQS3_A_P  SCONN288_ADR50001P013C01  I126
  J20     44  DQS3_A_P  SCONN288_ADR50001P003C01  I124
  U1     U58  DDR1_SA_DQS_DP3  SOCKET4677_AZIFS054P001C01  I91

M_B_CPU1_SA_DQS_DP<4>   @S9S_MB_2U_LIB.S9S_MB_2U(SCH_1):M_B_CPU1_SA_DQS_DP<4>
  J19     55  DQS4_A_P  SCONN288_ADR50001P013C01  I126
  J20     55  DQS4_A_P  SCONN288_ADR50001P003C01  I124
  U1     K55  DDR1_SA_DQS_DP4  SOCKET4677_AZIFS054P001C01  I91

M_B_CPU1_SA_DQS_DP<5>   @S9S_MB_2U_LIB.S9S_MB_2U(SCH_1):M_B_CPU1_SA_DQS_DP<5>
  J19    157  DQS5_A_P  SCONN288_ADR50001P013C01  I126
  J20    157  DQS5_A_P  SCONN288_ADR50001P003C01  I124
  U1     P73  DDR1_SA_DQS_DP5  SOCKET4677_AZIFS054P001C01  I91

M_B_CPU1_SA_DQS_DP<6>   @S9S_MB_2U_LIB.S9S_MB_2U(SCH_1):M_B_CPU1_SA_DQS_DP<6>
  J19    168  DQS6_A_P  SCONN288_ADR50001P013C01  I126
  J20    168  DQS6_A_P  SCONN288_ADR50001P003C01  I124
  U1     W70  DDR1_SA_DQS_DP6  SOCKET4677_AZIFS054P001C01  I91

M_B_CPU1_SA_DQS_DP<7>   @S9S_MB_2U_LIB.S9S_MB_2U(SCH_1):M_B_CPU1_SA_DQS_DP<7>
  J19    179  DQS7_A_P  SCONN288_ADR50001P013C01  I126
  J20    179  DQS7_A_P  SCONN288_ADR50001P003C01  I124
  U1     P61  DDR1_SA_DQS_DP7  SOCKET4677_AZIFS054P001C01  I91

M_B_CPU1_SA_DQS_DP<8>   @S9S_MB_2U_LIB.S9S_MB_2U(SCH_1):M_B_CPU1_SA_DQS_DP<8>
  J19    190  DQS8_A_P  SCONN288_ADR50001P013C01  I126
  J20    190  DQS8_A_P  SCONN288_ADR50001P003C01  I124
  U1     W58  DDR1_SA_DQS_DP8  SOCKET4677_AZIFS054P001C01  I91

M_B_CPU1_SA_DQS_DP<9>   @S9S_MB_2U_LIB.S9S_MB_2U(SCH_1):M_B_CPU1_SA_DQS_DP<9>
  J19    201  DQS9_A_P  SCONN288_ADR50001P013C01  I126
  J20    201  DQS9_A_P  SCONN288_ADR50001P003C01  I124
  U1     P55  DDR1_SA_DQS_DP9  SOCKET4677_AZIFS054P001C01  I91

M_B_CPU1_SA_PAR   @S9S_MB_2U_LIB.S9S_MB_2U(SCH_1):M_B_CPU1_SA_PAR
  J19     74  PAR_A  SCONN288_ADR50001P013C01  I25
  J20     74  PAR_A  SCONN288_ADR50001P003C01  I47
  U1     W43  DDR1_SA_PAR  SOCKET4677_AZIFS054P001C01  I91

M_B_CPU1_SA_RSP<0>   @S9S_MB_2U_LIB.S9S_MB_2U(SCH_1):M_B_CPU1_SA_RSP<0>
  J19     86  LBD||RSP_N_A  SCONN288_ADR50001P013C01  I25
  U1     AL48  DDR1_A_RSP0  SOCKET4677_AZIFS054P001C01  I91

M_B_CPU1_SA_RSP<1>   @S9S_MB_2U_LIB.S9S_MB_2U(SCH_1):M_B_CPU1_SA_RSP<1>
  J20     86  LBD||RSP_N_A  SCONN288_ADR50001P003C01  I47
  U1     AK47  DDR1_A_RSP1  SOCKET4677_AZIFS054P001C01  I91

M_B_CPU1_SB_CA<0>   @S9S_MB_2U_LIB.S9S_MB_2U(SCH_1):M_B_CPU1_SB_CA<0>
  J19     76  CA0_B  SCONN288_ADR50001P013C01  I25
  J20     76  CA0_B  SCONN288_ADR50001P003C01  I47
  U1     T44  DDR1_SB_CA0  SOCKET4677_AZIFS054P001C01  I91

M_B_CPU1_SB_CA<1>   @S9S_MB_2U_LIB.S9S_MB_2U(SCH_1):M_B_CPU1_SB_CA<1>
  J19    221  CA1_B  SCONN288_ADR50001P013C01  I25
  J20    221  CA1_B  SCONN288_ADR50001P003C01  I47
  U1     U43  DDR1_SB_CA1  SOCKET4677_AZIFS054P001C01  I91

M_B_CPU1_SB_CA<2>   @S9S_MB_2U_LIB.S9S_MB_2U(SCH_1):M_B_CPU1_SB_CA<2>
  J19     78  CA2_B  SCONN288_ADR50001P013C01  I25
  J20     78  CA2_B  SCONN288_ADR50001P003C01  I47
  U1     K44  DDR1_SB_CA2  SOCKET4677_AZIFS054P001C01  I91

M_B_CPU1_SB_CA<3>   @S9S_MB_2U_LIB.S9S_MB_2U(SCH_1):M_B_CPU1_SB_CA<3>
  J19    223  CA3_B  SCONN288_ADR50001P013C01  I25
  J20    223  CA3_B  SCONN288_ADR50001P003C01  I47
  U1     M44  DDR1_SB_CA3  SOCKET4677_AZIFS054P001C01  I91

M_B_CPU1_SB_CA<4>   @S9S_MB_2U_LIB.S9S_MB_2U(SCH_1):M_B_CPU1_SB_CA<4>
  J19     80  CA4_B  SCONN288_ADR50001P013C01  I25
  J20     80  CA4_B  SCONN288_ADR50001P003C01  I47
  U1     J43  DDR1_SB_CA4  SOCKET4677_AZIFS054P001C01  I91

M_B_CPU1_SB_CA<5>   @S9S_MB_2U_LIB.S9S_MB_2U(SCH_1):M_B_CPU1_SB_CA<5>
  J19    225  CA5_B  SCONN288_ADR50001P013C01  I25
  J20    225  CA5_B  SCONN288_ADR50001P003C01  I47
  U1     N43  DDR1_SB_CA5  SOCKET4677_AZIFS054P001C01  I91

M_B_CPU1_SB_CA<6>   @S9S_MB_2U_LIB.S9S_MB_2U(SCH_1):M_B_CPU1_SB_CA<6>
  J19     82  CA6_B  SCONN288_ADR50001P013C01  I25
  J20     82  CA6_B  SCONN288_ADR50001P003C01  I47
  U1     H42  DDR1_SB_CA6  SOCKET4677_AZIFS054P001C01  I91

M_B_CPU1_SB_CB<0>   @S9S_MB_2U_LIB.S9S_MB_2U(SCH_1):M_B_CPU1_SB_CB<0>
  J19     96  CB_B0  SCONN288_ADR50001P013C01  I25
  J20     96  CB_B0  SCONN288_ADR50001P003C01  I47
  U1     J35  DDR1_SB_ECC0  SOCKET4677_AZIFS054P001C01  I91

M_B_CPU1_SB_CB<1>   @S9S_MB_2U_LIB.S9S_MB_2U(SCH_1):M_B_CPU1_SB_CB<1>
  J19     98  CB_B1  SCONN288_ADR50001P013C01  I25
  J20     98  CB_B1  SCONN288_ADR50001P003C01  I47
  U1     K34  DDR1_SB_ECC1  SOCKET4677_AZIFS054P001C01  I91

M_B_CPU1_SB_CB<2>   @S9S_MB_2U_LIB.S9S_MB_2U(SCH_1):M_B_CPU1_SB_CB<2>
  J19    241  CB_B2  SCONN288_ADR50001P013C01  I25
  J20    241  CB_B2  SCONN288_ADR50001P003C01  I47
  U1     N35  DDR1_SB_ECC2  SOCKET4677_AZIFS054P001C01  I91

M_B_CPU1_SB_CB<3>   @S9S_MB_2U_LIB.S9S_MB_2U(SCH_1):M_B_CPU1_SB_CB<3>
  J19    243  CB_B3  SCONN288_ADR50001P013C01  I25
  J20    243  CB_B3  SCONN288_ADR50001P003C01  I47
  U1     M34  DDR1_SB_ECC3  SOCKET4677_AZIFS054P001C01  I91

M_B_CPU1_SB_CB<4>   @S9S_MB_2U_LIB.S9S_MB_2U(SCH_1):M_B_CPU1_SB_CB<4>
  J19     89  CB_B4  SCONN288_ADR50001P013C01  I25
  J20     89  CB_B4  SCONN288_ADR50001P003C01  I47
  U1     K38  DDR1_SB_ECC4  SOCKET4677_AZIFS054P001C01  I91

M_B_CPU1_SB_CB<5>   @S9S_MB_2U_LIB.S9S_MB_2U(SCH_1):M_B_CPU1_SB_CB<5>
  J19     91  CB_B5  SCONN288_ADR50001P013C01  I25
  J20     91  CB_B5  SCONN288_ADR50001P003C01  I47
  U1     J37  DDR1_SB_ECC5  SOCKET4677_AZIFS054P001C01  I91

M_B_CPU1_SB_CB<6>   @S9S_MB_2U_LIB.S9S_MB_2U(SCH_1):M_B_CPU1_SB_CB<6>
  J19    234  CB_B6  SCONN288_ADR50001P013C01  I25
  J20    234  CB_B6  SCONN288_ADR50001P003C01  I47
  U1     M38  DDR1_SB_ECC6  SOCKET4677_AZIFS054P001C01  I91

M_B_CPU1_SB_CB<7>   @S9S_MB_2U_LIB.S9S_MB_2U(SCH_1):M_B_CPU1_SB_CB<7>
  J19    236  CB_B7  SCONN288_ADR50001P013C01  I25
  J20    236  CB_B7  SCONN288_ADR50001P003C01  I47
  U1     N37  DDR1_SB_ECC7  SOCKET4677_AZIFS054P001C01  I91

M_B_CPU1_SB_CS_N<0>   @S9S_MB_2U_LIB.S9S_MB_2U(SCH_1):M_B_CPU1_SB_CS_N<0>
  J19     84  CS0_N_B  SCONN288_ADR50001P013C01  I25
  U1     J41  DDR1_SB_CS0_N  SOCKET4677_AZIFS054P001C01  I91

M_B_CPU1_SB_CS_N<1>   @S9S_MB_2U_LIB.S9S_MB_2U(SCH_1):M_B_CPU1_SB_CS_N<1>
  J19    229  CS1_N_B  SCONN288_ADR50001P013C01  I25
  U1     K40  DDR1_SB_CS1_N  SOCKET4677_AZIFS054P001C01  I91

M_B_CPU1_SB_CS_N<2>   @S9S_MB_2U_LIB.S9S_MB_2U(SCH_1):M_B_CPU1_SB_CS_N<2>
  J20     84  CS0_N_B  SCONN288_ADR50001P003C01  I47
  U1     N41  DDR1_SB_CS2_N  SOCKET4677_AZIFS054P001C01  I91

M_B_CPU1_SB_CS_N<3>   @S9S_MB_2U_LIB.S9S_MB_2U(SCH_1):M_B_CPU1_SB_CS_N<3>
  J20    229  CS1_N_B  SCONN288_ADR50001P003C01  I47
  U1     M40  DDR1_SB_CS3_N  SOCKET4677_AZIFS054P001C01  I91

M_B_CPU1_SB_DQ<0>   @S9S_MB_2U_LIB.S9S_MB_2U(SCH_1):M_B_CPU1_SB_DQ<0>
  J19    100  DQ_B0  SCONN288_ADR50001P013C01  I25
  J20    100  DQ_B0  SCONN288_ADR50001P003C01  I47
  U1     U29  DDR1_SB_DQ0  SOCKET4677_AZIFS054P001C01  I91

M_B_CPU1_SB_DQ<1>   @S9S_MB_2U_LIB.S9S_MB_2U(SCH_1):M_B_CPU1_SB_DQ<1>
  J19    102  DQ_B1  SCONN288_ADR50001P013C01  I25
  J20    102  DQ_B1  SCONN288_ADR50001P003C01  I47
  U1     T28  DDR1_SB_DQ1  SOCKET4677_AZIFS054P001C01  I91

M_B_CPU1_SB_DQ<2>   @S9S_MB_2U_LIB.S9S_MB_2U(SCH_1):M_B_CPU1_SB_DQ<2>
  J19    245  DQ_B2  SCONN288_ADR50001P013C01  I25
  J20    245  DQ_B2  SCONN288_ADR50001P003C01  I47
  U1     W29  DDR1_SB_DQ2  SOCKET4677_AZIFS054P001C01  I91

M_B_CPU1_SB_DQ<3>   @S9S_MB_2U_LIB.S9S_MB_2U(SCH_1):M_B_CPU1_SB_DQ<3>
  J19    247  DQ_B3  SCONN288_ADR50001P013C01  I25
  J20    247  DQ_B3  SCONN288_ADR50001P003C01  I47
  U1     Y28  DDR1_SB_DQ3  SOCKET4677_AZIFS054P001C01  I91

M_B_CPU1_SB_DQ<4>   @S9S_MB_2U_LIB.S9S_MB_2U(SCH_1):M_B_CPU1_SB_DQ<4>
  J19    107  DQ_B4  SCONN288_ADR50001P013C01  I25
  J20    107  DQ_B4  SCONN288_ADR50001P003C01  I47
  U1     T26  DDR1_SB_DQ4  SOCKET4677_AZIFS054P001C01  I91

M_B_CPU1_SB_DQ<5>   @S9S_MB_2U_LIB.S9S_MB_2U(SCH_1):M_B_CPU1_SB_DQ<5>
  J19    109  DQ_B5  SCONN288_ADR50001P013C01  I25
  J20    109  DQ_B5  SCONN288_ADR50001P003C01  I47
  U1     U25  DDR1_SB_DQ5  SOCKET4677_AZIFS054P001C01  I91

M_B_CPU1_SB_DQ<6>   @S9S_MB_2U_LIB.S9S_MB_2U(SCH_1):M_B_CPU1_SB_DQ<6>
  J19    252  DQ_B6  SCONN288_ADR50001P013C01  I25
  J20    252  DQ_B6  SCONN288_ADR50001P003C01  I47
  U1     Y26  DDR1_SB_DQ6  SOCKET4677_AZIFS054P001C01  I91

M_B_CPU1_SB_DQ<7>   @S9S_MB_2U_LIB.S9S_MB_2U(SCH_1):M_B_CPU1_SB_DQ<7>
  J19    254  DQ_B7  SCONN288_ADR50001P013C01  I25
  J20    254  DQ_B7  SCONN288_ADR50001P003C01  I47
  U1     W25  DDR1_SB_DQ7  SOCKET4677_AZIFS054P001C01  I91

M_B_CPU1_SB_DQ<8>   @S9S_MB_2U_LIB.S9S_MB_2U(SCH_1):M_B_CPU1_SB_DQ<8>
  J19    111  DQ_B8  SCONN288_ADR50001P013C01  I25
  J20    111  DQ_B8  SCONN288_ADR50001P003C01  I47
  U1     K26  DDR1_SB_DQ8  SOCKET4677_AZIFS054P001C01  I91

M_B_CPU1_SB_DQ<9>   @S9S_MB_2U_LIB.S9S_MB_2U(SCH_1):M_B_CPU1_SB_DQ<9>
  J19    113  DQ_B9  SCONN288_ADR50001P013C01  I25
  J20    113  DQ_B9  SCONN288_ADR50001P003C01  I47
  U1     J25  DDR1_SB_DQ9  SOCKET4677_AZIFS054P001C01  I91

M_B_CPU1_SB_DQ<10>   @S9S_MB_2U_LIB.S9S_MB_2U(SCH_1):M_B_CPU1_SB_DQ<10>
  J19    256  DQ_B10  SCONN288_ADR50001P013C01  I25
  J20    256  DQ_B10  SCONN288_ADR50001P003C01  I47
  U1     M26  DDR1_SB_DQ10  SOCKET4677_AZIFS054P001C01  I91

M_B_CPU1_SB_DQ<11>   @S9S_MB_2U_LIB.S9S_MB_2U(SCH_1):M_B_CPU1_SB_DQ<11>
  J19    258  DQ_B11  SCONN288_ADR50001P013C01  I25
  J20    258  DQ_B11  SCONN288_ADR50001P003C01  I47
  U1     N25  DDR1_SB_DQ11  SOCKET4677_AZIFS054P001C01  I91

M_B_CPU1_SB_DQ<12>   @S9S_MB_2U_LIB.S9S_MB_2U(SCH_1):M_B_CPU1_SB_DQ<12>
  J19    118  DQ_B12  SCONN288_ADR50001P013C01  I25
  J20    118  DQ_B12  SCONN288_ADR50001P003C01  I47
  U1     J23  DDR1_SB_DQ12  SOCKET4677_AZIFS054P001C01  I91

M_B_CPU1_SB_DQ<13>   @S9S_MB_2U_LIB.S9S_MB_2U(SCH_1):M_B_CPU1_SB_DQ<13>
  J19    120  DQ_B13  SCONN288_ADR50001P013C01  I25
  J20    120  DQ_B13  SCONN288_ADR50001P003C01  I47
  U1     K22  DDR1_SB_DQ13  SOCKET4677_AZIFS054P001C01  I91

M_B_CPU1_SB_DQ<14>   @S9S_MB_2U_LIB.S9S_MB_2U(SCH_1):M_B_CPU1_SB_DQ<14>
  J19    263  DQ_B14  SCONN288_ADR50001P013C01  I25
  J20    263  DQ_B14  SCONN288_ADR50001P003C01  I47
  U1     N23  DDR1_SB_DQ14  SOCKET4677_AZIFS054P001C01  I91

M_B_CPU1_SB_DQ<15>   @S9S_MB_2U_LIB.S9S_MB_2U(SCH_1):M_B_CPU1_SB_DQ<15>
  J19    265  DQ_B15  SCONN288_ADR50001P013C01  I25
  J20    265  DQ_B15  SCONN288_ADR50001P003C01  I47
  U1     M22  DDR1_SB_DQ15  SOCKET4677_AZIFS054P001C01  I91

M_B_CPU1_SB_DQ<16>   @S9S_MB_2U_LIB.S9S_MB_2U(SCH_1):M_B_CPU1_SB_DQ<16>
  J19    122  DQ_B16  SCONN288_ADR50001P013C01  I25
  J20    122  DQ_B16  SCONN288_ADR50001P003C01  I47
  U1     K20  DDR1_SB_DQ16  SOCKET4677_AZIFS054P001C01  I91

M_B_CPU1_SB_DQ<17>   @S9S_MB_2U_LIB.S9S_MB_2U(SCH_1):M_B_CPU1_SB_DQ<17>
  J19    124  DQ_B17  SCONN288_ADR50001P013C01  I25
  J20    124  DQ_B17  SCONN288_ADR50001P003C01  I47
  U1     J19  DDR1_SB_DQ17  SOCKET4677_AZIFS054P001C01  I91

M_B_CPU1_SB_DQ<18>   @S9S_MB_2U_LIB.S9S_MB_2U(SCH_1):M_B_CPU1_SB_DQ<18>
  J19    267  DQ_B18  SCONN288_ADR50001P013C01  I25
  J20    267  DQ_B18  SCONN288_ADR50001P003C01  I47
  U1     M20  DDR1_SB_DQ18  SOCKET4677_AZIFS054P001C01  I91

M_B_CPU1_SB_DQ<19>   @S9S_MB_2U_LIB.S9S_MB_2U(SCH_1):M_B_CPU1_SB_DQ<19>
  J19    269  DQ_B19  SCONN288_ADR50001P013C01  I25
  J20    269  DQ_B19  SCONN288_ADR50001P003C01  I47
  U1     N19  DDR1_SB_DQ19  SOCKET4677_AZIFS054P001C01  I91

M_B_CPU1_SB_DQ<20>   @S9S_MB_2U_LIB.S9S_MB_2U(SCH_1):M_B_CPU1_SB_DQ<20>
  J19    129  DQ_B20  SCONN288_ADR50001P013C01  I25
  J20    129  DQ_B20  SCONN288_ADR50001P003C01  I47
  U1     J17  DDR1_SB_DQ20  SOCKET4677_AZIFS054P001C01  I91

M_B_CPU1_SB_DQ<21>   @S9S_MB_2U_LIB.S9S_MB_2U(SCH_1):M_B_CPU1_SB_DQ<21>
  J19    131  DQ_B21  SCONN288_ADR50001P013C01  I25
  J20    131  DQ_B21  SCONN288_ADR50001P003C01  I47
  U1     K16  DDR1_SB_DQ21  SOCKET4677_AZIFS054P001C01  I91

M_B_CPU1_SB_DQ<22>   @S9S_MB_2U_LIB.S9S_MB_2U(SCH_1):M_B_CPU1_SB_DQ<22>
  J19    274  DQ_B22  SCONN288_ADR50001P013C01  I25
  J20    274  DQ_B22  SCONN288_ADR50001P003C01  I47
  U1     N17  DDR1_SB_DQ22  SOCKET4677_AZIFS054P001C01  I91

M_B_CPU1_SB_DQ<23>   @S9S_MB_2U_LIB.S9S_MB_2U(SCH_1):M_B_CPU1_SB_DQ<23>
  J19    276  DQ_B23  SCONN288_ADR50001P013C01  I25
  J20    276  DQ_B23  SCONN288_ADR50001P003C01  I47
  U1     M16  DDR1_SB_DQ23  SOCKET4677_AZIFS054P001C01  I91

M_B_CPU1_SB_DQ<24>   @S9S_MB_2U_LIB.S9S_MB_2U(SCH_1):M_B_CPU1_SB_DQ<24>
  J19    133  DQ_B24  SCONN288_ADR50001P013C01  I25
  J20    133  DQ_B24  SCONN288_ADR50001P003C01  I47
  U1     C17  DDR1_SB_DQ24  SOCKET4677_AZIFS054P001C01  I91

M_B_CPU1_SB_DQ<25>   @S9S_MB_2U_LIB.S9S_MB_2U(SCH_1):M_B_CPU1_SB_DQ<25>
  J19    135  DQ_B25  SCONN288_ADR50001P013C01  I25
  J20    135  DQ_B25  SCONN288_ADR50001P003C01  I47
  U1     B16  DDR1_SB_DQ25  SOCKET4677_AZIFS054P001C01  I91

M_B_CPU1_SB_DQ<26>   @S9S_MB_2U_LIB.S9S_MB_2U(SCH_1):M_B_CPU1_SB_DQ<26>
  J19    278  DQ_B26  SCONN288_ADR50001P013C01  I25
  J20    278  DQ_B26  SCONN288_ADR50001P003C01  I47
  U1     E17  DDR1_SB_DQ26  SOCKET4677_AZIFS054P001C01  I91

M_B_CPU1_SB_DQ<27>   @S9S_MB_2U_LIB.S9S_MB_2U(SCH_1):M_B_CPU1_SB_DQ<27>
  J19    280  DQ_B27  SCONN288_ADR50001P013C01  I25
  J20    280  DQ_B27  SCONN288_ADR50001P003C01  I47
  U1     F16  DDR1_SB_DQ27  SOCKET4677_AZIFS054P001C01  I91

M_B_CPU1_SB_DQ<28>   @S9S_MB_2U_LIB.S9S_MB_2U(SCH_1):M_B_CPU1_SB_DQ<28>
  J19    140  DQ_B28  SCONN288_ADR50001P013C01  I25
  J20    140  DQ_B28  SCONN288_ADR50001P003C01  I47
  U1     C13  DDR1_SB_DQ28  SOCKET4677_AZIFS054P001C01  I91

M_B_CPU1_SB_DQ<29>   @S9S_MB_2U_LIB.S9S_MB_2U(SCH_1):M_B_CPU1_SB_DQ<29>
  J19    142  DQ_B29  SCONN288_ADR50001P013C01  I25
  J20    142  DQ_B29  SCONN288_ADR50001P003C01  I47
  U1     E13  DDR1_SB_DQ29  SOCKET4677_AZIFS054P001C01  I91

M_B_CPU1_SB_DQ<30>   @S9S_MB_2U_LIB.S9S_MB_2U(SCH_1):M_B_CPU1_SB_DQ<30>
  J19    285  DQ_B30  SCONN288_ADR50001P013C01  I25
  J20    285  DQ_B30  SCONN288_ADR50001P003C01  I47
  U1     B14  DDR1_SB_DQ30  SOCKET4677_AZIFS054P001C01  I91

M_B_CPU1_SB_DQ<31>   @S9S_MB_2U_LIB.S9S_MB_2U(SCH_1):M_B_CPU1_SB_DQ<31>
  J19    287  DQ_B31  SCONN288_ADR50001P013C01  I25
  J20    287  DQ_B31  SCONN288_ADR50001P003C01  I47
  U1     F14  DDR1_SB_DQ31  SOCKET4677_AZIFS054P001C01  I91

M_B_CPU1_SB_DQS_DN<0>   @S9S_MB_2U_LIB.S9S_MB_2U(SCH_1):M_B_CPU1_SB_DQS_DN<0>
  J19    105  DQS0_B_N  SCONN288_ADR50001P013C01  I126
  J20    105  DQS0_B_N  SCONN288_ADR50001P003C01  I124
  U1     R27  DDR1_SB_DQS_DN0  SOCKET4677_AZIFS054P001C01  I91

M_B_CPU1_SB_DQS_DN<1>   @S9S_MB_2U_LIB.S9S_MB_2U(SCH_1):M_B_CPU1_SB_DQS_DN<1>
  J19    116  DQS1_B_N  SCONN288_ADR50001P013C01  I126
  J20    116  DQS1_B_N  SCONN288_ADR50001P003C01  I124
  U1     H24  DDR1_SB_DQS_DN1  SOCKET4677_AZIFS054P001C01  I91

M_B_CPU1_SB_DQS_DN<2>   @S9S_MB_2U_LIB.S9S_MB_2U(SCH_1):M_B_CPU1_SB_DQS_DN<2>
  J19    127  DQS2_B_N  SCONN288_ADR50001P013C01  I126
  J20    127  DQS2_B_N  SCONN288_ADR50001P003C01  I124
  U1     H18  DDR1_SB_DQS_DN2  SOCKET4677_AZIFS054P001C01  I91

M_B_CPU1_SB_DQS_DN<3>   @S9S_MB_2U_LIB.S9S_MB_2U(SCH_1):M_B_CPU1_SB_DQS_DN<3>
  J19    138  DQS3_B_N  SCONN288_ADR50001P013C01  I126
  J20    138  DQS3_B_N  SCONN288_ADR50001P003C01  I124
  U1     A15  DDR1_SB_DQS_DN3  SOCKET4677_AZIFS054P001C01  I91

M_B_CPU1_SB_DQS_DN<4>   @S9S_MB_2U_LIB.S9S_MB_2U(SCH_1):M_B_CPU1_SB_DQS_DN<4>
  J19    238  DQS4_B_N  SCONN288_ADR50001P013C01  I126
  J20    238  DQS4_B_N  SCONN288_ADR50001P003C01  I124
  U1     P36  DDR1_SB_DQS_DN4  SOCKET4677_AZIFS054P001C01  I91

M_B_CPU1_SB_DQS_DN<5>   @S9S_MB_2U_LIB.S9S_MB_2U(SCH_1):M_B_CPU1_SB_DQS_DN<5>
  J19    249  DQS5_B_N  SCONN288_ADR50001P013C01  I126
  J20    249  DQS5_B_N  SCONN288_ADR50001P003C01  I124
  U1     W27  DDR1_SB_DQS_DN5  SOCKET4677_AZIFS054P001C01  I91

M_B_CPU1_SB_DQS_DN<6>   @S9S_MB_2U_LIB.S9S_MB_2U(SCH_1):M_B_CPU1_SB_DQS_DN<6>
  J19    260  DQS6_B_N  SCONN288_ADR50001P013C01  I126
  J20    260  DQS6_B_N  SCONN288_ADR50001P003C01  I124
  U1     M24  DDR1_SB_DQS_DN6  SOCKET4677_AZIFS054P001C01  I91

M_B_CPU1_SB_DQS_DN<7>   @S9S_MB_2U_LIB.S9S_MB_2U(SCH_1):M_B_CPU1_SB_DQS_DN<7>
  J19    271  DQS7_B_N  SCONN288_ADR50001P013C01  I126
  J20    271  DQS7_B_N  SCONN288_ADR50001P003C01  I124
  U1     M18  DDR1_SB_DQS_DN7  SOCKET4677_AZIFS054P001C01  I91

M_B_CPU1_SB_DQS_DN<8>   @S9S_MB_2U_LIB.S9S_MB_2U(SCH_1):M_B_CPU1_SB_DQS_DN<8>
  J19    282  DQS8_B_N  SCONN288_ADR50001P013C01  I126
  J20    282  DQS8_B_N  SCONN288_ADR50001P003C01  I124
  U1     E15  DDR1_SB_DQS_DN8  SOCKET4677_AZIFS054P001C01  I91

M_B_CPU1_SB_DQS_DN<9>   @S9S_MB_2U_LIB.S9S_MB_2U(SCH_1):M_B_CPU1_SB_DQS_DN<9>
  J19     94  DQS9_B_N  SCONN288_ADR50001P013C01  I126
  J20     94  DQS9_B_N  SCONN288_ADR50001P003C01  I124
  U1     K36  DDR1_SB_DQS_DN9  SOCKET4677_AZIFS054P001C01  I91

M_B_CPU1_SB_DQS_DP<0>   @S9S_MB_2U_LIB.S9S_MB_2U(SCH_1):M_B_CPU1_SB_DQS_DP<0>
  J19    104  DQS0_B_P  SCONN288_ADR50001P013C01  I126
  J20    104  DQS0_B_P  SCONN288_ADR50001P003C01  I124
  U1     U27  DDR1_SB_DQS_DP0  SOCKET4677_AZIFS054P001C01  I91

M_B_CPU1_SB_DQS_DP<1>   @S9S_MB_2U_LIB.S9S_MB_2U(SCH_1):M_B_CPU1_SB_DQS_DP<1>
  J19    115  DQS1_B_P  SCONN288_ADR50001P013C01  I126
  J20    115  DQS1_B_P  SCONN288_ADR50001P003C01  I124
  U1     K24  DDR1_SB_DQS_DP1  SOCKET4677_AZIFS054P001C01  I91

M_B_CPU1_SB_DQS_DP<2>   @S9S_MB_2U_LIB.S9S_MB_2U(SCH_1):M_B_CPU1_SB_DQS_DP<2>
  J19    126  DQS2_B_P  SCONN288_ADR50001P013C01  I126
  J20    126  DQS2_B_P  SCONN288_ADR50001P003C01  I124
  U1     K18  DDR1_SB_DQS_DP2  SOCKET4677_AZIFS054P001C01  I91

M_B_CPU1_SB_DQS_DP<3>   @S9S_MB_2U_LIB.S9S_MB_2U(SCH_1):M_B_CPU1_SB_DQS_DP<3>
  J19    137  DQS3_B_P  SCONN288_ADR50001P013C01  I126
  J20    137  DQS3_B_P  SCONN288_ADR50001P003C01  I124
  U1     C15  DDR1_SB_DQS_DP3  SOCKET4677_AZIFS054P001C01  I91

M_B_CPU1_SB_DQS_DP<4>   @S9S_MB_2U_LIB.S9S_MB_2U(SCH_1):M_B_CPU1_SB_DQS_DP<4>
  J19    239  DQS4_B_P  SCONN288_ADR50001P013C01  I126
  J20    239  DQS4_B_P  SCONN288_ADR50001P003C01  I124
  U1     M36  DDR1_SB_DQS_DP4  SOCKET4677_AZIFS054P001C01  I91

M_B_CPU1_SB_DQS_DP<5>   @S9S_MB_2U_LIB.S9S_MB_2U(SCH_1):M_B_CPU1_SB_DQS_DP<5>
  J19    250  DQS5_B_P  SCONN288_ADR50001P013C01  I126
  J20    250  DQS5_B_P  SCONN288_ADR50001P003C01  I124
  U1     AA27  DDR1_SB_DQS_DP5  SOCKET4677_AZIFS054P001C01  I91

M_B_CPU1_SB_DQS_DP<6>   @S9S_MB_2U_LIB.S9S_MB_2U(SCH_1):M_B_CPU1_SB_DQS_DP<6>
  J19    261  DQS6_B_P  SCONN288_ADR50001P013C01  I126
  J20    261  DQS6_B_P  SCONN288_ADR50001P003C01  I124
  U1     P24  DDR1_SB_DQS_DP6  SOCKET4677_AZIFS054P001C01  I91

M_B_CPU1_SB_DQS_DP<7>   @S9S_MB_2U_LIB.S9S_MB_2U(SCH_1):M_B_CPU1_SB_DQS_DP<7>
  J19    272  DQS7_B_P  SCONN288_ADR50001P013C01  I126
  J20    272  DQS7_B_P  SCONN288_ADR50001P003C01  I124
  U1     P18  DDR1_SB_DQS_DP7  SOCKET4677_AZIFS054P001C01  I91

M_B_CPU1_SB_DQS_DP<8>   @S9S_MB_2U_LIB.S9S_MB_2U(SCH_1):M_B_CPU1_SB_DQS_DP<8>
  J19    283  DQS8_B_P  SCONN288_ADR50001P013C01  I126
  J20    283  DQS8_B_P  SCONN288_ADR50001P003C01  I124
  U1     G15  DDR1_SB_DQS_DP8  SOCKET4677_AZIFS054P001C01  I91

M_B_CPU1_SB_DQS_DP<9>   @S9S_MB_2U_LIB.S9S_MB_2U(SCH_1):M_B_CPU1_SB_DQS_DP<9>
  J19     93  DQS9_B_P  SCONN288_ADR50001P013C01  I126
  J20     93  DQS9_B_P  SCONN288_ADR50001P003C01  I124
  U1     H36  DDR1_SB_DQS_DP9  SOCKET4677_AZIFS054P001C01  I91

M_B_CPU1_SB_PAR   @S9S_MB_2U_LIB.S9S_MB_2U(SCH_1):M_B_CPU1_SB_PAR
  J19    227  PAR_B  SCONN288_ADR50001P013C01  I25
  J20    227  PAR_B  SCONN288_ADR50001P003C01  I47
  U1     P42  DDR1_SB_PAR  SOCKET4677_AZIFS054P001C01  I91

M_B_CPU1_SB_RSP<0>   @S9S_MB_2U_LIB.S9S_MB_2U(SCH_1):M_B_CPU1_SB_RSP<0>
  J19     87  LBS||RSP_N_B  SCONN288_ADR50001P013C01  I25
  U1     AN48  DDR1_B_RSP0  SOCKET4677_AZIFS054P001C01  I91

M_B_CPU1_SB_RSP<1>   @S9S_MB_2U_LIB.S9S_MB_2U(SCH_1):M_B_CPU1_SB_RSP<1>
  J20     87  LBS||RSP_N_B  SCONN288_ADR50001P003C01  I47
  U1     AP47  DDR1_B_RSP1  SOCKET4677_AZIFS054P001C01  I91

M_C_CPU0_ALERT_N   @S9S_MB_2U_LIB.S9S_MB_2U(SCH_1):M_C_CPU0_ALERT_N
  J5      62  ALERT_N  SCONN288_ADR50001P013C01  I24
  J6      62  ALERT_N  SCONN288_ADR50001P003C01  I46
  U2     AT47  DDR2_ALERT_N  SOCKET4677_AZIFS054P001C01  I169

M_C_CPU0_CLK_DN<0>   @S9S_MB_2U_LIB.S9S_MB_2U(SCH_1):M_C_CPU0_CLK_DN<0>
  J5     218   CK_N  SCONN288_ADR50001P013C01  I24
  U2     AB49  DDR2_CLK_DN0  SOCKET4677_AZIFS054P001C01  I169

M_C_CPU0_CLK_DN<1>   @S9S_MB_2U_LIB.S9S_MB_2U(SCH_1):M_C_CPU0_CLK_DN<1>
  J6     218   CK_N  SCONN288_ADR50001P003C01  I46
  U2     AF49  DDR2_CLK_DN1  SOCKET4677_AZIFS054P001C01  I169

M_C_CPU0_CLK_DP<0>   @S9S_MB_2U_LIB.S9S_MB_2U(SCH_1):M_C_CPU0_CLK_DP<0>
  J5     217   CK_P  SCONN288_ADR50001P013C01  I24
  U2     AD49  DDR2_CLK_DP0  SOCKET4677_AZIFS054P001C01  I169

M_C_CPU0_CLK_DP<1>   @S9S_MB_2U_LIB.S9S_MB_2U(SCH_1):M_C_CPU0_CLK_DP<1>
  J6     217   CK_P  SCONN288_ADR50001P003C01  I46
  U2     AH49  DDR2_CLK_DP1  SOCKET4677_AZIFS054P001C01  I169

M_C_CPU0_SA_CA<0>   @S9S_MB_2U_LIB.S9S_MB_2U(SCH_1):M_C_CPU0_SA_CA<0>
  J5      66  CA0_A  SCONN288_ADR50001P013C01  I24
  J6      66  CA0_A  SCONN288_ADR50001P003C01  I46
  U2     R52  DDR2_SA_CA0  SOCKET4677_AZIFS054P001C01  I169

M_C_CPU0_SA_CA<1>   @S9S_MB_2U_LIB.S9S_MB_2U(SCH_1):M_C_CPU0_SA_CA<1>
  J5     211  CA1_A  SCONN288_ADR50001P013C01  I24
  J6     211  CA1_A  SCONN288_ADR50001P003C01  I46
  U2     AA52  DDR2_SA_CA1  SOCKET4677_AZIFS054P001C01  I169

M_C_CPU0_SA_CA<2>   @S9S_MB_2U_LIB.S9S_MB_2U(SCH_1):M_C_CPU0_SA_CA<2>
  J5      68  CA2_A  SCONN288_ADR50001P013C01  I24
  J6      68  CA2_A  SCONN288_ADR50001P003C01  I46
  U2     T51  DDR2_SA_CA2  SOCKET4677_AZIFS054P001C01  I169

M_C_CPU0_SA_CA<3>   @S9S_MB_2U_LIB.S9S_MB_2U(SCH_1):M_C_CPU0_SA_CA<3>
  J5     213  CA3_A  SCONN288_ADR50001P013C01  I24
  J6     213  CA3_A  SCONN288_ADR50001P003C01  I46
  U2     Y51  DDR2_SA_CA3  SOCKET4677_AZIFS054P001C01  I169

M_C_CPU0_SA_CA<4>   @S9S_MB_2U_LIB.S9S_MB_2U(SCH_1):M_C_CPU0_SA_CA<4>
  J5      70  CA4_A  SCONN288_ADR50001P013C01  I24
  J6      70  CA4_A  SCONN288_ADR50001P003C01  I46
  U2     U50  DDR2_SA_CA4  SOCKET4677_AZIFS054P001C01  I169

M_C_CPU0_SA_CA<5>   @S9S_MB_2U_LIB.S9S_MB_2U(SCH_1):M_C_CPU0_SA_CA<5>
  J5     215  CA5_A  SCONN288_ADR50001P013C01  I24
  J6     215  CA5_A  SCONN288_ADR50001P003C01  I46
  U2     W50  DDR2_SA_CA5  SOCKET4677_AZIFS054P001C01  I169

M_C_CPU0_SA_CA<6>   @S9S_MB_2U_LIB.S9S_MB_2U(SCH_1):M_C_CPU0_SA_CA<6>
  J5      72  CA6_A  SCONN288_ADR50001P013C01  I24
  J6      72  CA6_A  SCONN288_ADR50001P003C01  I46
  U2     U48  DDR2_SA_CA6  SOCKET4677_AZIFS054P001C01  I169

M_C_CPU0_SA_CB<0>   @S9S_MB_2U_LIB.S9S_MB_2U(SCH_1):M_C_CPU0_SA_CB<0>
  J5      51  CB_A0  SCONN288_ADR50001P013C01  I24
  J6      51  CB_A0  SCONN288_ADR50001P003C01  I46
  U2     AD57  DDR2_SA_ECC0  SOCKET4677_AZIFS054P001C01  I169

M_C_CPU0_SA_CB<1>   @S9S_MB_2U_LIB.S9S_MB_2U(SCH_1):M_C_CPU0_SA_CB<1>
  J5      53  CB_A1  SCONN288_ADR50001P013C01  I24
  J6      53  CB_A1  SCONN288_ADR50001P003C01  I46
  U2     AC56  DDR2_SA_ECC1  SOCKET4677_AZIFS054P001C01  I169

M_C_CPU0_SA_CB<2>   @S9S_MB_2U_LIB.S9S_MB_2U(SCH_1):M_C_CPU0_SA_CB<2>
  J5     196  CB_A2  SCONN288_ADR50001P013C01  I24
  J6     196  CB_A2  SCONN288_ADR50001P003C01  I46
  U2     AF57  DDR2_SA_ECC2  SOCKET4677_AZIFS054P001C01  I169

M_C_CPU0_SA_CB<3>   @S9S_MB_2U_LIB.S9S_MB_2U(SCH_1):M_C_CPU0_SA_CB<3>
  J5     198  CB_A3  SCONN288_ADR50001P013C01  I24
  J6     198  CB_A3  SCONN288_ADR50001P003C01  I46
  U2     AG56  DDR2_SA_ECC3  SOCKET4677_AZIFS054P001C01  I169

M_C_CPU0_SA_CB<4>   @S9S_MB_2U_LIB.S9S_MB_2U(SCH_1):M_C_CPU0_SA_CB<4>
  J5      58  CB_A4  SCONN288_ADR50001P013C01  I24
  J6      58  CB_A4  SCONN288_ADR50001P003C01  I46
  U2     AC54  DDR2_SA_ECC4  SOCKET4677_AZIFS054P001C01  I169

M_C_CPU0_SA_CB<5>   @S9S_MB_2U_LIB.S9S_MB_2U(SCH_1):M_C_CPU0_SA_CB<5>
  J5      60  CB_A5  SCONN288_ADR50001P013C01  I24
  J6      60  CB_A5  SCONN288_ADR50001P003C01  I46
  U2     AD53  DDR2_SA_ECC5  SOCKET4677_AZIFS054P001C01  I169

M_C_CPU0_SA_CB<6>   @S9S_MB_2U_LIB.S9S_MB_2U(SCH_1):M_C_CPU0_SA_CB<6>
  J5     203  CB_A6  SCONN288_ADR50001P013C01  I24
  J6     203  CB_A6  SCONN288_ADR50001P003C01  I46
  U2     AG54  DDR2_SA_ECC6  SOCKET4677_AZIFS054P001C01  I169

M_C_CPU0_SA_CB<7>   @S9S_MB_2U_LIB.S9S_MB_2U(SCH_1):M_C_CPU0_SA_CB<7>
  J5     205  CB_A7  SCONN288_ADR50001P013C01  I24
  J6     205  CB_A7  SCONN288_ADR50001P003C01  I46
  U2     AF53  DDR2_SA_ECC7  SOCKET4677_AZIFS054P001C01  I169

M_C_CPU0_SA_CS_N<0>   @S9S_MB_2U_LIB.S9S_MB_2U(SCH_1):M_C_CPU0_SA_CS_N<0>
  J5      64  CS0_N_A  SCONN288_ADR50001P013C01  I24
  U2     U54  DDR2_SA_CS0_N  SOCKET4677_AZIFS054P001C01  I169

M_C_CPU0_SA_CS_N<1>   @S9S_MB_2U_LIB.S9S_MB_2U(SCH_1):M_C_CPU0_SA_CS_N<1>
  J5     209  CS1_N_A  SCONN288_ADR50001P013C01  I24
  U2     T53  DDR2_SA_CS1_N  SOCKET4677_AZIFS054P001C01  I169

M_C_CPU0_SA_CS_N<2>   @S9S_MB_2U_LIB.S9S_MB_2U(SCH_1):M_C_CPU0_SA_CS_N<2>
  J6      64  CS0_N_A  SCONN288_ADR50001P003C01  I46
  U2     W54  DDR2_SA_CS2_N  SOCKET4677_AZIFS054P001C01  I169

M_C_CPU0_SA_CS_N<3>   @S9S_MB_2U_LIB.S9S_MB_2U(SCH_1):M_C_CPU0_SA_CS_N<3>
  J6     209  CS1_N_A  SCONN288_ADR50001P003C01  I46
  U2     Y53  DDR2_SA_CS3_N  SOCKET4677_AZIFS054P001C01  I169

M_C_CPU0_SA_DQ<0>   @S9S_MB_2U_LIB.S9S_MB_2U(SCH_1):M_C_CPU0_SA_DQ<0>
  J5       7  DQ_A0  SCONN288_ADR50001P013C01  I24
  J6       7  DQ_A0  SCONN288_ADR50001P003C01  I46
  U2     U78  DDR2_SA_DQ0  SOCKET4677_AZIFS054P001C01  I169

M_C_CPU0_SA_DQ<1>   @S9S_MB_2U_LIB.S9S_MB_2U(SCH_1):M_C_CPU0_SA_DQ<1>
  J5       9  DQ_A1  SCONN288_ADR50001P013C01  I24
  J6       9  DQ_A1  SCONN288_ADR50001P003C01  I46
  U2     T77  DDR2_SA_DQ1  SOCKET4677_AZIFS054P001C01  I169

M_C_CPU0_SA_DQ<2>   @S9S_MB_2U_LIB.S9S_MB_2U(SCH_1):M_C_CPU0_SA_DQ<2>
  J5     152  DQ_A2  SCONN288_ADR50001P013C01  I24
  J6     152  DQ_A2  SCONN288_ADR50001P003C01  I46
  U2     W78  DDR2_SA_DQ2  SOCKET4677_AZIFS054P001C01  I169

M_C_CPU0_SA_DQ<3>   @S9S_MB_2U_LIB.S9S_MB_2U(SCH_1):M_C_CPU0_SA_DQ<3>
  J5     154  DQ_A3  SCONN288_ADR50001P013C01  I24
  J6     154  DQ_A3  SCONN288_ADR50001P003C01  I46
  U2     Y77  DDR2_SA_DQ3  SOCKET4677_AZIFS054P001C01  I169

M_C_CPU0_SA_DQ<4>   @S9S_MB_2U_LIB.S9S_MB_2U(SCH_1):M_C_CPU0_SA_DQ<4>
  J5      14  DQ_A4  SCONN288_ADR50001P013C01  I24
  J6      14  DQ_A4  SCONN288_ADR50001P003C01  I46
  U2     T75  DDR2_SA_DQ4  SOCKET4677_AZIFS054P001C01  I169

M_C_CPU0_SA_DQ<5>   @S9S_MB_2U_LIB.S9S_MB_2U(SCH_1):M_C_CPU0_SA_DQ<5>
  J5      16  DQ_A5  SCONN288_ADR50001P013C01  I24
  J6      16  DQ_A5  SCONN288_ADR50001P003C01  I46
  U2     U74  DDR2_SA_DQ5  SOCKET4677_AZIFS054P001C01  I169

M_C_CPU0_SA_DQ<6>   @S9S_MB_2U_LIB.S9S_MB_2U(SCH_1):M_C_CPU0_SA_DQ<6>
  J5     159  DQ_A6  SCONN288_ADR50001P013C01  I24
  J6     159  DQ_A6  SCONN288_ADR50001P003C01  I46
  U2     Y75  DDR2_SA_DQ6  SOCKET4677_AZIFS054P001C01  I169

M_C_CPU0_SA_DQ<7>   @S9S_MB_2U_LIB.S9S_MB_2U(SCH_1):M_C_CPU0_SA_DQ<7>
  J5     161  DQ_A7  SCONN288_ADR50001P013C01  I24
  J6     161  DQ_A7  SCONN288_ADR50001P003C01  I46
  U2     W74  DDR2_SA_DQ7  SOCKET4677_AZIFS054P001C01  I169

M_C_CPU0_SA_DQ<8>   @S9S_MB_2U_LIB.S9S_MB_2U(SCH_1):M_C_CPU0_SA_DQ<8>
  J5      18  DQ_A8  SCONN288_ADR50001P013C01  I24
  J6      18  DQ_A8  SCONN288_ADR50001P003C01  I46
  U2     AD69  DDR2_SA_DQ8  SOCKET4677_AZIFS054P001C01  I169

M_C_CPU0_SA_DQ<9>   @S9S_MB_2U_LIB.S9S_MB_2U(SCH_1):M_C_CPU0_SA_DQ<9>
  J5      20  DQ_A9  SCONN288_ADR50001P013C01  I24
  J6      20  DQ_A9  SCONN288_ADR50001P003C01  I46
  U2     AC68  DDR2_SA_DQ9  SOCKET4677_AZIFS054P001C01  I169

M_C_CPU0_SA_DQ<10>   @S9S_MB_2U_LIB.S9S_MB_2U(SCH_1):M_C_CPU0_SA_DQ<10>
  J5     163  DQ_A10  SCONN288_ADR50001P013C01  I24
  J6     163  DQ_A10  SCONN288_ADR50001P003C01  I46
  U2     AF69  DDR2_SA_DQ10  SOCKET4677_AZIFS054P001C01  I169

M_C_CPU0_SA_DQ<11>   @S9S_MB_2U_LIB.S9S_MB_2U(SCH_1):M_C_CPU0_SA_DQ<11>
  J5     165  DQ_A11  SCONN288_ADR50001P013C01  I24
  J6     165  DQ_A11  SCONN288_ADR50001P003C01  I46
  U2     AG68  DDR2_SA_DQ11  SOCKET4677_AZIFS054P001C01  I169

M_C_CPU0_SA_DQ<12>   @S9S_MB_2U_LIB.S9S_MB_2U(SCH_1):M_C_CPU0_SA_DQ<12>
  J5      25  DQ_A12  SCONN288_ADR50001P013C01  I24
  J6      25  DQ_A12  SCONN288_ADR50001P003C01  I46
  U2     AC66  DDR2_SA_DQ12  SOCKET4677_AZIFS054P001C01  I169

M_C_CPU0_SA_DQ<13>   @S9S_MB_2U_LIB.S9S_MB_2U(SCH_1):M_C_CPU0_SA_DQ<13>
  J5      27  DQ_A13  SCONN288_ADR50001P013C01  I24
  J6      27  DQ_A13  SCONN288_ADR50001P003C01  I46
  U2     AD65  DDR2_SA_DQ13  SOCKET4677_AZIFS054P001C01  I169

M_C_CPU0_SA_DQ<14>   @S9S_MB_2U_LIB.S9S_MB_2U(SCH_1):M_C_CPU0_SA_DQ<14>
  J5     170  DQ_A14  SCONN288_ADR50001P013C01  I24
  J6     170  DQ_A14  SCONN288_ADR50001P003C01  I46
  U2     AG66  DDR2_SA_DQ14  SOCKET4677_AZIFS054P001C01  I169

M_C_CPU0_SA_DQ<15>   @S9S_MB_2U_LIB.S9S_MB_2U(SCH_1):M_C_CPU0_SA_DQ<15>
  J5     172  DQ_A15  SCONN288_ADR50001P013C01  I24
  J6     172  DQ_A15  SCONN288_ADR50001P003C01  I46
  U2     AF65  DDR2_SA_DQ15  SOCKET4677_AZIFS054P001C01  I169

M_C_CPU0_SA_DQ<16>   @S9S_MB_2U_LIB.S9S_MB_2U(SCH_1):M_C_CPU0_SA_DQ<16>
  J5      29  DQ_A16  SCONN288_ADR50001P013C01  I24
  J6      29  DQ_A16  SCONN288_ADR50001P003C01  I46
  U2     U66  DDR2_SA_DQ16  SOCKET4677_AZIFS054P001C01  I169

M_C_CPU0_SA_DQ<17>   @S9S_MB_2U_LIB.S9S_MB_2U(SCH_1):M_C_CPU0_SA_DQ<17>
  J5      31  DQ_A17  SCONN288_ADR50001P013C01  I24
  J6      31  DQ_A17  SCONN288_ADR50001P003C01  I46
  U2     T65  DDR2_SA_DQ17  SOCKET4677_AZIFS054P001C01  I169

M_C_CPU0_SA_DQ<18>   @S9S_MB_2U_LIB.S9S_MB_2U(SCH_1):M_C_CPU0_SA_DQ<18>
  J5     174  DQ_A18  SCONN288_ADR50001P013C01  I24
  J6     174  DQ_A18  SCONN288_ADR50001P003C01  I46
  U2     W66  DDR2_SA_DQ18  SOCKET4677_AZIFS054P001C01  I169

M_C_CPU0_SA_DQ<19>   @S9S_MB_2U_LIB.S9S_MB_2U(SCH_1):M_C_CPU0_SA_DQ<19>
  J5     176  DQ_A19  SCONN288_ADR50001P013C01  I24
  J6     176  DQ_A19  SCONN288_ADR50001P003C01  I46
  U2     Y65  DDR2_SA_DQ19  SOCKET4677_AZIFS054P001C01  I169

M_C_CPU0_SA_DQ<20>   @S9S_MB_2U_LIB.S9S_MB_2U(SCH_1):M_C_CPU0_SA_DQ<20>
  J5      36  DQ_A20  SCONN288_ADR50001P013C01  I24
  J6      36  DQ_A20  SCONN288_ADR50001P003C01  I46
  U2     T63  DDR2_SA_DQ20  SOCKET4677_AZIFS054P001C01  I169

M_C_CPU0_SA_DQ<21>   @S9S_MB_2U_LIB.S9S_MB_2U(SCH_1):M_C_CPU0_SA_DQ<21>
  J5      38  DQ_A21  SCONN288_ADR50001P013C01  I24
  J6      38  DQ_A21  SCONN288_ADR50001P003C01  I46
  U2     U62  DDR2_SA_DQ21  SOCKET4677_AZIFS054P001C01  I169

M_C_CPU0_SA_DQ<22>   @S9S_MB_2U_LIB.S9S_MB_2U(SCH_1):M_C_CPU0_SA_DQ<22>
  J5     181  DQ_A22  SCONN288_ADR50001P013C01  I24
  J6     181  DQ_A22  SCONN288_ADR50001P003C01  I46
  U2     Y63  DDR2_SA_DQ22  SOCKET4677_AZIFS054P001C01  I169

M_C_CPU0_SA_DQ<23>   @S9S_MB_2U_LIB.S9S_MB_2U(SCH_1):M_C_CPU0_SA_DQ<23>
  J5     183  DQ_A23  SCONN288_ADR50001P013C01  I24
  J6     183  DQ_A23  SCONN288_ADR50001P003C01  I46
  U2     W62  DDR2_SA_DQ23  SOCKET4677_AZIFS054P001C01  I169

M_C_CPU0_SA_DQ<24>   @S9S_MB_2U_LIB.S9S_MB_2U(SCH_1):M_C_CPU0_SA_DQ<24>
  J5      40  DQ_A24  SCONN288_ADR50001P013C01  I24
  J6      40  DQ_A24  SCONN288_ADR50001P003C01  I46
  U2     AD63  DDR2_SA_DQ24  SOCKET4677_AZIFS054P001C01  I169

M_C_CPU0_SA_DQ<25>   @S9S_MB_2U_LIB.S9S_MB_2U(SCH_1):M_C_CPU0_SA_DQ<25>
  J5      42  DQ_A25  SCONN288_ADR50001P013C01  I24
  J6      42  DQ_A25  SCONN288_ADR50001P003C01  I46
  U2     AC62  DDR2_SA_DQ25  SOCKET4677_AZIFS054P001C01  I169

M_C_CPU0_SA_DQ<26>   @S9S_MB_2U_LIB.S9S_MB_2U(SCH_1):M_C_CPU0_SA_DQ<26>
  J5     185  DQ_A26  SCONN288_ADR50001P013C01  I24
  J6     185  DQ_A26  SCONN288_ADR50001P003C01  I46
  U2     AF63  DDR2_SA_DQ26  SOCKET4677_AZIFS054P001C01  I169

M_C_CPU0_SA_DQ<27>   @S9S_MB_2U_LIB.S9S_MB_2U(SCH_1):M_C_CPU0_SA_DQ<27>
  J5     187  DQ_A27  SCONN288_ADR50001P013C01  I24
  J6     187  DQ_A27  SCONN288_ADR50001P003C01  I46
  U2     AG62  DDR2_SA_DQ27  SOCKET4677_AZIFS054P001C01  I169

M_C_CPU0_SA_DQ<28>   @S9S_MB_2U_LIB.S9S_MB_2U(SCH_1):M_C_CPU0_SA_DQ<28>
  J5      47  DQ_A28  SCONN288_ADR50001P013C01  I24
  J6      47  DQ_A28  SCONN288_ADR50001P003C01  I46
  U2     AC60  DDR2_SA_DQ28  SOCKET4677_AZIFS054P001C01  I169

M_C_CPU0_SA_DQ<29>   @S9S_MB_2U_LIB.S9S_MB_2U(SCH_1):M_C_CPU0_SA_DQ<29>
  J5      49  DQ_A29  SCONN288_ADR50001P013C01  I24
  J6      49  DQ_A29  SCONN288_ADR50001P003C01  I46
  U2     AD59  DDR2_SA_DQ29  SOCKET4677_AZIFS054P001C01  I169

M_C_CPU0_SA_DQ<30>   @S9S_MB_2U_LIB.S9S_MB_2U(SCH_1):M_C_CPU0_SA_DQ<30>
  J5     192  DQ_A30  SCONN288_ADR50001P013C01  I24
  J6     192  DQ_A30  SCONN288_ADR50001P003C01  I46
  U2     AG60  DDR2_SA_DQ30  SOCKET4677_AZIFS054P001C01  I169

M_C_CPU0_SA_DQ<31>   @S9S_MB_2U_LIB.S9S_MB_2U(SCH_1):M_C_CPU0_SA_DQ<31>
  J5     194  DQ_A31  SCONN288_ADR50001P013C01  I24
  J6     194  DQ_A31  SCONN288_ADR50001P003C01  I46
  U2     AF59  DDR2_SA_DQ31  SOCKET4677_AZIFS054P001C01  I169

M_C_CPU0_SA_DQS_DN<0>   @S9S_MB_2U_LIB.S9S_MB_2U(SCH_1):M_C_CPU0_SA_DQS_DN<0>
  J5      12  DQS0_A_N  SCONN288_ADR50001P013C01  I125
  J6      12  DQS0_A_N  SCONN288_ADR50001P003C01  I123
  U2     R76  DDR2_SA_DQS_DN0  SOCKET4677_AZIFS054P001C01  I169

M_C_CPU0_SA_DQS_DN<1>   @S9S_MB_2U_LIB.S9S_MB_2U(SCH_1):M_C_CPU0_SA_DQS_DN<1>
  J5      23  DQS1_A_N  SCONN288_ADR50001P013C01  I125
  J6      23  DQS1_A_N  SCONN288_ADR50001P003C01  I123
  U2     AB67  DDR2_SA_DQS_DN1  SOCKET4677_AZIFS054P001C01  I169

M_C_CPU0_SA_DQS_DN<2>   @S9S_MB_2U_LIB.S9S_MB_2U(SCH_1):M_C_CPU0_SA_DQS_DN<2>
  J5      34  DQS2_A_N  SCONN288_ADR50001P013C01  I125
  J6      34  DQS2_A_N  SCONN288_ADR50001P003C01  I123
  U2     R64  DDR2_SA_DQS_DN2  SOCKET4677_AZIFS054P001C01  I169

M_C_CPU0_SA_DQS_DN<3>   @S9S_MB_2U_LIB.S9S_MB_2U(SCH_1):M_C_CPU0_SA_DQS_DN<3>
  J5      45  DQS3_A_N  SCONN288_ADR50001P013C01  I125
  J6      45  DQS3_A_N  SCONN288_ADR50001P003C01  I123
  U2     AB61  DDR2_SA_DQS_DN3  SOCKET4677_AZIFS054P001C01  I169

M_C_CPU0_SA_DQS_DN<4>   @S9S_MB_2U_LIB.S9S_MB_2U(SCH_1):M_C_CPU0_SA_DQS_DN<4>
  J5      56  DQS4_A_N  SCONN288_ADR50001P013C01  I125
  J6      56  DQS4_A_N  SCONN288_ADR50001P003C01  I123
  U2     AD55  DDR2_SA_DQS_DN4  SOCKET4677_AZIFS054P001C01  I169

M_C_CPU0_SA_DQS_DN<5>   @S9S_MB_2U_LIB.S9S_MB_2U(SCH_1):M_C_CPU0_SA_DQS_DN<5>
  J5     156  DQS5_A_N  SCONN288_ADR50001P013C01  I125
  J6     156  DQS5_A_N  SCONN288_ADR50001P003C01  I123
  U2     W76  DDR2_SA_DQS_DN5  SOCKET4677_AZIFS054P001C01  I169

M_C_CPU0_SA_DQS_DN<6>   @S9S_MB_2U_LIB.S9S_MB_2U(SCH_1):M_C_CPU0_SA_DQS_DN<6>
  J5     167  DQS6_A_N  SCONN288_ADR50001P013C01  I125
  J6     167  DQS6_A_N  SCONN288_ADR50001P003C01  I123
  U2     AH67  DDR2_SA_DQS_DN6  SOCKET4677_AZIFS054P001C01  I169

M_C_CPU0_SA_DQS_DN<7>   @S9S_MB_2U_LIB.S9S_MB_2U(SCH_1):M_C_CPU0_SA_DQS_DN<7>
  J5     178  DQS7_A_N  SCONN288_ADR50001P013C01  I125
  J6     178  DQS7_A_N  SCONN288_ADR50001P003C01  I123
  U2     AA64  DDR2_SA_DQS_DN7  SOCKET4677_AZIFS054P001C01  I169

M_C_CPU0_SA_DQS_DN<8>   @S9S_MB_2U_LIB.S9S_MB_2U(SCH_1):M_C_CPU0_SA_DQS_DN<8>
  J5     189  DQS8_A_N  SCONN288_ADR50001P013C01  I125
  J6     189  DQS8_A_N  SCONN288_ADR50001P003C01  I123
  U2     AF61  DDR2_SA_DQS_DN8  SOCKET4677_AZIFS054P001C01  I169

M_C_CPU0_SA_DQS_DN<9>   @S9S_MB_2U_LIB.S9S_MB_2U(SCH_1):M_C_CPU0_SA_DQS_DN<9>
  J5     200  DQS9_A_N  SCONN288_ADR50001P013C01  I125
  J6     200  DQS9_A_N  SCONN288_ADR50001P003C01  I123
  U2     AH55  DDR2_SA_DQS_DN9  SOCKET4677_AZIFS054P001C01  I169

M_C_CPU0_SA_DQS_DP<0>   @S9S_MB_2U_LIB.S9S_MB_2U(SCH_1):M_C_CPU0_SA_DQS_DP<0>
  J5      11  DQS0_A_P  SCONN288_ADR50001P013C01  I125
  J6      11  DQS0_A_P  SCONN288_ADR50001P003C01  I123
  U2     U76  DDR2_SA_DQS_DP0  SOCKET4677_AZIFS054P001C01  I169

M_C_CPU0_SA_DQS_DP<1>   @S9S_MB_2U_LIB.S9S_MB_2U(SCH_1):M_C_CPU0_SA_DQS_DP<1>
  J5      22  DQS1_A_P  SCONN288_ADR50001P013C01  I125
  J6      22  DQS1_A_P  SCONN288_ADR50001P003C01  I123
  U2     AD67  DDR2_SA_DQS_DP1  SOCKET4677_AZIFS054P001C01  I169

M_C_CPU0_SA_DQS_DP<2>   @S9S_MB_2U_LIB.S9S_MB_2U(SCH_1):M_C_CPU0_SA_DQS_DP<2>
  J5      33  DQS2_A_P  SCONN288_ADR50001P013C01  I125
  J6      33  DQS2_A_P  SCONN288_ADR50001P003C01  I123
  U2     U64  DDR2_SA_DQS_DP2  SOCKET4677_AZIFS054P001C01  I169

M_C_CPU0_SA_DQS_DP<3>   @S9S_MB_2U_LIB.S9S_MB_2U(SCH_1):M_C_CPU0_SA_DQS_DP<3>
  J5      44  DQS3_A_P  SCONN288_ADR50001P013C01  I125
  J6      44  DQS3_A_P  SCONN288_ADR50001P003C01  I123
  U2     AD61  DDR2_SA_DQS_DP3  SOCKET4677_AZIFS054P001C01  I169

M_C_CPU0_SA_DQS_DP<4>   @S9S_MB_2U_LIB.S9S_MB_2U(SCH_1):M_C_CPU0_SA_DQS_DP<4>
  J5      55  DQS4_A_P  SCONN288_ADR50001P013C01  I125
  J6      55  DQS4_A_P  SCONN288_ADR50001P003C01  I123
  U2     AB55  DDR2_SA_DQS_DP4  SOCKET4677_AZIFS054P001C01  I169

M_C_CPU0_SA_DQS_DP<5>   @S9S_MB_2U_LIB.S9S_MB_2U(SCH_1):M_C_CPU0_SA_DQS_DP<5>
  J5     157  DQS5_A_P  SCONN288_ADR50001P013C01  I125
  J6     157  DQS5_A_P  SCONN288_ADR50001P003C01  I123
  U2     AA76  DDR2_SA_DQS_DP5  SOCKET4677_AZIFS054P001C01  I169

M_C_CPU0_SA_DQS_DP<6>   @S9S_MB_2U_LIB.S9S_MB_2U(SCH_1):M_C_CPU0_SA_DQS_DP<6>
  J5     168  DQS6_A_P  SCONN288_ADR50001P013C01  I125
  J6     168  DQS6_A_P  SCONN288_ADR50001P003C01  I123
  U2     AF67  DDR2_SA_DQS_DP6  SOCKET4677_AZIFS054P001C01  I169

M_C_CPU0_SA_DQS_DP<7>   @S9S_MB_2U_LIB.S9S_MB_2U(SCH_1):M_C_CPU0_SA_DQS_DP<7>
  J5     179  DQS7_A_P  SCONN288_ADR50001P013C01  I125
  J6     179  DQS7_A_P  SCONN288_ADR50001P003C01  I123
  U2     W64  DDR2_SA_DQS_DP7  SOCKET4677_AZIFS054P001C01  I169

M_C_CPU0_SA_DQS_DP<8>   @S9S_MB_2U_LIB.S9S_MB_2U(SCH_1):M_C_CPU0_SA_DQS_DP<8>
  J5     190  DQS8_A_P  SCONN288_ADR50001P013C01  I125
  J6     190  DQS8_A_P  SCONN288_ADR50001P003C01  I123
  U2     AH61  DDR2_SA_DQS_DP8  SOCKET4677_AZIFS054P001C01  I169

M_C_CPU0_SA_DQS_DP<9>   @S9S_MB_2U_LIB.S9S_MB_2U(SCH_1):M_C_CPU0_SA_DQS_DP<9>
  J5     201  DQS9_A_P  SCONN288_ADR50001P013C01  I125
  J6     201  DQS9_A_P  SCONN288_ADR50001P003C01  I123
  U2     AF55  DDR2_SA_DQS_DP9  SOCKET4677_AZIFS054P001C01  I169

M_C_CPU0_SA_PAR   @S9S_MB_2U_LIB.S9S_MB_2U(SCH_1):M_C_CPU0_SA_PAR
  J5      74  PAR_A  SCONN288_ADR50001P013C01  I24
  J6      74  PAR_A  SCONN288_ADR50001P003C01  I46
  U2     T47  DDR2_SA_PAR  SOCKET4677_AZIFS054P001C01  I169

M_C_CPU0_SA_RSP<0>   @S9S_MB_2U_LIB.S9S_MB_2U(SCH_1):M_C_CPU0_SA_RSP<0>
  J5      86  LBD||RSP_N_A  SCONN288_ADR50001P013C01  I24
  U2     AC48  DDR2_A_RSP0  SOCKET4677_AZIFS054P001C01  I169

M_C_CPU0_SA_RSP<1>   @S9S_MB_2U_LIB.S9S_MB_2U(SCH_1):M_C_CPU0_SA_RSP<1>
  J6      86  LBD||RSP_N_A  SCONN288_ADR50001P003C01  I46
  U2     AD47  DDR2_A_RSP1  SOCKET4677_AZIFS054P001C01  I169

M_C_CPU0_SB_CA<0>   @S9S_MB_2U_LIB.S9S_MB_2U(SCH_1):M_C_CPU0_SB_CA<0>
  J5      76  CA0_B  SCONN288_ADR50001P013C01  I24
  J6      76  CA0_B  SCONN288_ADR50001P003C01  I46
  U2     W48  DDR2_SB_CA0  SOCKET4677_AZIFS054P001C01  I169

M_C_CPU0_SB_CA<1>   @S9S_MB_2U_LIB.S9S_MB_2U(SCH_1):M_C_CPU0_SB_CA<1>
  J5     221  CA1_B  SCONN288_ADR50001P013C01  I24
  J6     221  CA1_B  SCONN288_ADR50001P003C01  I46
  U2     Y47  DDR2_SB_CA1  SOCKET4677_AZIFS054P001C01  I169

M_C_CPU0_SB_CA<2>   @S9S_MB_2U_LIB.S9S_MB_2U(SCH_1):M_C_CPU0_SB_CA<2>
  J5      78  CA2_B  SCONN288_ADR50001P013C01  I24
  J6      78  CA2_B  SCONN288_ADR50001P003C01  I46
  U2     U41  DDR2_SB_CA2  SOCKET4677_AZIFS054P001C01  I169

M_C_CPU0_SB_CA<3>   @S9S_MB_2U_LIB.S9S_MB_2U(SCH_1):M_C_CPU0_SB_CA<3>
  J5     223  CA3_B  SCONN288_ADR50001P013C01  I24
  J6     223  CA3_B  SCONN288_ADR50001P003C01  I46
  U2     W41  DDR2_SB_CA3  SOCKET4677_AZIFS054P001C01  I169

M_C_CPU0_SB_CA<4>   @S9S_MB_2U_LIB.S9S_MB_2U(SCH_1):M_C_CPU0_SB_CA<4>
  J5      80  CA4_B  SCONN288_ADR50001P013C01  I24
  J6      80  CA4_B  SCONN288_ADR50001P003C01  I46
  U2     T40  DDR2_SB_CA4  SOCKET4677_AZIFS054P001C01  I169

M_C_CPU0_SB_CA<5>   @S9S_MB_2U_LIB.S9S_MB_2U(SCH_1):M_C_CPU0_SB_CA<5>
  J5     225  CA5_B  SCONN288_ADR50001P013C01  I24
  J6     225  CA5_B  SCONN288_ADR50001P003C01  I46
  U2     Y40  DDR2_SB_CA5  SOCKET4677_AZIFS054P001C01  I169

M_C_CPU0_SB_CA<6>   @S9S_MB_2U_LIB.S9S_MB_2U(SCH_1):M_C_CPU0_SB_CA<6>
  J5      82  CA6_B  SCONN288_ADR50001P013C01  I24
  J6      82  CA6_B  SCONN288_ADR50001P003C01  I46
  U2     R39  DDR2_SB_CA6  SOCKET4677_AZIFS054P001C01  I169

M_C_CPU0_SB_CB<0>   @S9S_MB_2U_LIB.S9S_MB_2U(SCH_1):M_C_CPU0_SB_CB<0>
  J5      96  CB_B0  SCONN288_ADR50001P013C01  I24
  J6      96  CB_B0  SCONN288_ADR50001P003C01  I46
  U2     T32  DDR2_SB_ECC0  SOCKET4677_AZIFS054P001C01  I169

M_C_CPU0_SB_CB<1>   @S9S_MB_2U_LIB.S9S_MB_2U(SCH_1):M_C_CPU0_SB_CB<1>
  J5      98  CB_B1  SCONN288_ADR50001P013C01  I24
  J6      98  CB_B1  SCONN288_ADR50001P003C01  I46
  U2     U31  DDR2_SB_ECC1  SOCKET4677_AZIFS054P001C01  I169

M_C_CPU0_SB_CB<2>   @S9S_MB_2U_LIB.S9S_MB_2U(SCH_1):M_C_CPU0_SB_CB<2>
  J5     241  CB_B2  SCONN288_ADR50001P013C01  I24
  J6     241  CB_B2  SCONN288_ADR50001P003C01  I46
  U2     Y32  DDR2_SB_ECC2  SOCKET4677_AZIFS054P001C01  I169

M_C_CPU0_SB_CB<3>   @S9S_MB_2U_LIB.S9S_MB_2U(SCH_1):M_C_CPU0_SB_CB<3>
  J5     243  CB_B3  SCONN288_ADR50001P013C01  I24
  J6     243  CB_B3  SCONN288_ADR50001P003C01  I46
  U2     W31  DDR2_SB_ECC3  SOCKET4677_AZIFS054P001C01  I169

M_C_CPU0_SB_CB<4>   @S9S_MB_2U_LIB.S9S_MB_2U(SCH_1):M_C_CPU0_SB_CB<4>
  J5      89  CB_B4  SCONN288_ADR50001P013C01  I24
  J6      89  CB_B4  SCONN288_ADR50001P003C01  I46
  U2     U35  DDR2_SB_ECC4  SOCKET4677_AZIFS054P001C01  I169

M_C_CPU0_SB_CB<5>   @S9S_MB_2U_LIB.S9S_MB_2U(SCH_1):M_C_CPU0_SB_CB<5>
  J5      91  CB_B5  SCONN288_ADR50001P013C01  I24
  J6      91  CB_B5  SCONN288_ADR50001P003C01  I46
  U2     T34  DDR2_SB_ECC5  SOCKET4677_AZIFS054P001C01  I169

M_C_CPU0_SB_CB<6>   @S9S_MB_2U_LIB.S9S_MB_2U(SCH_1):M_C_CPU0_SB_CB<6>
  J5     234  CB_B6  SCONN288_ADR50001P013C01  I24
  J6     234  CB_B6  SCONN288_ADR50001P003C01  I46
  U2     W35  DDR2_SB_ECC6  SOCKET4677_AZIFS054P001C01  I169

M_C_CPU0_SB_CB<7>   @S9S_MB_2U_LIB.S9S_MB_2U(SCH_1):M_C_CPU0_SB_CB<7>
  J5     236  CB_B7  SCONN288_ADR50001P013C01  I24
  J6     236  CB_B7  SCONN288_ADR50001P003C01  I46
  U2     Y34  DDR2_SB_ECC7  SOCKET4677_AZIFS054P001C01  I169

M_C_CPU0_SB_CS_N<0>   @S9S_MB_2U_LIB.S9S_MB_2U(SCH_1):M_C_CPU0_SB_CS_N<0>
  J5      84  CS0_N_B  SCONN288_ADR50001P013C01  I24
  U2     T38  DDR2_SB_CS0_N  SOCKET4677_AZIFS054P001C01  I169

M_C_CPU0_SB_CS_N<1>   @S9S_MB_2U_LIB.S9S_MB_2U(SCH_1):M_C_CPU0_SB_CS_N<1>
  J5     229  CS1_N_B  SCONN288_ADR50001P013C01  I24
  U2     U37  DDR2_SB_CS1_N  SOCKET4677_AZIFS054P001C01  I169

M_C_CPU0_SB_CS_N<2>   @S9S_MB_2U_LIB.S9S_MB_2U(SCH_1):M_C_CPU0_SB_CS_N<2>
  J6      84  CS0_N_B  SCONN288_ADR50001P003C01  I46
  U2     Y38  DDR2_SB_CS2_N  SOCKET4677_AZIFS054P001C01  I169

M_C_CPU0_SB_CS_N<3>   @S9S_MB_2U_LIB.S9S_MB_2U(SCH_1):M_C_CPU0_SB_CS_N<3>
  J6     229  CS1_N_B  SCONN288_ADR50001P003C01  I46
  U2     W37  DDR2_SB_CS3_N  SOCKET4677_AZIFS054P001C01  I169

M_C_CPU0_SB_DQ<0>   @S9S_MB_2U_LIB.S9S_MB_2U(SCH_1):M_C_CPU0_SB_DQ<0>
  J5     100  DQ_B0  SCONN288_ADR50001P013C01  I24
  J6     100  DQ_B0  SCONN288_ADR50001P003C01  I46
  U2     AD38  DDR2_SB_DQ0  SOCKET4677_AZIFS054P001C01  I169

M_C_CPU0_SB_DQ<1>   @S9S_MB_2U_LIB.S9S_MB_2U(SCH_1):M_C_CPU0_SB_DQ<1>
  J5     102  DQ_B1  SCONN288_ADR50001P013C01  I24
  J6     102  DQ_B1  SCONN288_ADR50001P003C01  I46
  U2     AC37  DDR2_SB_DQ1  SOCKET4677_AZIFS054P001C01  I169

M_C_CPU0_SB_DQ<2>   @S9S_MB_2U_LIB.S9S_MB_2U(SCH_1):M_C_CPU0_SB_DQ<2>
  J5     245  DQ_B2  SCONN288_ADR50001P013C01  I24
  J6     245  DQ_B2  SCONN288_ADR50001P003C01  I46
  U2     AF38  DDR2_SB_DQ2  SOCKET4677_AZIFS054P001C01  I169

M_C_CPU0_SB_DQ<3>   @S9S_MB_2U_LIB.S9S_MB_2U(SCH_1):M_C_CPU0_SB_DQ<3>
  J5     247  DQ_B3  SCONN288_ADR50001P013C01  I24
  J6     247  DQ_B3  SCONN288_ADR50001P003C01  I46
  U2     AG37  DDR2_SB_DQ3  SOCKET4677_AZIFS054P001C01  I169

M_C_CPU0_SB_DQ<4>   @S9S_MB_2U_LIB.S9S_MB_2U(SCH_1):M_C_CPU0_SB_DQ<4>
  J5     107  DQ_B4  SCONN288_ADR50001P013C01  I24
  J6     107  DQ_B4  SCONN288_ADR50001P003C01  I46
  U2     AC35  DDR2_SB_DQ4  SOCKET4677_AZIFS054P001C01  I169

M_C_CPU0_SB_DQ<5>   @S9S_MB_2U_LIB.S9S_MB_2U(SCH_1):M_C_CPU0_SB_DQ<5>
  J5     109  DQ_B5  SCONN288_ADR50001P013C01  I24
  J6     109  DQ_B5  SCONN288_ADR50001P003C01  I46
  U2     AD34  DDR2_SB_DQ5  SOCKET4677_AZIFS054P001C01  I169

M_C_CPU0_SB_DQ<6>   @S9S_MB_2U_LIB.S9S_MB_2U(SCH_1):M_C_CPU0_SB_DQ<6>
  J5     252  DQ_B6  SCONN288_ADR50001P013C01  I24
  J6     252  DQ_B6  SCONN288_ADR50001P003C01  I46
  U2     AG35  DDR2_SB_DQ6  SOCKET4677_AZIFS054P001C01  I169

M_C_CPU0_SB_DQ<7>   @S9S_MB_2U_LIB.S9S_MB_2U(SCH_1):M_C_CPU0_SB_DQ<7>
  J5     254  DQ_B7  SCONN288_ADR50001P013C01  I24
  J6     254  DQ_B7  SCONN288_ADR50001P003C01  I46
  U2     AF34  DDR2_SB_DQ7  SOCKET4677_AZIFS054P001C01  I169

M_C_CPU0_SB_DQ<8>   @S9S_MB_2U_LIB.S9S_MB_2U(SCH_1):M_C_CPU0_SB_DQ<8>
  J5     111  DQ_B8  SCONN288_ADR50001P013C01  I24
  J6     111  DQ_B8  SCONN288_ADR50001P003C01  I46
  U2     AD32  DDR2_SB_DQ8  SOCKET4677_AZIFS054P001C01  I169

M_C_CPU0_SB_DQ<9>   @S9S_MB_2U_LIB.S9S_MB_2U(SCH_1):M_C_CPU0_SB_DQ<9>
  J5     113  DQ_B9  SCONN288_ADR50001P013C01  I24
  J6     113  DQ_B9  SCONN288_ADR50001P003C01  I46
  U2     AC31  DDR2_SB_DQ9  SOCKET4677_AZIFS054P001C01  I169

M_C_CPU0_SB_DQ<10>   @S9S_MB_2U_LIB.S9S_MB_2U(SCH_1):M_C_CPU0_SB_DQ<10>
  J5     256  DQ_B10  SCONN288_ADR50001P013C01  I24
  J6     256  DQ_B10  SCONN288_ADR50001P003C01  I46
  U2     AF32  DDR2_SB_DQ10  SOCKET4677_AZIFS054P001C01  I169

M_C_CPU0_SB_DQ<11>   @S9S_MB_2U_LIB.S9S_MB_2U(SCH_1):M_C_CPU0_SB_DQ<11>
  J5     258  DQ_B11  SCONN288_ADR50001P013C01  I24
  J6     258  DQ_B11  SCONN288_ADR50001P003C01  I46
  U2     AG31  DDR2_SB_DQ11  SOCKET4677_AZIFS054P001C01  I169

M_C_CPU0_SB_DQ<12>   @S9S_MB_2U_LIB.S9S_MB_2U(SCH_1):M_C_CPU0_SB_DQ<12>
  J5     118  DQ_B12  SCONN288_ADR50001P013C01  I24
  J6     118  DQ_B12  SCONN288_ADR50001P003C01  I46
  U2     AC29  DDR2_SB_DQ12  SOCKET4677_AZIFS054P001C01  I169

M_C_CPU0_SB_DQ<13>   @S9S_MB_2U_LIB.S9S_MB_2U(SCH_1):M_C_CPU0_SB_DQ<13>
  J5     120  DQ_B13  SCONN288_ADR50001P013C01  I24
  J6     120  DQ_B13  SCONN288_ADR50001P003C01  I46
  U2     AD28  DDR2_SB_DQ13  SOCKET4677_AZIFS054P001C01  I169

M_C_CPU0_SB_DQ<14>   @S9S_MB_2U_LIB.S9S_MB_2U(SCH_1):M_C_CPU0_SB_DQ<14>
  J5     263  DQ_B14  SCONN288_ADR50001P013C01  I24
  J6     263  DQ_B14  SCONN288_ADR50001P003C01  I46
  U2     AG29  DDR2_SB_DQ14  SOCKET4677_AZIFS054P001C01  I169

M_C_CPU0_SB_DQ<15>   @S9S_MB_2U_LIB.S9S_MB_2U(SCH_1):M_C_CPU0_SB_DQ<15>
  J5     265  DQ_B15  SCONN288_ADR50001P013C01  I24
  J6     265  DQ_B15  SCONN288_ADR50001P003C01  I46
  U2     AF28  DDR2_SB_DQ15  SOCKET4677_AZIFS054P001C01  I169

M_C_CPU0_SB_DQ<16>   @S9S_MB_2U_LIB.S9S_MB_2U(SCH_1):M_C_CPU0_SB_DQ<16>
  J5     122  DQ_B16  SCONN288_ADR50001P013C01  I24
  J6     122  DQ_B16  SCONN288_ADR50001P003C01  I46
  U2     U23  DDR2_SB_DQ16  SOCKET4677_AZIFS054P001C01  I169

M_C_CPU0_SB_DQ<17>   @S9S_MB_2U_LIB.S9S_MB_2U(SCH_1):M_C_CPU0_SB_DQ<17>
  J5     124  DQ_B17  SCONN288_ADR50001P013C01  I24
  J6     124  DQ_B17  SCONN288_ADR50001P003C01  I46
  U2     T22  DDR2_SB_DQ17  SOCKET4677_AZIFS054P001C01  I169

M_C_CPU0_SB_DQ<18>   @S9S_MB_2U_LIB.S9S_MB_2U(SCH_1):M_C_CPU0_SB_DQ<18>
  J5     267  DQ_B18  SCONN288_ADR50001P013C01  I24
  J6     267  DQ_B18  SCONN288_ADR50001P003C01  I46
  U2     W23  DDR2_SB_DQ18  SOCKET4677_AZIFS054P001C01  I169

M_C_CPU0_SB_DQ<19>   @S9S_MB_2U_LIB.S9S_MB_2U(SCH_1):M_C_CPU0_SB_DQ<19>
  J5     269  DQ_B19  SCONN288_ADR50001P013C01  I24
  J6     269  DQ_B19  SCONN288_ADR50001P003C01  I46
  U2     Y22  DDR2_SB_DQ19  SOCKET4677_AZIFS054P001C01  I169

M_C_CPU0_SB_DQ<20>   @S9S_MB_2U_LIB.S9S_MB_2U(SCH_1):M_C_CPU0_SB_DQ<20>
  J5     129  DQ_B20  SCONN288_ADR50001P013C01  I24
  J6     129  DQ_B20  SCONN288_ADR50001P003C01  I46
  U2     T20  DDR2_SB_DQ20  SOCKET4677_AZIFS054P001C01  I169

M_C_CPU0_SB_DQ<21>   @S9S_MB_2U_LIB.S9S_MB_2U(SCH_1):M_C_CPU0_SB_DQ<21>
  J5     131  DQ_B21  SCONN288_ADR50001P013C01  I24
  J6     131  DQ_B21  SCONN288_ADR50001P003C01  I46
  U2     U19  DDR2_SB_DQ21  SOCKET4677_AZIFS054P001C01  I169

M_C_CPU0_SB_DQ<22>   @S9S_MB_2U_LIB.S9S_MB_2U(SCH_1):M_C_CPU0_SB_DQ<22>
  J5     274  DQ_B22  SCONN288_ADR50001P013C01  I24
  J6     274  DQ_B22  SCONN288_ADR50001P003C01  I46
  U2     Y20  DDR2_SB_DQ22  SOCKET4677_AZIFS054P001C01  I169

M_C_CPU0_SB_DQ<23>   @S9S_MB_2U_LIB.S9S_MB_2U(SCH_1):M_C_CPU0_SB_DQ<23>
  J5     276  DQ_B23  SCONN288_ADR50001P013C01  I24
  J6     276  DQ_B23  SCONN288_ADR50001P003C01  I46
  U2     W19  DDR2_SB_DQ23  SOCKET4677_AZIFS054P001C01  I169

M_C_CPU0_SB_DQ<24>   @S9S_MB_2U_LIB.S9S_MB_2U(SCH_1):M_C_CPU0_SB_DQ<24>
  J5     133  DQ_B24  SCONN288_ADR50001P013C01  I24
  J6     133  DQ_B24  SCONN288_ADR50001P003C01  I46
  U2     AD20  DDR2_SB_DQ24  SOCKET4677_AZIFS054P001C01  I169

M_C_CPU0_SB_DQ<25>   @S9S_MB_2U_LIB.S9S_MB_2U(SCH_1):M_C_CPU0_SB_DQ<25>
  J5     135  DQ_B25  SCONN288_ADR50001P013C01  I24
  J6     135  DQ_B25  SCONN288_ADR50001P003C01  I46
  U2     AC19  DDR2_SB_DQ25  SOCKET4677_AZIFS054P001C01  I169

M_C_CPU0_SB_DQ<26>   @S9S_MB_2U_LIB.S9S_MB_2U(SCH_1):M_C_CPU0_SB_DQ<26>
  J5     278  DQ_B26  SCONN288_ADR50001P013C01  I24
  J6     278  DQ_B26  SCONN288_ADR50001P003C01  I46
  U2     AF20  DDR2_SB_DQ26  SOCKET4677_AZIFS054P001C01  I169

M_C_CPU0_SB_DQ<27>   @S9S_MB_2U_LIB.S9S_MB_2U(SCH_1):M_C_CPU0_SB_DQ<27>
  J5     280  DQ_B27  SCONN288_ADR50001P013C01  I24
  J6     280  DQ_B27  SCONN288_ADR50001P003C01  I46
  U2     AG19  DDR2_SB_DQ27  SOCKET4677_AZIFS054P001C01  I169

M_C_CPU0_SB_DQ<28>   @S9S_MB_2U_LIB.S9S_MB_2U(SCH_1):M_C_CPU0_SB_DQ<28>
  J5     140  DQ_B28  SCONN288_ADR50001P013C01  I24
  J6     140  DQ_B28  SCONN288_ADR50001P003C01  I46
  U2     AA17  DDR2_SB_DQ28  SOCKET4677_AZIFS054P001C01  I169

M_C_CPU0_SB_DQ<29>   @S9S_MB_2U_LIB.S9S_MB_2U(SCH_1):M_C_CPU0_SB_DQ<29>
  J5     142  DQ_B29  SCONN288_ADR50001P013C01  I24
  J6     142  DQ_B29  SCONN288_ADR50001P003C01  I46
  U2     AG17  DDR2_SB_DQ29  SOCKET4677_AZIFS054P001C01  I169

M_C_CPU0_SB_DQ<30>   @S9S_MB_2U_LIB.S9S_MB_2U(SCH_1):M_C_CPU0_SB_DQ<30>
  J5     285  DQ_B30  SCONN288_ADR50001P013C01  I24
  J6     285  DQ_B30  SCONN288_ADR50001P003C01  I46
  U2     AC17  DDR2_SB_DQ30  SOCKET4677_AZIFS054P001C01  I169

M_C_CPU0_SB_DQ<31>   @S9S_MB_2U_LIB.S9S_MB_2U(SCH_1):M_C_CPU0_SB_DQ<31>
  J5     287  DQ_B31  SCONN288_ADR50001P013C01  I24
  J6     287  DQ_B31  SCONN288_ADR50001P003C01  I46
  U2     AJ17  DDR2_SB_DQ31  SOCKET4677_AZIFS054P001C01  I169

M_C_CPU0_SB_DQS_DN<0>   @S9S_MB_2U_LIB.S9S_MB_2U(SCH_1):M_C_CPU0_SB_DQS_DN<0>
  J5     105  DQS0_B_N  SCONN288_ADR50001P013C01  I125
  J6     105  DQS0_B_N  SCONN288_ADR50001P003C01  I123
  U2     AB36  DDR2_SB_DQS_DN0  SOCKET4677_AZIFS054P001C01  I169

M_C_CPU0_SB_DQS_DN<1>   @S9S_MB_2U_LIB.S9S_MB_2U(SCH_1):M_C_CPU0_SB_DQS_DN<1>
  J5     116  DQS1_B_N  SCONN288_ADR50001P013C01  I125
  J6     116  DQS1_B_N  SCONN288_ADR50001P003C01  I123
  U2     AB30  DDR2_SB_DQS_DN1  SOCKET4677_AZIFS054P001C01  I169

M_C_CPU0_SB_DQS_DN<2>   @S9S_MB_2U_LIB.S9S_MB_2U(SCH_1):M_C_CPU0_SB_DQS_DN<2>
  J5     127  DQS2_B_N  SCONN288_ADR50001P013C01  I125
  J6     127  DQS2_B_N  SCONN288_ADR50001P003C01  I123
  U2     R21  DDR2_SB_DQS_DN2  SOCKET4677_AZIFS054P001C01  I169

M_C_CPU0_SB_DQS_DN<3>   @S9S_MB_2U_LIB.S9S_MB_2U(SCH_1):M_C_CPU0_SB_DQS_DN<3>
  J5     138  DQS3_B_N  SCONN288_ADR50001P013C01  I125
  J6     138  DQS3_B_N  SCONN288_ADR50001P003C01  I123
  U2     AB18  DDR2_SB_DQS_DN3  SOCKET4677_AZIFS054P001C01  I169

M_C_CPU0_SB_DQS_DN<4>   @S9S_MB_2U_LIB.S9S_MB_2U(SCH_1):M_C_CPU0_SB_DQS_DN<4>
  J5     238  DQS4_B_N  SCONN288_ADR50001P013C01  I125
  J6     238  DQS4_B_N  SCONN288_ADR50001P003C01  I123
  U2     W33  DDR2_SB_DQS_DN4  SOCKET4677_AZIFS054P001C01  I169

M_C_CPU0_SB_DQS_DN<5>   @S9S_MB_2U_LIB.S9S_MB_2U(SCH_1):M_C_CPU0_SB_DQS_DN<5>
  J5     249  DQS5_B_N  SCONN288_ADR50001P013C01  I125
  J6     249  DQS5_B_N  SCONN288_ADR50001P003C01  I123
  U2     AF36  DDR2_SB_DQS_DN5  SOCKET4677_AZIFS054P001C01  I169

M_C_CPU0_SB_DQS_DN<6>   @S9S_MB_2U_LIB.S9S_MB_2U(SCH_1):M_C_CPU0_SB_DQS_DN<6>
  J5     260  DQS6_B_N  SCONN288_ADR50001P013C01  I125
  J6     260  DQS6_B_N  SCONN288_ADR50001P003C01  I123
  U2     AF30  DDR2_SB_DQS_DN6  SOCKET4677_AZIFS054P001C01  I169

M_C_CPU0_SB_DQS_DN<7>   @S9S_MB_2U_LIB.S9S_MB_2U(SCH_1):M_C_CPU0_SB_DQS_DN<7>
  J5     271  DQS7_B_N  SCONN288_ADR50001P013C01  I125
  J6     271  DQS7_B_N  SCONN288_ADR50001P003C01  I123
  U2     W21  DDR2_SB_DQS_DN7  SOCKET4677_AZIFS054P001C01  I169

M_C_CPU0_SB_DQS_DN<8>   @S9S_MB_2U_LIB.S9S_MB_2U(SCH_1):M_C_CPU0_SB_DQS_DN<8>
  J5     282  DQS8_B_N  SCONN288_ADR50001P013C01  I125
  J6     282  DQS8_B_N  SCONN288_ADR50001P003C01  I123
  U2     AF18  DDR2_SB_DQS_DN8  SOCKET4677_AZIFS054P001C01  I169

M_C_CPU0_SB_DQS_DN<9>   @S9S_MB_2U_LIB.S9S_MB_2U(SCH_1):M_C_CPU0_SB_DQS_DN<9>
  J5      94  DQS9_B_N  SCONN288_ADR50001P013C01  I125
  J6      94  DQS9_B_N  SCONN288_ADR50001P003C01  I123
  U2     R33  DDR2_SB_DQS_DN9  SOCKET4677_AZIFS054P001C01  I169

M_C_CPU0_SB_DQS_DP<0>   @S9S_MB_2U_LIB.S9S_MB_2U(SCH_1):M_C_CPU0_SB_DQS_DP<0>
  J5     104  DQS0_B_P  SCONN288_ADR50001P013C01  I125
  J6     104  DQS0_B_P  SCONN288_ADR50001P003C01  I123
  U2     AD36  DDR2_SB_DQS_DP0  SOCKET4677_AZIFS054P001C01  I169

M_C_CPU0_SB_DQS_DP<1>   @S9S_MB_2U_LIB.S9S_MB_2U(SCH_1):M_C_CPU0_SB_DQS_DP<1>
  J5     115  DQS1_B_P  SCONN288_ADR50001P013C01  I125
  J6     115  DQS1_B_P  SCONN288_ADR50001P003C01  I123
  U2     AD30  DDR2_SB_DQS_DP1  SOCKET4677_AZIFS054P001C01  I169

M_C_CPU0_SB_DQS_DP<2>   @S9S_MB_2U_LIB.S9S_MB_2U(SCH_1):M_C_CPU0_SB_DQS_DP<2>
  J5     126  DQS2_B_P  SCONN288_ADR50001P013C01  I125
  J6     126  DQS2_B_P  SCONN288_ADR50001P003C01  I123
  U2     U21  DDR2_SB_DQS_DP2  SOCKET4677_AZIFS054P001C01  I169

M_C_CPU0_SB_DQS_DP<3>   @S9S_MB_2U_LIB.S9S_MB_2U(SCH_1):M_C_CPU0_SB_DQS_DP<3>
  J5     137  DQS3_B_P  SCONN288_ADR50001P013C01  I125
  J6     137  DQS3_B_P  SCONN288_ADR50001P003C01  I123
  U2     AD18  DDR2_SB_DQS_DP3  SOCKET4677_AZIFS054P001C01  I169

M_C_CPU0_SB_DQS_DP<4>   @S9S_MB_2U_LIB.S9S_MB_2U(SCH_1):M_C_CPU0_SB_DQS_DP<4>
  J5     239  DQS4_B_P  SCONN288_ADR50001P013C01  I125
  J6     239  DQS4_B_P  SCONN288_ADR50001P003C01  I123
  U2     AA33  DDR2_SB_DQS_DP4  SOCKET4677_AZIFS054P001C01  I169

M_C_CPU0_SB_DQS_DP<5>   @S9S_MB_2U_LIB.S9S_MB_2U(SCH_1):M_C_CPU0_SB_DQS_DP<5>
  J5     250  DQS5_B_P  SCONN288_ADR50001P013C01  I125
  J6     250  DQS5_B_P  SCONN288_ADR50001P003C01  I123
  U2     AH36  DDR2_SB_DQS_DP5  SOCKET4677_AZIFS054P001C01  I169

M_C_CPU0_SB_DQS_DP<6>   @S9S_MB_2U_LIB.S9S_MB_2U(SCH_1):M_C_CPU0_SB_DQS_DP<6>
  J5     261  DQS6_B_P  SCONN288_ADR50001P013C01  I125
  J6     261  DQS6_B_P  SCONN288_ADR50001P003C01  I123
  U2     AH30  DDR2_SB_DQS_DP6  SOCKET4677_AZIFS054P001C01  I169

M_C_CPU0_SB_DQS_DP<7>   @S9S_MB_2U_LIB.S9S_MB_2U(SCH_1):M_C_CPU0_SB_DQS_DP<7>
  J5     272  DQS7_B_P  SCONN288_ADR50001P013C01  I125
  J6     272  DQS7_B_P  SCONN288_ADR50001P003C01  I123
  U2     AA21  DDR2_SB_DQS_DP7  SOCKET4677_AZIFS054P001C01  I169

M_C_CPU0_SB_DQS_DP<8>   @S9S_MB_2U_LIB.S9S_MB_2U(SCH_1):M_C_CPU0_SB_DQS_DP<8>
  J5     283  DQS8_B_P  SCONN288_ADR50001P013C01  I125
  J6     283  DQS8_B_P  SCONN288_ADR50001P003C01  I123
  U2     AH18  DDR2_SB_DQS_DP8  SOCKET4677_AZIFS054P001C01  I169

M_C_CPU0_SB_DQS_DP<9>   @S9S_MB_2U_LIB.S9S_MB_2U(SCH_1):M_C_CPU0_SB_DQS_DP<9>
  J5      93  DQS9_B_P  SCONN288_ADR50001P013C01  I125
  J6      93  DQS9_B_P  SCONN288_ADR50001P003C01  I123
  U2     U33  DDR2_SB_DQS_DP9  SOCKET4677_AZIFS054P001C01  I169

M_C_CPU0_SB_PAR   @S9S_MB_2U_LIB.S9S_MB_2U(SCH_1):M_C_CPU0_SB_PAR
  J5     227  PAR_B  SCONN288_ADR50001P013C01  I24
  J6     227  PAR_B  SCONN288_ADR50001P003C01  I46
  U2     AA39  DDR2_SB_PAR  SOCKET4677_AZIFS054P001C01  I169

M_C_CPU0_SB_RSP<0>   @S9S_MB_2U_LIB.S9S_MB_2U(SCH_1):M_C_CPU0_SB_RSP<0>
  J5      87  LBS||RSP_N_B  SCONN288_ADR50001P013C01  I24
  U2     AG48  DDR2_B_RSP0  SOCKET4677_AZIFS054P001C01  I169

M_C_CPU0_SB_RSP<1>   @S9S_MB_2U_LIB.S9S_MB_2U(SCH_1):M_C_CPU0_SB_RSP<1>
  J6      87  LBS||RSP_N_B  SCONN288_ADR50001P003C01  I46
  U2     AF47  DDR2_B_RSP1  SOCKET4677_AZIFS054P001C01  I169

M_C_CPU1_ALERT_N   @S9S_MB_2U_LIB.S9S_MB_2U(SCH_1):M_C_CPU1_ALERT_N
  J21     62  ALERT_N  SCONN288_ADR50001P013C01  I13
  J22     62  ALERT_N  SCONN288_ADR50001P003C01  I51
  U1     AT47  DDR2_ALERT_N  SOCKET4677_AZIFS054P001C01  I91

M_C_CPU1_CLK_DN<0>   @S9S_MB_2U_LIB.S9S_MB_2U(SCH_1):M_C_CPU1_CLK_DN<0>
  J21    218   CK_N  SCONN288_ADR50001P013C01  I13
  U1     AB49  DDR2_CLK_DN0  SOCKET4677_AZIFS054P001C01  I91

M_C_CPU1_CLK_DN<1>   @S9S_MB_2U_LIB.S9S_MB_2U(SCH_1):M_C_CPU1_CLK_DN<1>
  J22    218   CK_N  SCONN288_ADR50001P003C01  I51
  U1     AF49  DDR2_CLK_DN1  SOCKET4677_AZIFS054P001C01  I91

M_C_CPU1_CLK_DP<0>   @S9S_MB_2U_LIB.S9S_MB_2U(SCH_1):M_C_CPU1_CLK_DP<0>
  J21    217   CK_P  SCONN288_ADR50001P013C01  I13
  U1     AD49  DDR2_CLK_DP0  SOCKET4677_AZIFS054P001C01  I91

M_C_CPU1_CLK_DP<1>   @S9S_MB_2U_LIB.S9S_MB_2U(SCH_1):M_C_CPU1_CLK_DP<1>
  J22    217   CK_P  SCONN288_ADR50001P003C01  I51
  U1     AH49  DDR2_CLK_DP1  SOCKET4677_AZIFS054P001C01  I91

M_C_CPU1_SA_CA<0>   @S9S_MB_2U_LIB.S9S_MB_2U(SCH_1):M_C_CPU1_SA_CA<0>
  J21     66  CA0_A  SCONN288_ADR50001P013C01  I13
  J22     66  CA0_A  SCONN288_ADR50001P003C01  I51
  U1     R52  DDR2_SA_CA0  SOCKET4677_AZIFS054P001C01  I91

M_C_CPU1_SA_CA<1>   @S9S_MB_2U_LIB.S9S_MB_2U(SCH_1):M_C_CPU1_SA_CA<1>
  J21    211  CA1_A  SCONN288_ADR50001P013C01  I13
  J22    211  CA1_A  SCONN288_ADR50001P003C01  I51
  U1     AA52  DDR2_SA_CA1  SOCKET4677_AZIFS054P001C01  I91

M_C_CPU1_SA_CA<2>   @S9S_MB_2U_LIB.S9S_MB_2U(SCH_1):M_C_CPU1_SA_CA<2>
  J21     68  CA2_A  SCONN288_ADR50001P013C01  I13
  J22     68  CA2_A  SCONN288_ADR50001P003C01  I51
  U1     T51  DDR2_SA_CA2  SOCKET4677_AZIFS054P001C01  I91

M_C_CPU1_SA_CA<3>   @S9S_MB_2U_LIB.S9S_MB_2U(SCH_1):M_C_CPU1_SA_CA<3>
  J21    213  CA3_A  SCONN288_ADR50001P013C01  I13
  J22    213  CA3_A  SCONN288_ADR50001P003C01  I51
  U1     Y51  DDR2_SA_CA3  SOCKET4677_AZIFS054P001C01  I91

M_C_CPU1_SA_CA<4>   @S9S_MB_2U_LIB.S9S_MB_2U(SCH_1):M_C_CPU1_SA_CA<4>
  J21     70  CA4_A  SCONN288_ADR50001P013C01  I13
  J22     70  CA4_A  SCONN288_ADR50001P003C01  I51
  U1     U50  DDR2_SA_CA4  SOCKET4677_AZIFS054P001C01  I91

M_C_CPU1_SA_CA<5>   @S9S_MB_2U_LIB.S9S_MB_2U(SCH_1):M_C_CPU1_SA_CA<5>
  J21    215  CA5_A  SCONN288_ADR50001P013C01  I13
  J22    215  CA5_A  SCONN288_ADR50001P003C01  I51
  U1     W50  DDR2_SA_CA5  SOCKET4677_AZIFS054P001C01  I91

M_C_CPU1_SA_CA<6>   @S9S_MB_2U_LIB.S9S_MB_2U(SCH_1):M_C_CPU1_SA_CA<6>
  J21     72  CA6_A  SCONN288_ADR50001P013C01  I13
  J22     72  CA6_A  SCONN288_ADR50001P003C01  I51
  U1     U48  DDR2_SA_CA6  SOCKET4677_AZIFS054P001C01  I91

M_C_CPU1_SA_CB<0>   @S9S_MB_2U_LIB.S9S_MB_2U(SCH_1):M_C_CPU1_SA_CB<0>
  J21     51  CB_A0  SCONN288_ADR50001P013C01  I13
  J22     51  CB_A0  SCONN288_ADR50001P003C01  I51
  U1     AD57  DDR2_SA_ECC0  SOCKET4677_AZIFS054P001C01  I91

M_C_CPU1_SA_CB<1>   @S9S_MB_2U_LIB.S9S_MB_2U(SCH_1):M_C_CPU1_SA_CB<1>
  J21     53  CB_A1  SCONN288_ADR50001P013C01  I13
  J22     53  CB_A1  SCONN288_ADR50001P003C01  I51
  U1     AC56  DDR2_SA_ECC1  SOCKET4677_AZIFS054P001C01  I91

M_C_CPU1_SA_CB<2>   @S9S_MB_2U_LIB.S9S_MB_2U(SCH_1):M_C_CPU1_SA_CB<2>
  J21    196  CB_A2  SCONN288_ADR50001P013C01  I13
  J22    196  CB_A2  SCONN288_ADR50001P003C01  I51
  U1     AF57  DDR2_SA_ECC2  SOCKET4677_AZIFS054P001C01  I91

M_C_CPU1_SA_CB<3>   @S9S_MB_2U_LIB.S9S_MB_2U(SCH_1):M_C_CPU1_SA_CB<3>
  J21    198  CB_A3  SCONN288_ADR50001P013C01  I13
  J22    198  CB_A3  SCONN288_ADR50001P003C01  I51
  U1     AG56  DDR2_SA_ECC3  SOCKET4677_AZIFS054P001C01  I91

M_C_CPU1_SA_CB<4>   @S9S_MB_2U_LIB.S9S_MB_2U(SCH_1):M_C_CPU1_SA_CB<4>
  J21     58  CB_A4  SCONN288_ADR50001P013C01  I13
  J22     58  CB_A4  SCONN288_ADR50001P003C01  I51
  U1     AC54  DDR2_SA_ECC4  SOCKET4677_AZIFS054P001C01  I91

M_C_CPU1_SA_CB<5>   @S9S_MB_2U_LIB.S9S_MB_2U(SCH_1):M_C_CPU1_SA_CB<5>
  J21     60  CB_A5  SCONN288_ADR50001P013C01  I13
  J22     60  CB_A5  SCONN288_ADR50001P003C01  I51
  U1     AD53  DDR2_SA_ECC5  SOCKET4677_AZIFS054P001C01  I91

M_C_CPU1_SA_CB<6>   @S9S_MB_2U_LIB.S9S_MB_2U(SCH_1):M_C_CPU1_SA_CB<6>
  J21    203  CB_A6  SCONN288_ADR50001P013C01  I13
  J22    203  CB_A6  SCONN288_ADR50001P003C01  I51
  U1     AG54  DDR2_SA_ECC6  SOCKET4677_AZIFS054P001C01  I91

M_C_CPU1_SA_CB<7>   @S9S_MB_2U_LIB.S9S_MB_2U(SCH_1):M_C_CPU1_SA_CB<7>
  J21    205  CB_A7  SCONN288_ADR50001P013C01  I13
  J22    205  CB_A7  SCONN288_ADR50001P003C01  I51
  U1     AF53  DDR2_SA_ECC7  SOCKET4677_AZIFS054P001C01  I91

M_C_CPU1_SA_CS_N<0>   @S9S_MB_2U_LIB.S9S_MB_2U(SCH_1):M_C_CPU1_SA_CS_N<0>
  J21     64  CS0_N_A  SCONN288_ADR50001P013C01  I13
  U1     U54  DDR2_SA_CS0_N  SOCKET4677_AZIFS054P001C01  I91

M_C_CPU1_SA_CS_N<1>   @S9S_MB_2U_LIB.S9S_MB_2U(SCH_1):M_C_CPU1_SA_CS_N<1>
  J21    209  CS1_N_A  SCONN288_ADR50001P013C01  I13
  U1     T53  DDR2_SA_CS1_N  SOCKET4677_AZIFS054P001C01  I91

M_C_CPU1_SA_CS_N<2>   @S9S_MB_2U_LIB.S9S_MB_2U(SCH_1):M_C_CPU1_SA_CS_N<2>
  J22     64  CS0_N_A  SCONN288_ADR50001P003C01  I51
  U1     W54  DDR2_SA_CS2_N  SOCKET4677_AZIFS054P001C01  I91

M_C_CPU1_SA_CS_N<3>   @S9S_MB_2U_LIB.S9S_MB_2U(SCH_1):M_C_CPU1_SA_CS_N<3>
  J22    209  CS1_N_A  SCONN288_ADR50001P003C01  I51
  U1     Y53  DDR2_SA_CS3_N  SOCKET4677_AZIFS054P001C01  I91

M_C_CPU1_SA_DQ<0>   @S9S_MB_2U_LIB.S9S_MB_2U(SCH_1):M_C_CPU1_SA_DQ<0>
  J21      7  DQ_A0  SCONN288_ADR50001P013C01  I13
  J22      7  DQ_A0  SCONN288_ADR50001P003C01  I51
  U1     U78  DDR2_SA_DQ0  SOCKET4677_AZIFS054P001C01  I91

M_C_CPU1_SA_DQ<1>   @S9S_MB_2U_LIB.S9S_MB_2U(SCH_1):M_C_CPU1_SA_DQ<1>
  J21      9  DQ_A1  SCONN288_ADR50001P013C01  I13
  J22      9  DQ_A1  SCONN288_ADR50001P003C01  I51
  U1     T77  DDR2_SA_DQ1  SOCKET4677_AZIFS054P001C01  I91

M_C_CPU1_SA_DQ<2>   @S9S_MB_2U_LIB.S9S_MB_2U(SCH_1):M_C_CPU1_SA_DQ<2>
  J21    152  DQ_A2  SCONN288_ADR50001P013C01  I13
  J22    152  DQ_A2  SCONN288_ADR50001P003C01  I51
  U1     W78  DDR2_SA_DQ2  SOCKET4677_AZIFS054P001C01  I91

M_C_CPU1_SA_DQ<3>   @S9S_MB_2U_LIB.S9S_MB_2U(SCH_1):M_C_CPU1_SA_DQ<3>
  J21    154  DQ_A3  SCONN288_ADR50001P013C01  I13
  J22    154  DQ_A3  SCONN288_ADR50001P003C01  I51
  U1     Y77  DDR2_SA_DQ3  SOCKET4677_AZIFS054P001C01  I91

M_C_CPU1_SA_DQ<4>   @S9S_MB_2U_LIB.S9S_MB_2U(SCH_1):M_C_CPU1_SA_DQ<4>
  J21     14  DQ_A4  SCONN288_ADR50001P013C01  I13
  J22     14  DQ_A4  SCONN288_ADR50001P003C01  I51
  U1     T75  DDR2_SA_DQ4  SOCKET4677_AZIFS054P001C01  I91

M_C_CPU1_SA_DQ<5>   @S9S_MB_2U_LIB.S9S_MB_2U(SCH_1):M_C_CPU1_SA_DQ<5>
  J21     16  DQ_A5  SCONN288_ADR50001P013C01  I13
  J22     16  DQ_A5  SCONN288_ADR50001P003C01  I51
  U1     U74  DDR2_SA_DQ5  SOCKET4677_AZIFS054P001C01  I91

M_C_CPU1_SA_DQ<6>   @S9S_MB_2U_LIB.S9S_MB_2U(SCH_1):M_C_CPU1_SA_DQ<6>
  J21    159  DQ_A6  SCONN288_ADR50001P013C01  I13
  J22    159  DQ_A6  SCONN288_ADR50001P003C01  I51
  U1     Y75  DDR2_SA_DQ6  SOCKET4677_AZIFS054P001C01  I91

M_C_CPU1_SA_DQ<7>   @S9S_MB_2U_LIB.S9S_MB_2U(SCH_1):M_C_CPU1_SA_DQ<7>
  J21    161  DQ_A7  SCONN288_ADR50001P013C01  I13
  J22    161  DQ_A7  SCONN288_ADR50001P003C01  I51
  U1     W74  DDR2_SA_DQ7  SOCKET4677_AZIFS054P001C01  I91

M_C_CPU1_SA_DQ<8>   @S9S_MB_2U_LIB.S9S_MB_2U(SCH_1):M_C_CPU1_SA_DQ<8>
  J21     18  DQ_A8  SCONN288_ADR50001P013C01  I13
  J22     18  DQ_A8  SCONN288_ADR50001P003C01  I51
  U1     AD69  DDR2_SA_DQ8  SOCKET4677_AZIFS054P001C01  I91

M_C_CPU1_SA_DQ<9>   @S9S_MB_2U_LIB.S9S_MB_2U(SCH_1):M_C_CPU1_SA_DQ<9>
  J21     20  DQ_A9  SCONN288_ADR50001P013C01  I13
  J22     20  DQ_A9  SCONN288_ADR50001P003C01  I51
  U1     AC68  DDR2_SA_DQ9  SOCKET4677_AZIFS054P001C01  I91

M_C_CPU1_SA_DQ<10>   @S9S_MB_2U_LIB.S9S_MB_2U(SCH_1):M_C_CPU1_SA_DQ<10>
  J21    163  DQ_A10  SCONN288_ADR50001P013C01  I13
  J22    163  DQ_A10  SCONN288_ADR50001P003C01  I51
  U1     AF69  DDR2_SA_DQ10  SOCKET4677_AZIFS054P001C01  I91

M_C_CPU1_SA_DQ<11>   @S9S_MB_2U_LIB.S9S_MB_2U(SCH_1):M_C_CPU1_SA_DQ<11>
  J21    165  DQ_A11  SCONN288_ADR50001P013C01  I13
  J22    165  DQ_A11  SCONN288_ADR50001P003C01  I51
  U1     AG68  DDR2_SA_DQ11  SOCKET4677_AZIFS054P001C01  I91

M_C_CPU1_SA_DQ<12>   @S9S_MB_2U_LIB.S9S_MB_2U(SCH_1):M_C_CPU1_SA_DQ<12>
  J21     25  DQ_A12  SCONN288_ADR50001P013C01  I13
  J22     25  DQ_A12  SCONN288_ADR50001P003C01  I51
  U1     AC66  DDR2_SA_DQ12  SOCKET4677_AZIFS054P001C01  I91

M_C_CPU1_SA_DQ<13>   @S9S_MB_2U_LIB.S9S_MB_2U(SCH_1):M_C_CPU1_SA_DQ<13>
  J21     27  DQ_A13  SCONN288_ADR50001P013C01  I13
  J22     27  DQ_A13  SCONN288_ADR50001P003C01  I51
  U1     AD65  DDR2_SA_DQ13  SOCKET4677_AZIFS054P001C01  I91

M_C_CPU1_SA_DQ<14>   @S9S_MB_2U_LIB.S9S_MB_2U(SCH_1):M_C_CPU1_SA_DQ<14>
  J21    170  DQ_A14  SCONN288_ADR50001P013C01  I13
  J22    170  DQ_A14  SCONN288_ADR50001P003C01  I51
  U1     AG66  DDR2_SA_DQ14  SOCKET4677_AZIFS054P001C01  I91

M_C_CPU1_SA_DQ<15>   @S9S_MB_2U_LIB.S9S_MB_2U(SCH_1):M_C_CPU1_SA_DQ<15>
  J21    172  DQ_A15  SCONN288_ADR50001P013C01  I13
  J22    172  DQ_A15  SCONN288_ADR50001P003C01  I51
  U1     AF65  DDR2_SA_DQ15  SOCKET4677_AZIFS054P001C01  I91

M_C_CPU1_SA_DQ<16>   @S9S_MB_2U_LIB.S9S_MB_2U(SCH_1):M_C_CPU1_SA_DQ<16>
  J21     29  DQ_A16  SCONN288_ADR50001P013C01  I13
  J22     29  DQ_A16  SCONN288_ADR50001P003C01  I51
  U1     U66  DDR2_SA_DQ16  SOCKET4677_AZIFS054P001C01  I91

M_C_CPU1_SA_DQ<17>   @S9S_MB_2U_LIB.S9S_MB_2U(SCH_1):M_C_CPU1_SA_DQ<17>
  J21     31  DQ_A17  SCONN288_ADR50001P013C01  I13
  J22     31  DQ_A17  SCONN288_ADR50001P003C01  I51
  U1     T65  DDR2_SA_DQ17  SOCKET4677_AZIFS054P001C01  I91

M_C_CPU1_SA_DQ<18>   @S9S_MB_2U_LIB.S9S_MB_2U(SCH_1):M_C_CPU1_SA_DQ<18>
  J21    174  DQ_A18  SCONN288_ADR50001P013C01  I13
  J22    174  DQ_A18  SCONN288_ADR50001P003C01  I51
  U1     W66  DDR2_SA_DQ18  SOCKET4677_AZIFS054P001C01  I91

M_C_CPU1_SA_DQ<19>   @S9S_MB_2U_LIB.S9S_MB_2U(SCH_1):M_C_CPU1_SA_DQ<19>
  J21    176  DQ_A19  SCONN288_ADR50001P013C01  I13
  J22    176  DQ_A19  SCONN288_ADR50001P003C01  I51
  U1     Y65  DDR2_SA_DQ19  SOCKET4677_AZIFS054P001C01  I91

M_C_CPU1_SA_DQ<20>   @S9S_MB_2U_LIB.S9S_MB_2U(SCH_1):M_C_CPU1_SA_DQ<20>
  J21     36  DQ_A20  SCONN288_ADR50001P013C01  I13
  J22     36  DQ_A20  SCONN288_ADR50001P003C01  I51
  U1     T63  DDR2_SA_DQ20  SOCKET4677_AZIFS054P001C01  I91

M_C_CPU1_SA_DQ<21>   @S9S_MB_2U_LIB.S9S_MB_2U(SCH_1):M_C_CPU1_SA_DQ<21>
  J21     38  DQ_A21  SCONN288_ADR50001P013C01  I13
  J22     38  DQ_A21  SCONN288_ADR50001P003C01  I51
  U1     U62  DDR2_SA_DQ21  SOCKET4677_AZIFS054P001C01  I91

M_C_CPU1_SA_DQ<22>   @S9S_MB_2U_LIB.S9S_MB_2U(SCH_1):M_C_CPU1_SA_DQ<22>
  J21    181  DQ_A22  SCONN288_ADR50001P013C01  I13
  J22    181  DQ_A22  SCONN288_ADR50001P003C01  I51
  U1     Y63  DDR2_SA_DQ22  SOCKET4677_AZIFS054P001C01  I91

M_C_CPU1_SA_DQ<23>   @S9S_MB_2U_LIB.S9S_MB_2U(SCH_1):M_C_CPU1_SA_DQ<23>
  J21    183  DQ_A23  SCONN288_ADR50001P013C01  I13
  J22    183  DQ_A23  SCONN288_ADR50001P003C01  I51
  U1     W62  DDR2_SA_DQ23  SOCKET4677_AZIFS054P001C01  I91

M_C_CPU1_SA_DQ<24>   @S9S_MB_2U_LIB.S9S_MB_2U(SCH_1):M_C_CPU1_SA_DQ<24>
  J21     40  DQ_A24  SCONN288_ADR50001P013C01  I13
  J22     40  DQ_A24  SCONN288_ADR50001P003C01  I51
  U1     AD63  DDR2_SA_DQ24  SOCKET4677_AZIFS054P001C01  I91

M_C_CPU1_SA_DQ<25>   @S9S_MB_2U_LIB.S9S_MB_2U(SCH_1):M_C_CPU1_SA_DQ<25>
  J21     42  DQ_A25  SCONN288_ADR50001P013C01  I13
  J22     42  DQ_A25  SCONN288_ADR50001P003C01  I51
  U1     AC62  DDR2_SA_DQ25  SOCKET4677_AZIFS054P001C01  I91

M_C_CPU1_SA_DQ<26>   @S9S_MB_2U_LIB.S9S_MB_2U(SCH_1):M_C_CPU1_SA_DQ<26>
  J21    185  DQ_A26  SCONN288_ADR50001P013C01  I13
  J22    185  DQ_A26  SCONN288_ADR50001P003C01  I51
  U1     AF63  DDR2_SA_DQ26  SOCKET4677_AZIFS054P001C01  I91

M_C_CPU1_SA_DQ<27>   @S9S_MB_2U_LIB.S9S_MB_2U(SCH_1):M_C_CPU1_SA_DQ<27>
  J21    187  DQ_A27  SCONN288_ADR50001P013C01  I13
  J22    187  DQ_A27  SCONN288_ADR50001P003C01  I51
  U1     AG62  DDR2_SA_DQ27  SOCKET4677_AZIFS054P001C01  I91

M_C_CPU1_SA_DQ<28>   @S9S_MB_2U_LIB.S9S_MB_2U(SCH_1):M_C_CPU1_SA_DQ<28>
  J21     47  DQ_A28  SCONN288_ADR50001P013C01  I13
  J22     47  DQ_A28  SCONN288_ADR50001P003C01  I51
  U1     AC60  DDR2_SA_DQ28  SOCKET4677_AZIFS054P001C01  I91

M_C_CPU1_SA_DQ<29>   @S9S_MB_2U_LIB.S9S_MB_2U(SCH_1):M_C_CPU1_SA_DQ<29>
  J21     49  DQ_A29  SCONN288_ADR50001P013C01  I13
  J22     49  DQ_A29  SCONN288_ADR50001P003C01  I51
  U1     AD59  DDR2_SA_DQ29  SOCKET4677_AZIFS054P001C01  I91

M_C_CPU1_SA_DQ<30>   @S9S_MB_2U_LIB.S9S_MB_2U(SCH_1):M_C_CPU1_SA_DQ<30>
  J21    192  DQ_A30  SCONN288_ADR50001P013C01  I13
  J22    192  DQ_A30  SCONN288_ADR50001P003C01  I51
  U1     AG60  DDR2_SA_DQ30  SOCKET4677_AZIFS054P001C01  I91

M_C_CPU1_SA_DQ<31>   @S9S_MB_2U_LIB.S9S_MB_2U(SCH_1):M_C_CPU1_SA_DQ<31>
  J21    194  DQ_A31  SCONN288_ADR50001P013C01  I13
  J22    194  DQ_A31  SCONN288_ADR50001P003C01  I51
  U1     AF59  DDR2_SA_DQ31  SOCKET4677_AZIFS054P001C01  I91

M_C_CPU1_SA_DQS_DN<0>   @S9S_MB_2U_LIB.S9S_MB_2U(SCH_1):M_C_CPU1_SA_DQS_DN<0>
  J21     12  DQS0_A_N  SCONN288_ADR50001P013C01  I126
  J22     12  DQS0_A_N  SCONN288_ADR50001P003C01  I125
  U1     R76  DDR2_SA_DQS_DN0  SOCKET4677_AZIFS054P001C01  I91

M_C_CPU1_SA_DQS_DN<1>   @S9S_MB_2U_LIB.S9S_MB_2U(SCH_1):M_C_CPU1_SA_DQS_DN<1>
  J21     23  DQS1_A_N  SCONN288_ADR50001P013C01  I126
  J22     23  DQS1_A_N  SCONN288_ADR50001P003C01  I125
  U1     AB67  DDR2_SA_DQS_DN1  SOCKET4677_AZIFS054P001C01  I91

M_C_CPU1_SA_DQS_DN<2>   @S9S_MB_2U_LIB.S9S_MB_2U(SCH_1):M_C_CPU1_SA_DQS_DN<2>
  J21     34  DQS2_A_N  SCONN288_ADR50001P013C01  I126
  J22     34  DQS2_A_N  SCONN288_ADR50001P003C01  I125
  U1     R64  DDR2_SA_DQS_DN2  SOCKET4677_AZIFS054P001C01  I91

M_C_CPU1_SA_DQS_DN<3>   @S9S_MB_2U_LIB.S9S_MB_2U(SCH_1):M_C_CPU1_SA_DQS_DN<3>
  J21     45  DQS3_A_N  SCONN288_ADR50001P013C01  I126
  J22     45  DQS3_A_N  SCONN288_ADR50001P003C01  I125
  U1     AB61  DDR2_SA_DQS_DN3  SOCKET4677_AZIFS054P001C01  I91

M_C_CPU1_SA_DQS_DN<4>   @S9S_MB_2U_LIB.S9S_MB_2U(SCH_1):M_C_CPU1_SA_DQS_DN<4>
  J21     56  DQS4_A_N  SCONN288_ADR50001P013C01  I126
  J22     56  DQS4_A_N  SCONN288_ADR50001P003C01  I125
  U1     AD55  DDR2_SA_DQS_DN4  SOCKET4677_AZIFS054P001C01  I91

M_C_CPU1_SA_DQS_DN<5>   @S9S_MB_2U_LIB.S9S_MB_2U(SCH_1):M_C_CPU1_SA_DQS_DN<5>
  J21    156  DQS5_A_N  SCONN288_ADR50001P013C01  I126
  J22    156  DQS5_A_N  SCONN288_ADR50001P003C01  I125
  U1     W76  DDR2_SA_DQS_DN5  SOCKET4677_AZIFS054P001C01  I91

M_C_CPU1_SA_DQS_DN<6>   @S9S_MB_2U_LIB.S9S_MB_2U(SCH_1):M_C_CPU1_SA_DQS_DN<6>
  J21    167  DQS6_A_N  SCONN288_ADR50001P013C01  I126
  J22    167  DQS6_A_N  SCONN288_ADR50001P003C01  I125
  U1     AH67  DDR2_SA_DQS_DN6  SOCKET4677_AZIFS054P001C01  I91

M_C_CPU1_SA_DQS_DN<7>   @S9S_MB_2U_LIB.S9S_MB_2U(SCH_1):M_C_CPU1_SA_DQS_DN<7>
  J21    178  DQS7_A_N  SCONN288_ADR50001P013C01  I126
  J22    178  DQS7_A_N  SCONN288_ADR50001P003C01  I125
  U1     AA64  DDR2_SA_DQS_DN7  SOCKET4677_AZIFS054P001C01  I91

M_C_CPU1_SA_DQS_DN<8>   @S9S_MB_2U_LIB.S9S_MB_2U(SCH_1):M_C_CPU1_SA_DQS_DN<8>
  J21    189  DQS8_A_N  SCONN288_ADR50001P013C01  I126
  J22    189  DQS8_A_N  SCONN288_ADR50001P003C01  I125
  U1     AF61  DDR2_SA_DQS_DN8  SOCKET4677_AZIFS054P001C01  I91

M_C_CPU1_SA_DQS_DN<9>   @S9S_MB_2U_LIB.S9S_MB_2U(SCH_1):M_C_CPU1_SA_DQS_DN<9>
  J21    200  DQS9_A_N  SCONN288_ADR50001P013C01  I126
  J22    200  DQS9_A_N  SCONN288_ADR50001P003C01  I125
  U1     AH55  DDR2_SA_DQS_DN9  SOCKET4677_AZIFS054P001C01  I91

M_C_CPU1_SA_DQS_DP<0>   @S9S_MB_2U_LIB.S9S_MB_2U(SCH_1):M_C_CPU1_SA_DQS_DP<0>
  J21     11  DQS0_A_P  SCONN288_ADR50001P013C01  I126
  J22     11  DQS0_A_P  SCONN288_ADR50001P003C01  I125
  U1     U76  DDR2_SA_DQS_DP0  SOCKET4677_AZIFS054P001C01  I91

M_C_CPU1_SA_DQS_DP<1>   @S9S_MB_2U_LIB.S9S_MB_2U(SCH_1):M_C_CPU1_SA_DQS_DP<1>
  J21     22  DQS1_A_P  SCONN288_ADR50001P013C01  I126
  J22     22  DQS1_A_P  SCONN288_ADR50001P003C01  I125
  U1     AD67  DDR2_SA_DQS_DP1  SOCKET4677_AZIFS054P001C01  I91

M_C_CPU1_SA_DQS_DP<2>   @S9S_MB_2U_LIB.S9S_MB_2U(SCH_1):M_C_CPU1_SA_DQS_DP<2>
  J21     33  DQS2_A_P  SCONN288_ADR50001P013C01  I126
  J22     33  DQS2_A_P  SCONN288_ADR50001P003C01  I125
  U1     U64  DDR2_SA_DQS_DP2  SOCKET4677_AZIFS054P001C01  I91

M_C_CPU1_SA_DQS_DP<3>   @S9S_MB_2U_LIB.S9S_MB_2U(SCH_1):M_C_CPU1_SA_DQS_DP<3>
  J21     44  DQS3_A_P  SCONN288_ADR50001P013C01  I126
  J22     44  DQS3_A_P  SCONN288_ADR50001P003C01  I125
  U1     AD61  DDR2_SA_DQS_DP3  SOCKET4677_AZIFS054P001C01  I91

M_C_CPU1_SA_DQS_DP<4>   @S9S_MB_2U_LIB.S9S_MB_2U(SCH_1):M_C_CPU1_SA_DQS_DP<4>
  J21     55  DQS4_A_P  SCONN288_ADR50001P013C01  I126
  J22     55  DQS4_A_P  SCONN288_ADR50001P003C01  I125
  U1     AB55  DDR2_SA_DQS_DP4  SOCKET4677_AZIFS054P001C01  I91

M_C_CPU1_SA_DQS_DP<5>   @S9S_MB_2U_LIB.S9S_MB_2U(SCH_1):M_C_CPU1_SA_DQS_DP<5>
  J21    157  DQS5_A_P  SCONN288_ADR50001P013C01  I126
  J22    157  DQS5_A_P  SCONN288_ADR50001P003C01  I125
  U1     AA76  DDR2_SA_DQS_DP5  SOCKET4677_AZIFS054P001C01  I91

M_C_CPU1_SA_DQS_DP<6>   @S9S_MB_2U_LIB.S9S_MB_2U(SCH_1):M_C_CPU1_SA_DQS_DP<6>
  J21    168  DQS6_A_P  SCONN288_ADR50001P013C01  I126
  J22    168  DQS6_A_P  SCONN288_ADR50001P003C01  I125
  U1     AF67  DDR2_SA_DQS_DP6  SOCKET4677_AZIFS054P001C01  I91

M_C_CPU1_SA_DQS_DP<7>   @S9S_MB_2U_LIB.S9S_MB_2U(SCH_1):M_C_CPU1_SA_DQS_DP<7>
  J21    179  DQS7_A_P  SCONN288_ADR50001P013C01  I126
  J22    179  DQS7_A_P  SCONN288_ADR50001P003C01  I125
  U1     W64  DDR2_SA_DQS_DP7  SOCKET4677_AZIFS054P001C01  I91

M_C_CPU1_SA_DQS_DP<8>   @S9S_MB_2U_LIB.S9S_MB_2U(SCH_1):M_C_CPU1_SA_DQS_DP<8>
  J21    190  DQS8_A_P  SCONN288_ADR50001P013C01  I126
  J22    190  DQS8_A_P  SCONN288_ADR50001P003C01  I125
  U1     AH61  DDR2_SA_DQS_DP8  SOCKET4677_AZIFS054P001C01  I91

M_C_CPU1_SA_DQS_DP<9>   @S9S_MB_2U_LIB.S9S_MB_2U(SCH_1):M_C_CPU1_SA_DQS_DP<9>
  J21    201  DQS9_A_P  SCONN288_ADR50001P013C01  I126
  J22    201  DQS9_A_P  SCONN288_ADR50001P003C01  I125
  U1     AF55  DDR2_SA_DQS_DP9  SOCKET4677_AZIFS054P001C01  I91

M_C_CPU1_SA_PAR   @S9S_MB_2U_LIB.S9S_MB_2U(SCH_1):M_C_CPU1_SA_PAR
  J21     74  PAR_A  SCONN288_ADR50001P013C01  I13
  J22     74  PAR_A  SCONN288_ADR50001P003C01  I51
  U1     T47  DDR2_SA_PAR  SOCKET4677_AZIFS054P001C01  I91

M_C_CPU1_SA_RSP<0>   @S9S_MB_2U_LIB.S9S_MB_2U(SCH_1):M_C_CPU1_SA_RSP<0>
  J21     86  LBD||RSP_N_A  SCONN288_ADR50001P013C01  I13
  U1     AC48  DDR2_A_RSP0  SOCKET4677_AZIFS054P001C01  I91

M_C_CPU1_SA_RSP<1>   @S9S_MB_2U_LIB.S9S_MB_2U(SCH_1):M_C_CPU1_SA_RSP<1>
  J22     86  LBD||RSP_N_A  SCONN288_ADR50001P003C01  I51
  U1     AD47  DDR2_A_RSP1  SOCKET4677_AZIFS054P001C01  I91

M_C_CPU1_SB_CA<0>   @S9S_MB_2U_LIB.S9S_MB_2U(SCH_1):M_C_CPU1_SB_CA<0>
  J21     76  CA0_B  SCONN288_ADR50001P013C01  I13
  J22     76  CA0_B  SCONN288_ADR50001P003C01  I51
  U1     W48  DDR2_SB_CA0  SOCKET4677_AZIFS054P001C01  I91

M_C_CPU1_SB_CA<1>   @S9S_MB_2U_LIB.S9S_MB_2U(SCH_1):M_C_CPU1_SB_CA<1>
  J21    221  CA1_B  SCONN288_ADR50001P013C01  I13
  J22    221  CA1_B  SCONN288_ADR50001P003C01  I51
  U1     Y47  DDR2_SB_CA1  SOCKET4677_AZIFS054P001C01  I91

M_C_CPU1_SB_CA<2>   @S9S_MB_2U_LIB.S9S_MB_2U(SCH_1):M_C_CPU1_SB_CA<2>
  J21     78  CA2_B  SCONN288_ADR50001P013C01  I13
  J22     78  CA2_B  SCONN288_ADR50001P003C01  I51
  U1     U41  DDR2_SB_CA2  SOCKET4677_AZIFS054P001C01  I91

M_C_CPU1_SB_CA<3>   @S9S_MB_2U_LIB.S9S_MB_2U(SCH_1):M_C_CPU1_SB_CA<3>
  J21    223  CA3_B  SCONN288_ADR50001P013C01  I13
  J22    223  CA3_B  SCONN288_ADR50001P003C01  I51
  U1     W41  DDR2_SB_CA3  SOCKET4677_AZIFS054P001C01  I91

M_C_CPU1_SB_CA<4>   @S9S_MB_2U_LIB.S9S_MB_2U(SCH_1):M_C_CPU1_SB_CA<4>
  J21     80  CA4_B  SCONN288_ADR50001P013C01  I13
  J22     80  CA4_B  SCONN288_ADR50001P003C01  I51
  U1     T40  DDR2_SB_CA4  SOCKET4677_AZIFS054P001C01  I91

M_C_CPU1_SB_CA<5>   @S9S_MB_2U_LIB.S9S_MB_2U(SCH_1):M_C_CPU1_SB_CA<5>
  J21    225  CA5_B  SCONN288_ADR50001P013C01  I13
  J22    225  CA5_B  SCONN288_ADR50001P003C01  I51
  U1     Y40  DDR2_SB_CA5  SOCKET4677_AZIFS054P001C01  I91

M_C_CPU1_SB_CA<6>   @S9S_MB_2U_LIB.S9S_MB_2U(SCH_1):M_C_CPU1_SB_CA<6>
  J21     82  CA6_B  SCONN288_ADR50001P013C01  I13
  J22     82  CA6_B  SCONN288_ADR50001P003C01  I51
  U1     R39  DDR2_SB_CA6  SOCKET4677_AZIFS054P001C01  I91

M_C_CPU1_SB_CB<0>   @S9S_MB_2U_LIB.S9S_MB_2U(SCH_1):M_C_CPU1_SB_CB<0>
  J21     96  CB_B0  SCONN288_ADR50001P013C01  I13
  J22     96  CB_B0  SCONN288_ADR50001P003C01  I51
  U1     T32  DDR2_SB_ECC0  SOCKET4677_AZIFS054P001C01  I91

M_C_CPU1_SB_CB<1>   @S9S_MB_2U_LIB.S9S_MB_2U(SCH_1):M_C_CPU1_SB_CB<1>
  J21     98  CB_B1  SCONN288_ADR50001P013C01  I13
  J22     98  CB_B1  SCONN288_ADR50001P003C01  I51
  U1     U31  DDR2_SB_ECC1  SOCKET4677_AZIFS054P001C01  I91

M_C_CPU1_SB_CB<2>   @S9S_MB_2U_LIB.S9S_MB_2U(SCH_1):M_C_CPU1_SB_CB<2>
  J21    241  CB_B2  SCONN288_ADR50001P013C01  I13
  J22    241  CB_B2  SCONN288_ADR50001P003C01  I51
  U1     Y32  DDR2_SB_ECC2  SOCKET4677_AZIFS054P001C01  I91

M_C_CPU1_SB_CB<3>   @S9S_MB_2U_LIB.S9S_MB_2U(SCH_1):M_C_CPU1_SB_CB<3>
  J21    243  CB_B3  SCONN288_ADR50001P013C01  I13
  J22    243  CB_B3  SCONN288_ADR50001P003C01  I51
  U1     W31  DDR2_SB_ECC3  SOCKET4677_AZIFS054P001C01  I91

M_C_CPU1_SB_CB<4>   @S9S_MB_2U_LIB.S9S_MB_2U(SCH_1):M_C_CPU1_SB_CB<4>
  J21     89  CB_B4  SCONN288_ADR50001P013C01  I13
  J22     89  CB_B4  SCONN288_ADR50001P003C01  I51
  U1     U35  DDR2_SB_ECC4  SOCKET4677_AZIFS054P001C01  I91

M_C_CPU1_SB_CB<5>   @S9S_MB_2U_LIB.S9S_MB_2U(SCH_1):M_C_CPU1_SB_CB<5>
  J21     91  CB_B5  SCONN288_ADR50001P013C01  I13
  J22     91  CB_B5  SCONN288_ADR50001P003C01  I51
  U1     T34  DDR2_SB_ECC5  SOCKET4677_AZIFS054P001C01  I91

M_C_CPU1_SB_CB<6>   @S9S_MB_2U_LIB.S9S_MB_2U(SCH_1):M_C_CPU1_SB_CB<6>
  J21    234  CB_B6  SCONN288_ADR50001P013C01  I13
  J22    234  CB_B6  SCONN288_ADR50001P003C01  I51
  U1     W35  DDR2_SB_ECC6  SOCKET4677_AZIFS054P001C01  I91

M_C_CPU1_SB_CB<7>   @S9S_MB_2U_LIB.S9S_MB_2U(SCH_1):M_C_CPU1_SB_CB<7>
  J21    236  CB_B7  SCONN288_ADR50001P013C01  I13
  J22    236  CB_B7  SCONN288_ADR50001P003C01  I51
  U1     Y34  DDR2_SB_ECC7  SOCKET4677_AZIFS054P001C01  I91

M_C_CPU1_SB_CS_N<0>   @S9S_MB_2U_LIB.S9S_MB_2U(SCH_1):M_C_CPU1_SB_CS_N<0>
  J21     84  CS0_N_B  SCONN288_ADR50001P013C01  I13
  U1     T38  DDR2_SB_CS0_N  SOCKET4677_AZIFS054P001C01  I91

M_C_CPU1_SB_CS_N<1>   @S9S_MB_2U_LIB.S9S_MB_2U(SCH_1):M_C_CPU1_SB_CS_N<1>
  J21    229  CS1_N_B  SCONN288_ADR50001P013C01  I13
  U1     U37  DDR2_SB_CS1_N  SOCKET4677_AZIFS054P001C01  I91

M_C_CPU1_SB_CS_N<2>   @S9S_MB_2U_LIB.S9S_MB_2U(SCH_1):M_C_CPU1_SB_CS_N<2>
  J22     84  CS0_N_B  SCONN288_ADR50001P003C01  I51
  U1     Y38  DDR2_SB_CS2_N  SOCKET4677_AZIFS054P001C01  I91

M_C_CPU1_SB_CS_N<3>   @S9S_MB_2U_LIB.S9S_MB_2U(SCH_1):M_C_CPU1_SB_CS_N<3>
  J22    229  CS1_N_B  SCONN288_ADR50001P003C01  I51
  U1     W37  DDR2_SB_CS3_N  SOCKET4677_AZIFS054P001C01  I91

M_C_CPU1_SB_DQ<0>   @S9S_MB_2U_LIB.S9S_MB_2U(SCH_1):M_C_CPU1_SB_DQ<0>
  J21    100  DQ_B0  SCONN288_ADR50001P013C01  I13
  J22    100  DQ_B0  SCONN288_ADR50001P003C01  I51
  U1     AD38  DDR2_SB_DQ0  SOCKET4677_AZIFS054P001C01  I91

M_C_CPU1_SB_DQ<1>   @S9S_MB_2U_LIB.S9S_MB_2U(SCH_1):M_C_CPU1_SB_DQ<1>
  J21    102  DQ_B1  SCONN288_ADR50001P013C01  I13
  J22    102  DQ_B1  SCONN288_ADR50001P003C01  I51
  U1     AC37  DDR2_SB_DQ1  SOCKET4677_AZIFS054P001C01  I91

M_C_CPU1_SB_DQ<2>   @S9S_MB_2U_LIB.S9S_MB_2U(SCH_1):M_C_CPU1_SB_DQ<2>
  J21    245  DQ_B2  SCONN288_ADR50001P013C01  I13
  J22    245  DQ_B2  SCONN288_ADR50001P003C01  I51
  U1     AF38  DDR2_SB_DQ2  SOCKET4677_AZIFS054P001C01  I91

M_C_CPU1_SB_DQ<3>   @S9S_MB_2U_LIB.S9S_MB_2U(SCH_1):M_C_CPU1_SB_DQ<3>
  J21    247  DQ_B3  SCONN288_ADR50001P013C01  I13
  J22    247  DQ_B3  SCONN288_ADR50001P003C01  I51
  U1     AG37  DDR2_SB_DQ3  SOCKET4677_AZIFS054P001C01  I91

M_C_CPU1_SB_DQ<4>   @S9S_MB_2U_LIB.S9S_MB_2U(SCH_1):M_C_CPU1_SB_DQ<4>
  J21    107  DQ_B4  SCONN288_ADR50001P013C01  I13
  J22    107  DQ_B4  SCONN288_ADR50001P003C01  I51
  U1     AC35  DDR2_SB_DQ4  SOCKET4677_AZIFS054P001C01  I91

M_C_CPU1_SB_DQ<5>   @S9S_MB_2U_LIB.S9S_MB_2U(SCH_1):M_C_CPU1_SB_DQ<5>
  J21    109  DQ_B5  SCONN288_ADR50001P013C01  I13
  J22    109  DQ_B5  SCONN288_ADR50001P003C01  I51
  U1     AD34  DDR2_SB_DQ5  SOCKET4677_AZIFS054P001C01  I91

M_C_CPU1_SB_DQ<6>   @S9S_MB_2U_LIB.S9S_MB_2U(SCH_1):M_C_CPU1_SB_DQ<6>
  J21    252  DQ_B6  SCONN288_ADR50001P013C01  I13
  J22    252  DQ_B6  SCONN288_ADR50001P003C01  I51
  U1     AG35  DDR2_SB_DQ6  SOCKET4677_AZIFS054P001C01  I91

M_C_CPU1_SB_DQ<7>   @S9S_MB_2U_LIB.S9S_MB_2U(SCH_1):M_C_CPU1_SB_DQ<7>
  J21    254  DQ_B7  SCONN288_ADR50001P013C01  I13
  J22    254  DQ_B7  SCONN288_ADR50001P003C01  I51
  U1     AF34  DDR2_SB_DQ7  SOCKET4677_AZIFS054P001C01  I91

M_C_CPU1_SB_DQ<8>   @S9S_MB_2U_LIB.S9S_MB_2U(SCH_1):M_C_CPU1_SB_DQ<8>
  J21    111  DQ_B8  SCONN288_ADR50001P013C01  I13
  J22    111  DQ_B8  SCONN288_ADR50001P003C01  I51
  U1     AD32  DDR2_SB_DQ8  SOCKET4677_AZIFS054P001C01  I91

M_C_CPU1_SB_DQ<9>   @S9S_MB_2U_LIB.S9S_MB_2U(SCH_1):M_C_CPU1_SB_DQ<9>
  J21    113  DQ_B9  SCONN288_ADR50001P013C01  I13
  J22    113  DQ_B9  SCONN288_ADR50001P003C01  I51
  U1     AC31  DDR2_SB_DQ9  SOCKET4677_AZIFS054P001C01  I91

M_C_CPU1_SB_DQ<10>   @S9S_MB_2U_LIB.S9S_MB_2U(SCH_1):M_C_CPU1_SB_DQ<10>
  J21    256  DQ_B10  SCONN288_ADR50001P013C01  I13
  J22    256  DQ_B10  SCONN288_ADR50001P003C01  I51
  U1     AF32  DDR2_SB_DQ10  SOCKET4677_AZIFS054P001C01  I91

M_C_CPU1_SB_DQ<11>   @S9S_MB_2U_LIB.S9S_MB_2U(SCH_1):M_C_CPU1_SB_DQ<11>
  J21    258  DQ_B11  SCONN288_ADR50001P013C01  I13
  J22    258  DQ_B11  SCONN288_ADR50001P003C01  I51
  U1     AG31  DDR2_SB_DQ11  SOCKET4677_AZIFS054P001C01  I91

M_C_CPU1_SB_DQ<12>   @S9S_MB_2U_LIB.S9S_MB_2U(SCH_1):M_C_CPU1_SB_DQ<12>
  J21    118  DQ_B12  SCONN288_ADR50001P013C01  I13
  J22    118  DQ_B12  SCONN288_ADR50001P003C01  I51
  U1     AC29  DDR2_SB_DQ12  SOCKET4677_AZIFS054P001C01  I91

M_C_CPU1_SB_DQ<13>   @S9S_MB_2U_LIB.S9S_MB_2U(SCH_1):M_C_CPU1_SB_DQ<13>
  J21    120  DQ_B13  SCONN288_ADR50001P013C01  I13
  J22    120  DQ_B13  SCONN288_ADR50001P003C01  I51
  U1     AD28  DDR2_SB_DQ13  SOCKET4677_AZIFS054P001C01  I91

M_C_CPU1_SB_DQ<14>   @S9S_MB_2U_LIB.S9S_MB_2U(SCH_1):M_C_CPU1_SB_DQ<14>
  J21    263  DQ_B14  SCONN288_ADR50001P013C01  I13
  J22    263  DQ_B14  SCONN288_ADR50001P003C01  I51
  U1     AG29  DDR2_SB_DQ14  SOCKET4677_AZIFS054P001C01  I91

M_C_CPU1_SB_DQ<15>   @S9S_MB_2U_LIB.S9S_MB_2U(SCH_1):M_C_CPU1_SB_DQ<15>
  J21    265  DQ_B15  SCONN288_ADR50001P013C01  I13
  J22    265  DQ_B15  SCONN288_ADR50001P003C01  I51
  U1     AF28  DDR2_SB_DQ15  SOCKET4677_AZIFS054P001C01  I91

M_C_CPU1_SB_DQ<16>   @S9S_MB_2U_LIB.S9S_MB_2U(SCH_1):M_C_CPU1_SB_DQ<16>
  J21    122  DQ_B16  SCONN288_ADR50001P013C01  I13
  J22    122  DQ_B16  SCONN288_ADR50001P003C01  I51
  U1     U23  DDR2_SB_DQ16  SOCKET4677_AZIFS054P001C01  I91

M_C_CPU1_SB_DQ<17>   @S9S_MB_2U_LIB.S9S_MB_2U(SCH_1):M_C_CPU1_SB_DQ<17>
  J21    124  DQ_B17  SCONN288_ADR50001P013C01  I13
  J22    124  DQ_B17  SCONN288_ADR50001P003C01  I51
  U1     T22  DDR2_SB_DQ17  SOCKET4677_AZIFS054P001C01  I91

M_C_CPU1_SB_DQ<18>   @S9S_MB_2U_LIB.S9S_MB_2U(SCH_1):M_C_CPU1_SB_DQ<18>
  J21    267  DQ_B18  SCONN288_ADR50001P013C01  I13
  J22    267  DQ_B18  SCONN288_ADR50001P003C01  I51
  U1     W23  DDR2_SB_DQ18  SOCKET4677_AZIFS054P001C01  I91

M_C_CPU1_SB_DQ<19>   @S9S_MB_2U_LIB.S9S_MB_2U(SCH_1):M_C_CPU1_SB_DQ<19>
  J21    269  DQ_B19  SCONN288_ADR50001P013C01  I13
  J22    269  DQ_B19  SCONN288_ADR50001P003C01  I51
  U1     Y22  DDR2_SB_DQ19  SOCKET4677_AZIFS054P001C01  I91

M_C_CPU1_SB_DQ<20>   @S9S_MB_2U_LIB.S9S_MB_2U(SCH_1):M_C_CPU1_SB_DQ<20>
  J21    129  DQ_B20  SCONN288_ADR50001P013C01  I13
  J22    129  DQ_B20  SCONN288_ADR50001P003C01  I51
  U1     T20  DDR2_SB_DQ20  SOCKET4677_AZIFS054P001C01  I91

M_C_CPU1_SB_DQ<21>   @S9S_MB_2U_LIB.S9S_MB_2U(SCH_1):M_C_CPU1_SB_DQ<21>
  J21    131  DQ_B21  SCONN288_ADR50001P013C01  I13
  J22    131  DQ_B21  SCONN288_ADR50001P003C01  I51
  U1     U19  DDR2_SB_DQ21  SOCKET4677_AZIFS054P001C01  I91

M_C_CPU1_SB_DQ<22>   @S9S_MB_2U_LIB.S9S_MB_2U(SCH_1):M_C_CPU1_SB_DQ<22>
  J21    274  DQ_B22  SCONN288_ADR50001P013C01  I13
  J22    274  DQ_B22  SCONN288_ADR50001P003C01  I51
  U1     Y20  DDR2_SB_DQ22  SOCKET4677_AZIFS054P001C01  I91

M_C_CPU1_SB_DQ<23>   @S9S_MB_2U_LIB.S9S_MB_2U(SCH_1):M_C_CPU1_SB_DQ<23>
  J21    276  DQ_B23  SCONN288_ADR50001P013C01  I13
  J22    276  DQ_B23  SCONN288_ADR50001P003C01  I51
  U1     W19  DDR2_SB_DQ23  SOCKET4677_AZIFS054P001C01  I91

M_C_CPU1_SB_DQ<24>   @S9S_MB_2U_LIB.S9S_MB_2U(SCH_1):M_C_CPU1_SB_DQ<24>
  J21    133  DQ_B24  SCONN288_ADR50001P013C01  I13
  J22    133  DQ_B24  SCONN288_ADR50001P003C01  I51
  U1     AD20  DDR2_SB_DQ24  SOCKET4677_AZIFS054P001C01  I91

M_C_CPU1_SB_DQ<25>   @S9S_MB_2U_LIB.S9S_MB_2U(SCH_1):M_C_CPU1_SB_DQ<25>
  J21    135  DQ_B25  SCONN288_ADR50001P013C01  I13
  J22    135  DQ_B25  SCONN288_ADR50001P003C01  I51
  U1     AC19  DDR2_SB_DQ25  SOCKET4677_AZIFS054P001C01  I91

M_C_CPU1_SB_DQ<26>   @S9S_MB_2U_LIB.S9S_MB_2U(SCH_1):M_C_CPU1_SB_DQ<26>
  J21    278  DQ_B26  SCONN288_ADR50001P013C01  I13
  J22    278  DQ_B26  SCONN288_ADR50001P003C01  I51
  U1     AF20  DDR2_SB_DQ26  SOCKET4677_AZIFS054P001C01  I91

M_C_CPU1_SB_DQ<27>   @S9S_MB_2U_LIB.S9S_MB_2U(SCH_1):M_C_CPU1_SB_DQ<27>
  J21    280  DQ_B27  SCONN288_ADR50001P013C01  I13
  J22    280  DQ_B27  SCONN288_ADR50001P003C01  I51
  U1     AG19  DDR2_SB_DQ27  SOCKET4677_AZIFS054P001C01  I91

M_C_CPU1_SB_DQ<28>   @S9S_MB_2U_LIB.S9S_MB_2U(SCH_1):M_C_CPU1_SB_DQ<28>
  J21    140  DQ_B28  SCONN288_ADR50001P013C01  I13
  J22    140  DQ_B28  SCONN288_ADR50001P003C01  I51
  U1     AA17  DDR2_SB_DQ28  SOCKET4677_AZIFS054P001C01  I91

M_C_CPU1_SB_DQ<29>   @S9S_MB_2U_LIB.S9S_MB_2U(SCH_1):M_C_CPU1_SB_DQ<29>
  J21    142  DQ_B29  SCONN288_ADR50001P013C01  I13
  J22    142  DQ_B29  SCONN288_ADR50001P003C01  I51
  U1     AG17  DDR2_SB_DQ29  SOCKET4677_AZIFS054P001C01  I91

M_C_CPU1_SB_DQ<30>   @S9S_MB_2U_LIB.S9S_MB_2U(SCH_1):M_C_CPU1_SB_DQ<30>
  J21    285  DQ_B30  SCONN288_ADR50001P013C01  I13
  J22    285  DQ_B30  SCONN288_ADR50001P003C01  I51
  U1     AC17  DDR2_SB_DQ30  SOCKET4677_AZIFS054P001C01  I91

M_C_CPU1_SB_DQ<31>   @S9S_MB_2U_LIB.S9S_MB_2U(SCH_1):M_C_CPU1_SB_DQ<31>
  J21    287  DQ_B31  SCONN288_ADR50001P013C01  I13
  J22    287  DQ_B31  SCONN288_ADR50001P003C01  I51
  U1     AJ17  DDR2_SB_DQ31  SOCKET4677_AZIFS054P001C01  I91

M_C_CPU1_SB_DQS_DN<0>   @S9S_MB_2U_LIB.S9S_MB_2U(SCH_1):M_C_CPU1_SB_DQS_DN<0>
  J21    105  DQS0_B_N  SCONN288_ADR50001P013C01  I126
  J22    105  DQS0_B_N  SCONN288_ADR50001P003C01  I125
  U1     AB36  DDR2_SB_DQS_DN0  SOCKET4677_AZIFS054P001C01  I91

M_C_CPU1_SB_DQS_DN<1>   @S9S_MB_2U_LIB.S9S_MB_2U(SCH_1):M_C_CPU1_SB_DQS_DN<1>
  J21    116  DQS1_B_N  SCONN288_ADR50001P013C01  I126
  J22    116  DQS1_B_N  SCONN288_ADR50001P003C01  I125
  U1     AB30  DDR2_SB_DQS_DN1  SOCKET4677_AZIFS054P001C01  I91

M_C_CPU1_SB_DQS_DN<2>   @S9S_MB_2U_LIB.S9S_MB_2U(SCH_1):M_C_CPU1_SB_DQS_DN<2>
  J21    127  DQS2_B_N  SCONN288_ADR50001P013C01  I126
  J22    127  DQS2_B_N  SCONN288_ADR50001P003C01  I125
  U1     R21  DDR2_SB_DQS_DN2  SOCKET4677_AZIFS054P001C01  I91

M_C_CPU1_SB_DQS_DN<3>   @S9S_MB_2U_LIB.S9S_MB_2U(SCH_1):M_C_CPU1_SB_DQS_DN<3>
  J21    138  DQS3_B_N  SCONN288_ADR50001P013C01  I126
  J22    138  DQS3_B_N  SCONN288_ADR50001P003C01  I125
  U1     AB18  DDR2_SB_DQS_DN3  SOCKET4677_AZIFS054P001C01  I91

M_C_CPU1_SB_DQS_DN<4>   @S9S_MB_2U_LIB.S9S_MB_2U(SCH_1):M_C_CPU1_SB_DQS_DN<4>
  J21    238  DQS4_B_N  SCONN288_ADR50001P013C01  I126
  J22    238  DQS4_B_N  SCONN288_ADR50001P003C01  I125
  U1     W33  DDR2_SB_DQS_DN4  SOCKET4677_AZIFS054P001C01  I91

M_C_CPU1_SB_DQS_DN<5>   @S9S_MB_2U_LIB.S9S_MB_2U(SCH_1):M_C_CPU1_SB_DQS_DN<5>
  J21    249  DQS5_B_N  SCONN288_ADR50001P013C01  I126
  J22    249  DQS5_B_N  SCONN288_ADR50001P003C01  I125
  U1     AF36  DDR2_SB_DQS_DN5  SOCKET4677_AZIFS054P001C01  I91

M_C_CPU1_SB_DQS_DN<6>   @S9S_MB_2U_LIB.S9S_MB_2U(SCH_1):M_C_CPU1_SB_DQS_DN<6>
  J21    260  DQS6_B_N  SCONN288_ADR50001P013C01  I126
  J22    260  DQS6_B_N  SCONN288_ADR50001P003C01  I125
  U1     AF30  DDR2_SB_DQS_DN6  SOCKET4677_AZIFS054P001C01  I91

M_C_CPU1_SB_DQS_DN<7>   @S9S_MB_2U_LIB.S9S_MB_2U(SCH_1):M_C_CPU1_SB_DQS_DN<7>
  J21    271  DQS7_B_N  SCONN288_ADR50001P013C01  I126
  J22    271  DQS7_B_N  SCONN288_ADR50001P003C01  I125
  U1     W21  DDR2_SB_DQS_DN7  SOCKET4677_AZIFS054P001C01  I91

M_C_CPU1_SB_DQS_DN<8>   @S9S_MB_2U_LIB.S9S_MB_2U(SCH_1):M_C_CPU1_SB_DQS_DN<8>
  J21    282  DQS8_B_N  SCONN288_ADR50001P013C01  I126
  J22    282  DQS8_B_N  SCONN288_ADR50001P003C01  I125
  U1     AF18  DDR2_SB_DQS_DN8  SOCKET4677_AZIFS054P001C01  I91

M_C_CPU1_SB_DQS_DN<9>   @S9S_MB_2U_LIB.S9S_MB_2U(SCH_1):M_C_CPU1_SB_DQS_DN<9>
  J21     94  DQS9_B_N  SCONN288_ADR50001P013C01  I126
  J22     94  DQS9_B_N  SCONN288_ADR50001P003C01  I125
  U1     R33  DDR2_SB_DQS_DN9  SOCKET4677_AZIFS054P001C01  I91

M_C_CPU1_SB_DQS_DP<0>   @S9S_MB_2U_LIB.S9S_MB_2U(SCH_1):M_C_CPU1_SB_DQS_DP<0>
  J21    104  DQS0_B_P  SCONN288_ADR50001P013C01  I126
  J22    104  DQS0_B_P  SCONN288_ADR50001P003C01  I125
  U1     AD36  DDR2_SB_DQS_DP0  SOCKET4677_AZIFS054P001C01  I91

M_C_CPU1_SB_DQS_DP<1>   @S9S_MB_2U_LIB.S9S_MB_2U(SCH_1):M_C_CPU1_SB_DQS_DP<1>
  J21    115  DQS1_B_P  SCONN288_ADR50001P013C01  I126
  J22    115  DQS1_B_P  SCONN288_ADR50001P003C01  I125
  U1     AD30  DDR2_SB_DQS_DP1  SOCKET4677_AZIFS054P001C01  I91

M_C_CPU1_SB_DQS_DP<2>   @S9S_MB_2U_LIB.S9S_MB_2U(SCH_1):M_C_CPU1_SB_DQS_DP<2>
  J21    126  DQS2_B_P  SCONN288_ADR50001P013C01  I126
  J22    126  DQS2_B_P  SCONN288_ADR50001P003C01  I125
  U1     U21  DDR2_SB_DQS_DP2  SOCKET4677_AZIFS054P001C01  I91

M_C_CPU1_SB_DQS_DP<3>   @S9S_MB_2U_LIB.S9S_MB_2U(SCH_1):M_C_CPU1_SB_DQS_DP<3>
  J21    137  DQS3_B_P  SCONN288_ADR50001P013C01  I126
  J22    137  DQS3_B_P  SCONN288_ADR50001P003C01  I125
  U1     AD18  DDR2_SB_DQS_DP3  SOCKET4677_AZIFS054P001C01  I91

M_C_CPU1_SB_DQS_DP<4>   @S9S_MB_2U_LIB.S9S_MB_2U(SCH_1):M_C_CPU1_SB_DQS_DP<4>
  J21    239  DQS4_B_P  SCONN288_ADR50001P013C01  I126
  J22    239  DQS4_B_P  SCONN288_ADR50001P003C01  I125
  U1     AA33  DDR2_SB_DQS_DP4  SOCKET4677_AZIFS054P001C01  I91

M_C_CPU1_SB_DQS_DP<5>   @S9S_MB_2U_LIB.S9S_MB_2U(SCH_1):M_C_CPU1_SB_DQS_DP<5>
  J21    250  DQS5_B_P  SCONN288_ADR50001P013C01  I126
  J22    250  DQS5_B_P  SCONN288_ADR50001P003C01  I125
  U1     AH36  DDR2_SB_DQS_DP5  SOCKET4677_AZIFS054P001C01  I91

M_C_CPU1_SB_DQS_DP<6>   @S9S_MB_2U_LIB.S9S_MB_2U(SCH_1):M_C_CPU1_SB_DQS_DP<6>
  J21    261  DQS6_B_P  SCONN288_ADR50001P013C01  I126
  J22    261  DQS6_B_P  SCONN288_ADR50001P003C01  I125
  U1     AH30  DDR2_SB_DQS_DP6  SOCKET4677_AZIFS054P001C01  I91

M_C_CPU1_SB_DQS_DP<7>   @S9S_MB_2U_LIB.S9S_MB_2U(SCH_1):M_C_CPU1_SB_DQS_DP<7>
  J21    272  DQS7_B_P  SCONN288_ADR50001P013C01  I126
  J22    272  DQS7_B_P  SCONN288_ADR50001P003C01  I125
  U1     AA21  DDR2_SB_DQS_DP7  SOCKET4677_AZIFS054P001C01  I91

M_C_CPU1_SB_DQS_DP<8>   @S9S_MB_2U_LIB.S9S_MB_2U(SCH_1):M_C_CPU1_SB_DQS_DP<8>
  J21    283  DQS8_B_P  SCONN288_ADR50001P013C01  I126
  J22    283  DQS8_B_P  SCONN288_ADR50001P003C01  I125
  U1     AH18  DDR2_SB_DQS_DP8  SOCKET4677_AZIFS054P001C01  I91

M_C_CPU1_SB_DQS_DP<9>   @S9S_MB_2U_LIB.S9S_MB_2U(SCH_1):M_C_CPU1_SB_DQS_DP<9>
  J21     93  DQS9_B_P  SCONN288_ADR50001P013C01  I126
  J22     93  DQS9_B_P  SCONN288_ADR50001P003C01  I125
  U1     U33  DDR2_SB_DQS_DP9  SOCKET4677_AZIFS054P001C01  I91

M_C_CPU1_SB_PAR   @S9S_MB_2U_LIB.S9S_MB_2U(SCH_1):M_C_CPU1_SB_PAR
  J21    227  PAR_B  SCONN288_ADR50001P013C01  I13
  J22    227  PAR_B  SCONN288_ADR50001P003C01  I51
  U1     AA39  DDR2_SB_PAR  SOCKET4677_AZIFS054P001C01  I91

M_C_CPU1_SB_RSP<0>   @S9S_MB_2U_LIB.S9S_MB_2U(SCH_1):M_C_CPU1_SB_RSP<0>
  J21     87  LBS||RSP_N_B  SCONN288_ADR50001P013C01  I13
  U1     AG48  DDR2_B_RSP0  SOCKET4677_AZIFS054P001C01  I91

M_C_CPU1_SB_RSP<1>   @S9S_MB_2U_LIB.S9S_MB_2U(SCH_1):M_C_CPU1_SB_RSP<1>
  J22     87  LBS||RSP_N_B  SCONN288_ADR50001P003C01  I51
  U1     AF47  DDR2_B_RSP1  SOCKET4677_AZIFS054P001C01  I91

M_D_CPU0_ALERT_N   @S9S_MB_2U_LIB.S9S_MB_2U(SCH_1):M_D_CPU0_ALERT_N
  J7      62  ALERT_N  SCONN288_ADR50001P013C01  I12
  J8      62  ALERT_N  SCONN288_ADR50001P003C01  I50
  U2     AV47  DDR3_ALERT_N  SOCKET4677_AZIFS054P001C01  I169

M_D_CPU0_CLK_DN<0>   @S9S_MB_2U_LIB.S9S_MB_2U(SCH_1):M_D_CPU0_CLK_DN<0>
  J7     218   CK_N  SCONN288_ADR50001P013C01  I12
  U2     AJ45  DDR3_CLK_DN0  SOCKET4677_AZIFS054P001C01  I169

M_D_CPU0_CLK_DN<1>   @S9S_MB_2U_LIB.S9S_MB_2U(SCH_1):M_D_CPU0_CLK_DN<1>
  J8     218   CK_N  SCONN288_ADR50001P003C01  I50
  U2     AN45  DDR3_CLK_DN1  SOCKET4677_AZIFS054P001C01  I169

M_D_CPU0_CLK_DP<0>   @S9S_MB_2U_LIB.S9S_MB_2U(SCH_1):M_D_CPU0_CLK_DP<0>
  J7     217   CK_P  SCONN288_ADR50001P013C01  I12
  U2     AL45  DDR3_CLK_DP0  SOCKET4677_AZIFS054P001C01  I169

M_D_CPU0_CLK_DP<1>   @S9S_MB_2U_LIB.S9S_MB_2U(SCH_1):M_D_CPU0_CLK_DP<1>
  J8     217   CK_P  SCONN288_ADR50001P003C01  I50
  U2     AR45  DDR3_CLK_DP1  SOCKET4677_AZIFS054P001C01  I169

M_D_CPU0_SA_CA<0>   @S9S_MB_2U_LIB.S9S_MB_2U(SCH_1):M_D_CPU0_SA_CA<0>
  J7      66  CA0_A  SCONN288_ADR50001P013C01  I12
  J8      66  CA0_A  SCONN288_ADR50001P003C01  I50
  U2     AJ52  DDR3_SA_CA0  SOCKET4677_AZIFS054P001C01  I169

M_D_CPU0_SA_CA<1>   @S9S_MB_2U_LIB.S9S_MB_2U(SCH_1):M_D_CPU0_SA_CA<1>
  J7     211  CA1_A  SCONN288_ADR50001P013C01  I12
  J8     211  CA1_A  SCONN288_ADR50001P003C01  I50
  U2     AR52  DDR3_SA_CA1  SOCKET4677_AZIFS054P001C01  I169

M_D_CPU0_SA_CA<2>   @S9S_MB_2U_LIB.S9S_MB_2U(SCH_1):M_D_CPU0_SA_CA<2>
  J7      68  CA2_A  SCONN288_ADR50001P013C01  I12
  J8      68  CA2_A  SCONN288_ADR50001P003C01  I50
  U2     AK51  DDR3_SA_CA2  SOCKET4677_AZIFS054P001C01  I169

M_D_CPU0_SA_CA<3>   @S9S_MB_2U_LIB.S9S_MB_2U(SCH_1):M_D_CPU0_SA_CA<3>
  J7     213  CA3_A  SCONN288_ADR50001P013C01  I12
  J8     213  CA3_A  SCONN288_ADR50001P003C01  I50
  U2     AP51  DDR3_SA_CA3  SOCKET4677_AZIFS054P001C01  I169

M_D_CPU0_SA_CA<4>   @S9S_MB_2U_LIB.S9S_MB_2U(SCH_1):M_D_CPU0_SA_CA<4>
  J7      70  CA4_A  SCONN288_ADR50001P013C01  I12
  J8      70  CA4_A  SCONN288_ADR50001P003C01  I50
  U2     AL50  DDR3_SA_CA4  SOCKET4677_AZIFS054P001C01  I169

M_D_CPU0_SA_CA<5>   @S9S_MB_2U_LIB.S9S_MB_2U(SCH_1):M_D_CPU0_SA_CA<5>
  J7     215  CA5_A  SCONN288_ADR50001P013C01  I12
  J8     215  CA5_A  SCONN288_ADR50001P003C01  I50
  U2     AN50  DDR3_SA_CA5  SOCKET4677_AZIFS054P001C01  I169

M_D_CPU0_SA_CA<6>   @S9S_MB_2U_LIB.S9S_MB_2U(SCH_1):M_D_CPU0_SA_CA<6>
  J7      72  CA6_A  SCONN288_ADR50001P013C01  I12
  J8      72  CA6_A  SCONN288_ADR50001P003C01  I50
  U2     AN43  DDR3_SA_CA6  SOCKET4677_AZIFS054P001C01  I169

M_D_CPU0_SA_CB<0>   @S9S_MB_2U_LIB.S9S_MB_2U(SCH_1):M_D_CPU0_SA_CB<0>
  J7      51  CB_A0  SCONN288_ADR50001P013C01  I12
  J8      51  CB_A0  SCONN288_ADR50001P003C01  I50
  U2     AL60  DDR3_SA_ECC0  SOCKET4677_AZIFS054P001C01  I169

M_D_CPU0_SA_CB<1>   @S9S_MB_2U_LIB.S9S_MB_2U(SCH_1):M_D_CPU0_SA_CB<1>
  J7      53  CB_A1  SCONN288_ADR50001P013C01  I12
  J8      53  CB_A1  SCONN288_ADR50001P003C01  I50
  U2     AK59  DDR3_SA_ECC1  SOCKET4677_AZIFS054P001C01  I169

M_D_CPU0_SA_CB<2>   @S9S_MB_2U_LIB.S9S_MB_2U(SCH_1):M_D_CPU0_SA_CB<2>
  J7     196  CB_A2  SCONN288_ADR50001P013C01  I12
  J8     196  CB_A2  SCONN288_ADR50001P003C01  I50
  U2     AN60  DDR3_SA_ECC2  SOCKET4677_AZIFS054P001C01  I169

M_D_CPU0_SA_CB<3>   @S9S_MB_2U_LIB.S9S_MB_2U(SCH_1):M_D_CPU0_SA_CB<3>
  J7     198  CB_A3  SCONN288_ADR50001P013C01  I12
  J8     198  CB_A3  SCONN288_ADR50001P003C01  I50
  U2     AP59  DDR3_SA_ECC3  SOCKET4677_AZIFS054P001C01  I169

M_D_CPU0_SA_CB<4>   @S9S_MB_2U_LIB.S9S_MB_2U(SCH_1):M_D_CPU0_SA_CB<4>
  J7      58  CB_A4  SCONN288_ADR50001P013C01  I12
  J8      58  CB_A4  SCONN288_ADR50001P003C01  I50
  U2     AK57  DDR3_SA_ECC4  SOCKET4677_AZIFS054P001C01  I169

M_D_CPU0_SA_CB<5>   @S9S_MB_2U_LIB.S9S_MB_2U(SCH_1):M_D_CPU0_SA_CB<5>
  J7      60  CB_A5  SCONN288_ADR50001P013C01  I12
  J8      60  CB_A5  SCONN288_ADR50001P003C01  I50
  U2     AL56  DDR3_SA_ECC5  SOCKET4677_AZIFS054P001C01  I169

M_D_CPU0_SA_CB<6>   @S9S_MB_2U_LIB.S9S_MB_2U(SCH_1):M_D_CPU0_SA_CB<6>
  J7     203  CB_A6  SCONN288_ADR50001P013C01  I12
  J8     203  CB_A6  SCONN288_ADR50001P003C01  I50
  U2     AP57  DDR3_SA_ECC6  SOCKET4677_AZIFS054P001C01  I169

M_D_CPU0_SA_CB<7>   @S9S_MB_2U_LIB.S9S_MB_2U(SCH_1):M_D_CPU0_SA_CB<7>
  J7     205  CB_A7  SCONN288_ADR50001P013C01  I12
  J8     205  CB_A7  SCONN288_ADR50001P003C01  I50
  U2     AN56  DDR3_SA_ECC7  SOCKET4677_AZIFS054P001C01  I169

M_D_CPU0_SA_CS_N<0>   @S9S_MB_2U_LIB.S9S_MB_2U(SCH_1):M_D_CPU0_SA_CS_N<0>
  J7      64  CS0_N_A  SCONN288_ADR50001P013C01  I12
  U2     AL54  DDR3_SA_CS0_N  SOCKET4677_AZIFS054P001C01  I169

M_D_CPU0_SA_CS_N<1>   @S9S_MB_2U_LIB.S9S_MB_2U(SCH_1):M_D_CPU0_SA_CS_N<1>
  J7     209  CS1_N_A  SCONN288_ADR50001P013C01  I12
  U2     AK53  DDR3_SA_CS1_N  SOCKET4677_AZIFS054P001C01  I169

M_D_CPU0_SA_CS_N<2>   @S9S_MB_2U_LIB.S9S_MB_2U(SCH_1):M_D_CPU0_SA_CS_N<2>
  J8      64  CS0_N_A  SCONN288_ADR50001P003C01  I50
  U2     AN54  DDR3_SA_CS2_N  SOCKET4677_AZIFS054P001C01  I169

M_D_CPU0_SA_CS_N<3>   @S9S_MB_2U_LIB.S9S_MB_2U(SCH_1):M_D_CPU0_SA_CS_N<3>
  J8     209  CS1_N_A  SCONN288_ADR50001P003C01  I50
  U2     AP53  DDR3_SA_CS3_N  SOCKET4677_AZIFS054P001C01  I169

M_D_CPU0_SA_DQ<0>   @S9S_MB_2U_LIB.S9S_MB_2U(SCH_1):M_D_CPU0_SA_DQ<0>
  J7       7  DQ_A0  SCONN288_ADR50001P013C01  I12
  J8       7  DQ_A0  SCONN288_ADR50001P003C01  I50
  U2     AD75  DDR3_SA_DQ0  SOCKET4677_AZIFS054P001C01  I169

M_D_CPU0_SA_DQ<1>   @S9S_MB_2U_LIB.S9S_MB_2U(SCH_1):M_D_CPU0_SA_DQ<1>
  J7       9  DQ_A1  SCONN288_ADR50001P013C01  I12
  J8       9  DQ_A1  SCONN288_ADR50001P003C01  I50
  U2     AC74  DDR3_SA_DQ1  SOCKET4677_AZIFS054P001C01  I169

M_D_CPU0_SA_DQ<2>   @S9S_MB_2U_LIB.S9S_MB_2U(SCH_1):M_D_CPU0_SA_DQ<2>
  J7     152  DQ_A2  SCONN288_ADR50001P013C01  I12
  J8     152  DQ_A2  SCONN288_ADR50001P003C01  I50
  U2     AF75  DDR3_SA_DQ2  SOCKET4677_AZIFS054P001C01  I169

M_D_CPU0_SA_DQ<3>   @S9S_MB_2U_LIB.S9S_MB_2U(SCH_1):M_D_CPU0_SA_DQ<3>
  J7     154  DQ_A3  SCONN288_ADR50001P013C01  I12
  J8     154  DQ_A3  SCONN288_ADR50001P003C01  I50
  U2     AG74  DDR3_SA_DQ3  SOCKET4677_AZIFS054P001C01  I169

M_D_CPU0_SA_DQ<4>   @S9S_MB_2U_LIB.S9S_MB_2U(SCH_1):M_D_CPU0_SA_DQ<4>
  J7      14  DQ_A4  SCONN288_ADR50001P013C01  I12
  J8      14  DQ_A4  SCONN288_ADR50001P003C01  I50
  U2     AC72  DDR3_SA_DQ4  SOCKET4677_AZIFS054P001C01  I169

M_D_CPU0_SA_DQ<5>   @S9S_MB_2U_LIB.S9S_MB_2U(SCH_1):M_D_CPU0_SA_DQ<5>
  J7      16  DQ_A5  SCONN288_ADR50001P013C01  I12
  J8      16  DQ_A5  SCONN288_ADR50001P003C01  I50
  U2     AD71  DDR3_SA_DQ5  SOCKET4677_AZIFS054P001C01  I169

M_D_CPU0_SA_DQ<6>   @S9S_MB_2U_LIB.S9S_MB_2U(SCH_1):M_D_CPU0_SA_DQ<6>
  J7     159  DQ_A6  SCONN288_ADR50001P013C01  I12
  J8     159  DQ_A6  SCONN288_ADR50001P003C01  I50
  U2     AG72  DDR3_SA_DQ6  SOCKET4677_AZIFS054P001C01  I169

M_D_CPU0_SA_DQ<7>   @S9S_MB_2U_LIB.S9S_MB_2U(SCH_1):M_D_CPU0_SA_DQ<7>
  J7     161  DQ_A7  SCONN288_ADR50001P013C01  I12
  J8     161  DQ_A7  SCONN288_ADR50001P003C01  I50
  U2     AF71  DDR3_SA_DQ7  SOCKET4677_AZIFS054P001C01  I169

M_D_CPU0_SA_DQ<8>   @S9S_MB_2U_LIB.S9S_MB_2U(SCH_1):M_D_CPU0_SA_DQ<8>
  J7      18  DQ_A8  SCONN288_ADR50001P013C01  I12
  J8      18  DQ_A8  SCONN288_ADR50001P003C01  I50
  U2     AL78  DDR3_SA_DQ8  SOCKET4677_AZIFS054P001C01  I169

M_D_CPU0_SA_DQ<9>   @S9S_MB_2U_LIB.S9S_MB_2U(SCH_1):M_D_CPU0_SA_DQ<9>
  J7      20  DQ_A9  SCONN288_ADR50001P013C01  I12
  J8      20  DQ_A9  SCONN288_ADR50001P003C01  I50
  U2     AK77  DDR3_SA_DQ9  SOCKET4677_AZIFS054P001C01  I169

M_D_CPU0_SA_DQ<10>   @S9S_MB_2U_LIB.S9S_MB_2U(SCH_1):M_D_CPU0_SA_DQ<10>
  J7     163  DQ_A10  SCONN288_ADR50001P013C01  I12
  J8     163  DQ_A10  SCONN288_ADR50001P003C01  I50
  U2     AN78  DDR3_SA_DQ10  SOCKET4677_AZIFS054P001C01  I169

M_D_CPU0_SA_DQ<11>   @S9S_MB_2U_LIB.S9S_MB_2U(SCH_1):M_D_CPU0_SA_DQ<11>
  J7     165  DQ_A11  SCONN288_ADR50001P013C01  I12
  J8     165  DQ_A11  SCONN288_ADR50001P003C01  I50
  U2     AP77  DDR3_SA_DQ11  SOCKET4677_AZIFS054P001C01  I169

M_D_CPU0_SA_DQ<12>   @S9S_MB_2U_LIB.S9S_MB_2U(SCH_1):M_D_CPU0_SA_DQ<12>
  J7      25  DQ_A12  SCONN288_ADR50001P013C01  I12
  J8      25  DQ_A12  SCONN288_ADR50001P003C01  I50
  U2     AK75  DDR3_SA_DQ12  SOCKET4677_AZIFS054P001C01  I169

M_D_CPU0_SA_DQ<13>   @S9S_MB_2U_LIB.S9S_MB_2U(SCH_1):M_D_CPU0_SA_DQ<13>
  J7      27  DQ_A13  SCONN288_ADR50001P013C01  I12
  J8      27  DQ_A13  SCONN288_ADR50001P003C01  I50
  U2     AL74  DDR3_SA_DQ13  SOCKET4677_AZIFS054P001C01  I169

M_D_CPU0_SA_DQ<14>   @S9S_MB_2U_LIB.S9S_MB_2U(SCH_1):M_D_CPU0_SA_DQ<14>
  J7     170  DQ_A14  SCONN288_ADR50001P013C01  I12
  J8     170  DQ_A14  SCONN288_ADR50001P003C01  I50
  U2     AP75  DDR3_SA_DQ14  SOCKET4677_AZIFS054P001C01  I169

M_D_CPU0_SA_DQ<15>   @S9S_MB_2U_LIB.S9S_MB_2U(SCH_1):M_D_CPU0_SA_DQ<15>
  J7     172  DQ_A15  SCONN288_ADR50001P013C01  I12
  J8     172  DQ_A15  SCONN288_ADR50001P003C01  I50
  U2     AN74  DDR3_SA_DQ15  SOCKET4677_AZIFS054P001C01  I169

M_D_CPU0_SA_DQ<16>   @S9S_MB_2U_LIB.S9S_MB_2U(SCH_1):M_D_CPU0_SA_DQ<16>
  J7      29  DQ_A16  SCONN288_ADR50001P013C01  I12
  J8      29  DQ_A16  SCONN288_ADR50001P003C01  I50
  U2     AL72  DDR3_SA_DQ16  SOCKET4677_AZIFS054P001C01  I169

M_D_CPU0_SA_DQ<17>   @S9S_MB_2U_LIB.S9S_MB_2U(SCH_1):M_D_CPU0_SA_DQ<17>
  J7      31  DQ_A17  SCONN288_ADR50001P013C01  I12
  J8      31  DQ_A17  SCONN288_ADR50001P003C01  I50
  U2     AK71  DDR3_SA_DQ17  SOCKET4677_AZIFS054P001C01  I169

M_D_CPU0_SA_DQ<18>   @S9S_MB_2U_LIB.S9S_MB_2U(SCH_1):M_D_CPU0_SA_DQ<18>
  J7     174  DQ_A18  SCONN288_ADR50001P013C01  I12
  J8     174  DQ_A18  SCONN288_ADR50001P003C01  I50
  U2     AN72  DDR3_SA_DQ18  SOCKET4677_AZIFS054P001C01  I169

M_D_CPU0_SA_DQ<19>   @S9S_MB_2U_LIB.S9S_MB_2U(SCH_1):M_D_CPU0_SA_DQ<19>
  J7     176  DQ_A19  SCONN288_ADR50001P013C01  I12
  J8     176  DQ_A19  SCONN288_ADR50001P003C01  I50
  U2     AP71  DDR3_SA_DQ19  SOCKET4677_AZIFS054P001C01  I169

M_D_CPU0_SA_DQ<20>   @S9S_MB_2U_LIB.S9S_MB_2U(SCH_1):M_D_CPU0_SA_DQ<20>
  J7      36  DQ_A20  SCONN288_ADR50001P013C01  I12
  J8      36  DQ_A20  SCONN288_ADR50001P003C01  I50
  U2     AK69  DDR3_SA_DQ20  SOCKET4677_AZIFS054P001C01  I169

M_D_CPU0_SA_DQ<21>   @S9S_MB_2U_LIB.S9S_MB_2U(SCH_1):M_D_CPU0_SA_DQ<21>
  J7      38  DQ_A21  SCONN288_ADR50001P013C01  I12
  J8      38  DQ_A21  SCONN288_ADR50001P003C01  I50
  U2     AL68  DDR3_SA_DQ21  SOCKET4677_AZIFS054P001C01  I169

M_D_CPU0_SA_DQ<22>   @S9S_MB_2U_LIB.S9S_MB_2U(SCH_1):M_D_CPU0_SA_DQ<22>
  J7     181  DQ_A22  SCONN288_ADR50001P013C01  I12
  J8     181  DQ_A22  SCONN288_ADR50001P003C01  I50
  U2     AP69  DDR3_SA_DQ22  SOCKET4677_AZIFS054P001C01  I169

M_D_CPU0_SA_DQ<23>   @S9S_MB_2U_LIB.S9S_MB_2U(SCH_1):M_D_CPU0_SA_DQ<23>
  J7     183  DQ_A23  SCONN288_ADR50001P013C01  I12
  J8     183  DQ_A23  SCONN288_ADR50001P003C01  I50
  U2     AN68  DDR3_SA_DQ23  SOCKET4677_AZIFS054P001C01  I169

M_D_CPU0_SA_DQ<24>   @S9S_MB_2U_LIB.S9S_MB_2U(SCH_1):M_D_CPU0_SA_DQ<24>
  J7      40  DQ_A24  SCONN288_ADR50001P013C01  I12
  J8      40  DQ_A24  SCONN288_ADR50001P003C01  I50
  U2     AL66  DDR3_SA_DQ24  SOCKET4677_AZIFS054P001C01  I169

M_D_CPU0_SA_DQ<25>   @S9S_MB_2U_LIB.S9S_MB_2U(SCH_1):M_D_CPU0_SA_DQ<25>
  J7      42  DQ_A25  SCONN288_ADR50001P013C01  I12
  J8      42  DQ_A25  SCONN288_ADR50001P003C01  I50
  U2     AK65  DDR3_SA_DQ25  SOCKET4677_AZIFS054P001C01  I169

M_D_CPU0_SA_DQ<26>   @S9S_MB_2U_LIB.S9S_MB_2U(SCH_1):M_D_CPU0_SA_DQ<26>
  J7     185  DQ_A26  SCONN288_ADR50001P013C01  I12
  J8     185  DQ_A26  SCONN288_ADR50001P003C01  I50
  U2     AN66  DDR3_SA_DQ26  SOCKET4677_AZIFS054P001C01  I169

M_D_CPU0_SA_DQ<27>   @S9S_MB_2U_LIB.S9S_MB_2U(SCH_1):M_D_CPU0_SA_DQ<27>
  J7     187  DQ_A27  SCONN288_ADR50001P013C01  I12
  J8     187  DQ_A27  SCONN288_ADR50001P003C01  I50
  U2     AP65  DDR3_SA_DQ27  SOCKET4677_AZIFS054P001C01  I169

M_D_CPU0_SA_DQ<28>   @S9S_MB_2U_LIB.S9S_MB_2U(SCH_1):M_D_CPU0_SA_DQ<28>
  J7      47  DQ_A28  SCONN288_ADR50001P013C01  I12
  J8      47  DQ_A28  SCONN288_ADR50001P003C01  I50
  U2     AK63  DDR3_SA_DQ28  SOCKET4677_AZIFS054P001C01  I169

M_D_CPU0_SA_DQ<29>   @S9S_MB_2U_LIB.S9S_MB_2U(SCH_1):M_D_CPU0_SA_DQ<29>
  J7      49  DQ_A29  SCONN288_ADR50001P013C01  I12
  J8      49  DQ_A29  SCONN288_ADR50001P003C01  I50
  U2     AL62  DDR3_SA_DQ29  SOCKET4677_AZIFS054P001C01  I169

M_D_CPU0_SA_DQ<30>   @S9S_MB_2U_LIB.S9S_MB_2U(SCH_1):M_D_CPU0_SA_DQ<30>
  J7     192  DQ_A30  SCONN288_ADR50001P013C01  I12
  J8     192  DQ_A30  SCONN288_ADR50001P003C01  I50
  U2     AP63  DDR3_SA_DQ30  SOCKET4677_AZIFS054P001C01  I169

M_D_CPU0_SA_DQ<31>   @S9S_MB_2U_LIB.S9S_MB_2U(SCH_1):M_D_CPU0_SA_DQ<31>
  J7     194  DQ_A31  SCONN288_ADR50001P013C01  I12
  J8     194  DQ_A31  SCONN288_ADR50001P003C01  I50
  U2     AN62  DDR3_SA_DQ31  SOCKET4677_AZIFS054P001C01  I169

M_D_CPU0_SA_DQS_DN<0>   @S9S_MB_2U_LIB.S9S_MB_2U(SCH_1):M_D_CPU0_SA_DQS_DN<0>
  J7      12  DQS0_A_N  SCONN288_ADR50001P013C01  I125
  J8      12  DQS0_A_N  SCONN288_ADR50001P003C01  I124
  U2     AB73  DDR3_SA_DQS_DN0  SOCKET4677_AZIFS054P001C01  I169

M_D_CPU0_SA_DQS_DN<1>   @S9S_MB_2U_LIB.S9S_MB_2U(SCH_1):M_D_CPU0_SA_DQS_DN<1>
  J7      23  DQS1_A_N  SCONN288_ADR50001P013C01  I125
  J8      23  DQS1_A_N  SCONN288_ADR50001P003C01  I124
  U2     AJ76  DDR3_SA_DQS_DN1  SOCKET4677_AZIFS054P001C01  I169

M_D_CPU0_SA_DQS_DN<2>   @S9S_MB_2U_LIB.S9S_MB_2U(SCH_1):M_D_CPU0_SA_DQS_DN<2>
  J7      34  DQS2_A_N  SCONN288_ADR50001P013C01  I125
  J8      34  DQS2_A_N  SCONN288_ADR50001P003C01  I124
  U2     AJ70  DDR3_SA_DQS_DN2  SOCKET4677_AZIFS054P001C01  I169

M_D_CPU0_SA_DQS_DN<3>   @S9S_MB_2U_LIB.S9S_MB_2U(SCH_1):M_D_CPU0_SA_DQS_DN<3>
  J7      45  DQS3_A_N  SCONN288_ADR50001P013C01  I125
  J8      45  DQS3_A_N  SCONN288_ADR50001P003C01  I124
  U2     AJ64  DDR3_SA_DQS_DN3  SOCKET4677_AZIFS054P001C01  I169

M_D_CPU0_SA_DQS_DN<4>   @S9S_MB_2U_LIB.S9S_MB_2U(SCH_1):M_D_CPU0_SA_DQS_DN<4>
  J7      56  DQS4_A_N  SCONN288_ADR50001P013C01  I125
  J8      56  DQS4_A_N  SCONN288_ADR50001P003C01  I124
  U2     AJ58  DDR3_SA_DQS_DN4  SOCKET4677_AZIFS054P001C01  I169

M_D_CPU0_SA_DQS_DN<5>   @S9S_MB_2U_LIB.S9S_MB_2U(SCH_1):M_D_CPU0_SA_DQS_DN<5>
  J7     156  DQS5_A_N  SCONN288_ADR50001P013C01  I125
  J8     156  DQS5_A_N  SCONN288_ADR50001P003C01  I124
  U2     AH73  DDR3_SA_DQS_DN5  SOCKET4677_AZIFS054P001C01  I169

M_D_CPU0_SA_DQS_DN<6>   @S9S_MB_2U_LIB.S9S_MB_2U(SCH_1):M_D_CPU0_SA_DQS_DN<6>
  J7     167  DQS6_A_N  SCONN288_ADR50001P013C01  I125
  J8     167  DQS6_A_N  SCONN288_ADR50001P003C01  I124
  U2     AN76  DDR3_SA_DQS_DN6  SOCKET4677_AZIFS054P001C01  I169

M_D_CPU0_SA_DQS_DN<7>   @S9S_MB_2U_LIB.S9S_MB_2U(SCH_1):M_D_CPU0_SA_DQS_DN<7>
  J7     178  DQS7_A_N  SCONN288_ADR50001P013C01  I125
  J8     178  DQS7_A_N  SCONN288_ADR50001P003C01  I124
  U2     AN70  DDR3_SA_DQS_DN7  SOCKET4677_AZIFS054P001C01  I169

M_D_CPU0_SA_DQS_DN<8>   @S9S_MB_2U_LIB.S9S_MB_2U(SCH_1):M_D_CPU0_SA_DQS_DN<8>
  J7     189  DQS8_A_N  SCONN288_ADR50001P013C01  I125
  J8     189  DQS8_A_N  SCONN288_ADR50001P003C01  I124
  U2     AN64  DDR3_SA_DQS_DN8  SOCKET4677_AZIFS054P001C01  I169

M_D_CPU0_SA_DQS_DN<9>   @S9S_MB_2U_LIB.S9S_MB_2U(SCH_1):M_D_CPU0_SA_DQS_DN<9>
  J7     200  DQS9_A_N  SCONN288_ADR50001P013C01  I125
  J8     200  DQS9_A_N  SCONN288_ADR50001P003C01  I124
  U2     AN58  DDR3_SA_DQS_DN9  SOCKET4677_AZIFS054P001C01  I169

M_D_CPU0_SA_DQS_DP<0>   @S9S_MB_2U_LIB.S9S_MB_2U(SCH_1):M_D_CPU0_SA_DQS_DP<0>
  J7      11  DQS0_A_P  SCONN288_ADR50001P013C01  I125
  J8      11  DQS0_A_P  SCONN288_ADR50001P003C01  I124
  U2     AD73  DDR3_SA_DQS_DP0  SOCKET4677_AZIFS054P001C01  I169

M_D_CPU0_SA_DQS_DP<1>   @S9S_MB_2U_LIB.S9S_MB_2U(SCH_1):M_D_CPU0_SA_DQS_DP<1>
  J7      22  DQS1_A_P  SCONN288_ADR50001P013C01  I125
  J8      22  DQS1_A_P  SCONN288_ADR50001P003C01  I124
  U2     AL76  DDR3_SA_DQS_DP1  SOCKET4677_AZIFS054P001C01  I169

M_D_CPU0_SA_DQS_DP<2>   @S9S_MB_2U_LIB.S9S_MB_2U(SCH_1):M_D_CPU0_SA_DQS_DP<2>
  J7      33  DQS2_A_P  SCONN288_ADR50001P013C01  I125
  J8      33  DQS2_A_P  SCONN288_ADR50001P003C01  I124
  U2     AL70  DDR3_SA_DQS_DP2  SOCKET4677_AZIFS054P001C01  I169

M_D_CPU0_SA_DQS_DP<3>   @S9S_MB_2U_LIB.S9S_MB_2U(SCH_1):M_D_CPU0_SA_DQS_DP<3>
  J7      44  DQS3_A_P  SCONN288_ADR50001P013C01  I125
  J8      44  DQS3_A_P  SCONN288_ADR50001P003C01  I124
  U2     AL64  DDR3_SA_DQS_DP3  SOCKET4677_AZIFS054P001C01  I169

M_D_CPU0_SA_DQS_DP<4>   @S9S_MB_2U_LIB.S9S_MB_2U(SCH_1):M_D_CPU0_SA_DQS_DP<4>
  J7      55  DQS4_A_P  SCONN288_ADR50001P013C01  I125
  J8      55  DQS4_A_P  SCONN288_ADR50001P003C01  I124
  U2     AL58  DDR3_SA_DQS_DP4  SOCKET4677_AZIFS054P001C01  I169

M_D_CPU0_SA_DQS_DP<5>   @S9S_MB_2U_LIB.S9S_MB_2U(SCH_1):M_D_CPU0_SA_DQS_DP<5>
  J7     157  DQS5_A_P  SCONN288_ADR50001P013C01  I125
  J8     157  DQS5_A_P  SCONN288_ADR50001P003C01  I124
  U2     AF73  DDR3_SA_DQS_DP5  SOCKET4677_AZIFS054P001C01  I169

M_D_CPU0_SA_DQS_DP<6>   @S9S_MB_2U_LIB.S9S_MB_2U(SCH_1):M_D_CPU0_SA_DQS_DP<6>
  J7     168  DQS6_A_P  SCONN288_ADR50001P013C01  I125
  J8     168  DQS6_A_P  SCONN288_ADR50001P003C01  I124
  U2     AR76  DDR3_SA_DQS_DP6  SOCKET4677_AZIFS054P001C01  I169

M_D_CPU0_SA_DQS_DP<7>   @S9S_MB_2U_LIB.S9S_MB_2U(SCH_1):M_D_CPU0_SA_DQS_DP<7>
  J7     179  DQS7_A_P  SCONN288_ADR50001P013C01  I125
  J8     179  DQS7_A_P  SCONN288_ADR50001P003C01  I124
  U2     AR70  DDR3_SA_DQS_DP7  SOCKET4677_AZIFS054P001C01  I169

M_D_CPU0_SA_DQS_DP<8>   @S9S_MB_2U_LIB.S9S_MB_2U(SCH_1):M_D_CPU0_SA_DQS_DP<8>
  J7     190  DQS8_A_P  SCONN288_ADR50001P013C01  I125
  J8     190  DQS8_A_P  SCONN288_ADR50001P003C01  I124
  U2     AR64  DDR3_SA_DQS_DP8  SOCKET4677_AZIFS054P001C01  I169

M_D_CPU0_SA_DQS_DP<9>   @S9S_MB_2U_LIB.S9S_MB_2U(SCH_1):M_D_CPU0_SA_DQS_DP<9>
  J7     201  DQS9_A_P  SCONN288_ADR50001P013C01  I125
  J8     201  DQS9_A_P  SCONN288_ADR50001P003C01  I124
  U2     AR58  DDR3_SA_DQS_DP9  SOCKET4677_AZIFS054P001C01  I169

M_D_CPU0_SA_PAR   @S9S_MB_2U_LIB.S9S_MB_2U(SCH_1):M_D_CPU0_SA_PAR
  J7      74  PAR_A  SCONN288_ADR50001P013C01  I12
  J8      74  PAR_A  SCONN288_ADR50001P003C01  I50
  U2     AP44  DDR3_SA_PAR  SOCKET4677_AZIFS054P001C01  I169

M_D_CPU0_SA_RSP<0>   @S9S_MB_2U_LIB.S9S_MB_2U(SCH_1):M_D_CPU0_SA_RSP<0>
  J7      86  LBD||RSP_N_A  SCONN288_ADR50001P013C01  I12
  U2     AD51  DDR3_A_RSP0  SOCKET4677_AZIFS054P001C01  I169

M_D_CPU0_SA_RSP<1>   @S9S_MB_2U_LIB.S9S_MB_2U(SCH_1):M_D_CPU0_SA_RSP<1>
  J8      86  LBD||RSP_N_A  SCONN288_ADR50001P003C01  I50
  U2     AC50  DDR3_A_RSP1  SOCKET4677_AZIFS054P001C01  I169

M_D_CPU0_SB_CA<0>   @S9S_MB_2U_LIB.S9S_MB_2U(SCH_1):M_D_CPU0_SB_CA<0>
  J7      76  CA0_B  SCONN288_ADR50001P013C01  I12
  J8      76  CA0_B  SCONN288_ADR50001P003C01  I50
  U2     AK44  DDR3_SB_CA0  SOCKET4677_AZIFS054P001C01  I169

M_D_CPU0_SB_CA<1>   @S9S_MB_2U_LIB.S9S_MB_2U(SCH_1):M_D_CPU0_SB_CA<1>
  J7     221  CA1_B  SCONN288_ADR50001P013C01  I12
  J8     221  CA1_B  SCONN288_ADR50001P003C01  I50
  U2     AL43  DDR3_SB_CA1  SOCKET4677_AZIFS054P001C01  I169

M_D_CPU0_SB_CA<2>   @S9S_MB_2U_LIB.S9S_MB_2U(SCH_1):M_D_CPU0_SB_CA<2>
  J7      78  CA2_B  SCONN288_ADR50001P013C01  I12
  J8      78  CA2_B  SCONN288_ADR50001P003C01  I50
  U2     AD44  DDR3_SB_CA2  SOCKET4677_AZIFS054P001C01  I169

M_D_CPU0_SB_CA<3>   @S9S_MB_2U_LIB.S9S_MB_2U(SCH_1):M_D_CPU0_SB_CA<3>
  J7     223  CA3_B  SCONN288_ADR50001P013C01  I12
  J8     223  CA3_B  SCONN288_ADR50001P003C01  I50
  U2     AF44  DDR3_SB_CA3  SOCKET4677_AZIFS054P001C01  I169

M_D_CPU0_SB_CA<4>   @S9S_MB_2U_LIB.S9S_MB_2U(SCH_1):M_D_CPU0_SB_CA<4>
  J7      80  CA4_B  SCONN288_ADR50001P013C01  I12
  J8      80  CA4_B  SCONN288_ADR50001P003C01  I50
  U2     AC43  DDR3_SB_CA4  SOCKET4677_AZIFS054P001C01  I169

M_D_CPU0_SB_CA<5>   @S9S_MB_2U_LIB.S9S_MB_2U(SCH_1):M_D_CPU0_SB_CA<5>
  J7     225  CA5_B  SCONN288_ADR50001P013C01  I12
  J8     225  CA5_B  SCONN288_ADR50001P003C01  I50
  U2     AG43  DDR3_SB_CA5  SOCKET4677_AZIFS054P001C01  I169

M_D_CPU0_SB_CA<6>   @S9S_MB_2U_LIB.S9S_MB_2U(SCH_1):M_D_CPU0_SB_CA<6>
  J7      82  CA6_B  SCONN288_ADR50001P013C01  I12
  J8      82  CA6_B  SCONN288_ADR50001P003C01  I50
  U2     AB42  DDR3_SB_CA6  SOCKET4677_AZIFS054P001C01  I169

M_D_CPU0_SB_CB<0>   @S9S_MB_2U_LIB.S9S_MB_2U(SCH_1):M_D_CPU0_SB_CB<0>
  J7      96  CB_B0  SCONN288_ADR50001P013C01  I12
  J8      96  CB_B0  SCONN288_ADR50001P003C01  I50
  U2     AK38  DDR3_SB_ECC0  SOCKET4677_AZIFS054P001C01  I169

M_D_CPU0_SB_CB<1>   @S9S_MB_2U_LIB.S9S_MB_2U(SCH_1):M_D_CPU0_SB_CB<1>
  J7      98  CB_B1  SCONN288_ADR50001P013C01  I12
  J8      98  CB_B1  SCONN288_ADR50001P003C01  I50
  U2     AL37  DDR3_SB_ECC1  SOCKET4677_AZIFS054P001C01  I169

M_D_CPU0_SB_CB<2>   @S9S_MB_2U_LIB.S9S_MB_2U(SCH_1):M_D_CPU0_SB_CB<2>
  J7     241  CB_B2  SCONN288_ADR50001P013C01  I12
  J8     241  CB_B2  SCONN288_ADR50001P003C01  I50
  U2     AP38  DDR3_SB_ECC2  SOCKET4677_AZIFS054P001C01  I169

M_D_CPU0_SB_CB<3>   @S9S_MB_2U_LIB.S9S_MB_2U(SCH_1):M_D_CPU0_SB_CB<3>
  J7     243  CB_B3  SCONN288_ADR50001P013C01  I12
  J8     243  CB_B3  SCONN288_ADR50001P003C01  I50
  U2     AN37  DDR3_SB_ECC3  SOCKET4677_AZIFS054P001C01  I169

M_D_CPU0_SB_CB<4>   @S9S_MB_2U_LIB.S9S_MB_2U(SCH_1):M_D_CPU0_SB_CB<4>
  J7      89  CB_B4  SCONN288_ADR50001P013C01  I12
  J8      89  CB_B4  SCONN288_ADR50001P003C01  I50
  U2     AL41  DDR3_SB_ECC4  SOCKET4677_AZIFS054P001C01  I169

M_D_CPU0_SB_CB<5>   @S9S_MB_2U_LIB.S9S_MB_2U(SCH_1):M_D_CPU0_SB_CB<5>
  J7      91  CB_B5  SCONN288_ADR50001P013C01  I12
  J8      91  CB_B5  SCONN288_ADR50001P003C01  I50
  U2     AK40  DDR3_SB_ECC5  SOCKET4677_AZIFS054P001C01  I169

M_D_CPU0_SB_CB<6>   @S9S_MB_2U_LIB.S9S_MB_2U(SCH_1):M_D_CPU0_SB_CB<6>
  J7     234  CB_B6  SCONN288_ADR50001P013C01  I12
  J8     234  CB_B6  SCONN288_ADR50001P003C01  I50
  U2     AN41  DDR3_SB_ECC6  SOCKET4677_AZIFS054P001C01  I169

M_D_CPU0_SB_CB<7>   @S9S_MB_2U_LIB.S9S_MB_2U(SCH_1):M_D_CPU0_SB_CB<7>
  J7     236  CB_B7  SCONN288_ADR50001P013C01  I12
  J8     236  CB_B7  SCONN288_ADR50001P003C01  I50
  U2     AP40  DDR3_SB_ECC7  SOCKET4677_AZIFS054P001C01  I169

M_D_CPU0_SB_CS_N<0>   @S9S_MB_2U_LIB.S9S_MB_2U(SCH_1):M_D_CPU0_SB_CS_N<0>
  J7      84  CS0_N_B  SCONN288_ADR50001P013C01  I12
  U2     AC41  DDR3_SB_CS0_N  SOCKET4677_AZIFS054P001C01  I169

M_D_CPU0_SB_CS_N<1>   @S9S_MB_2U_LIB.S9S_MB_2U(SCH_1):M_D_CPU0_SB_CS_N<1>
  J7     229  CS1_N_B  SCONN288_ADR50001P013C01  I12
  U2     AG41  DDR3_SB_CS1_N  SOCKET4677_AZIFS054P001C01  I169

M_D_CPU0_SB_CS_N<2>   @S9S_MB_2U_LIB.S9S_MB_2U(SCH_1):M_D_CPU0_SB_CS_N<2>
  J8      84  CS0_N_B  SCONN288_ADR50001P003C01  I50
  U2     AF40  DDR3_SB_CS2_N  SOCKET4677_AZIFS054P001C01  I169

M_D_CPU0_SB_CS_N<3>   @S9S_MB_2U_LIB.S9S_MB_2U(SCH_1):M_D_CPU0_SB_CS_N<3>
  J8     229  CS1_N_B  SCONN288_ADR50001P003C01  I50
  U2     AD40  DDR3_SB_CS3_N  SOCKET4677_AZIFS054P001C01  I169

M_D_CPU0_SB_DQ<0>   @S9S_MB_2U_LIB.S9S_MB_2U(SCH_1):M_D_CPU0_SB_DQ<0>
  J7     100  DQ_B0  SCONN288_ADR50001P013C01  I12
  J8     100  DQ_B0  SCONN288_ADR50001P003C01  I50
  U2     AL35  DDR3_SB_DQ0  SOCKET4677_AZIFS054P001C01  I169

M_D_CPU0_SB_DQ<1>   @S9S_MB_2U_LIB.S9S_MB_2U(SCH_1):M_D_CPU0_SB_DQ<1>
  J7     102  DQ_B1  SCONN288_ADR50001P013C01  I12
  J8     102  DQ_B1  SCONN288_ADR50001P003C01  I50
  U2     AK34  DDR3_SB_DQ1  SOCKET4677_AZIFS054P001C01  I169

M_D_CPU0_SB_DQ<2>   @S9S_MB_2U_LIB.S9S_MB_2U(SCH_1):M_D_CPU0_SB_DQ<2>
  J7     245  DQ_B2  SCONN288_ADR50001P013C01  I12
  J8     245  DQ_B2  SCONN288_ADR50001P003C01  I50
  U2     AN35  DDR3_SB_DQ2  SOCKET4677_AZIFS054P001C01  I169

M_D_CPU0_SB_DQ<3>   @S9S_MB_2U_LIB.S9S_MB_2U(SCH_1):M_D_CPU0_SB_DQ<3>
  J7     247  DQ_B3  SCONN288_ADR50001P013C01  I12
  J8     247  DQ_B3  SCONN288_ADR50001P003C01  I50
  U2     AP34  DDR3_SB_DQ3  SOCKET4677_AZIFS054P001C01  I169

M_D_CPU0_SB_DQ<4>   @S9S_MB_2U_LIB.S9S_MB_2U(SCH_1):M_D_CPU0_SB_DQ<4>
  J7     107  DQ_B4  SCONN288_ADR50001P013C01  I12
  J8     107  DQ_B4  SCONN288_ADR50001P003C01  I50
  U2     AK32  DDR3_SB_DQ4  SOCKET4677_AZIFS054P001C01  I169

M_D_CPU0_SB_DQ<5>   @S9S_MB_2U_LIB.S9S_MB_2U(SCH_1):M_D_CPU0_SB_DQ<5>
  J7     109  DQ_B5  SCONN288_ADR50001P013C01  I12
  J8     109  DQ_B5  SCONN288_ADR50001P003C01  I50
  U2     AL31  DDR3_SB_DQ5  SOCKET4677_AZIFS054P001C01  I169

M_D_CPU0_SB_DQ<6>   @S9S_MB_2U_LIB.S9S_MB_2U(SCH_1):M_D_CPU0_SB_DQ<6>
  J7     252  DQ_B6  SCONN288_ADR50001P013C01  I12
  J8     252  DQ_B6  SCONN288_ADR50001P003C01  I50
  U2     AP32  DDR3_SB_DQ6  SOCKET4677_AZIFS054P001C01  I169

M_D_CPU0_SB_DQ<7>   @S9S_MB_2U_LIB.S9S_MB_2U(SCH_1):M_D_CPU0_SB_DQ<7>
  J7     254  DQ_B7  SCONN288_ADR50001P013C01  I12
  J8     254  DQ_B7  SCONN288_ADR50001P003C01  I50
  U2     AN31  DDR3_SB_DQ7  SOCKET4677_AZIFS054P001C01  I169

M_D_CPU0_SB_DQ<8>   @S9S_MB_2U_LIB.S9S_MB_2U(SCH_1):M_D_CPU0_SB_DQ<8>
  J7     111  DQ_B8  SCONN288_ADR50001P013C01  I12
  J8     111  DQ_B8  SCONN288_ADR50001P003C01  I50
  U2     AL29  DDR3_SB_DQ8  SOCKET4677_AZIFS054P001C01  I169

M_D_CPU0_SB_DQ<9>   @S9S_MB_2U_LIB.S9S_MB_2U(SCH_1):M_D_CPU0_SB_DQ<9>
  J7     113  DQ_B9  SCONN288_ADR50001P013C01  I12
  J8     113  DQ_B9  SCONN288_ADR50001P003C01  I50
  U2     AK28  DDR3_SB_DQ9  SOCKET4677_AZIFS054P001C01  I169

M_D_CPU0_SB_DQ<10>   @S9S_MB_2U_LIB.S9S_MB_2U(SCH_1):M_D_CPU0_SB_DQ<10>
  J7     256  DQ_B10  SCONN288_ADR50001P013C01  I12
  J8     256  DQ_B10  SCONN288_ADR50001P003C01  I50
  U2     AN29  DDR3_SB_DQ10  SOCKET4677_AZIFS054P001C01  I169

M_D_CPU0_SB_DQ<11>   @S9S_MB_2U_LIB.S9S_MB_2U(SCH_1):M_D_CPU0_SB_DQ<11>
  J7     258  DQ_B11  SCONN288_ADR50001P013C01  I12
  J8     258  DQ_B11  SCONN288_ADR50001P003C01  I50
  U2     AP28  DDR3_SB_DQ11  SOCKET4677_AZIFS054P001C01  I169

M_D_CPU0_SB_DQ<12>   @S9S_MB_2U_LIB.S9S_MB_2U(SCH_1):M_D_CPU0_SB_DQ<12>
  J7     118  DQ_B12  SCONN288_ADR50001P013C01  I12
  J8     118  DQ_B12  SCONN288_ADR50001P003C01  I50
  U2     AK26  DDR3_SB_DQ12  SOCKET4677_AZIFS054P001C01  I169

M_D_CPU0_SB_DQ<13>   @S9S_MB_2U_LIB.S9S_MB_2U(SCH_1):M_D_CPU0_SB_DQ<13>
  J7     120  DQ_B13  SCONN288_ADR50001P013C01  I12
  J8     120  DQ_B13  SCONN288_ADR50001P003C01  I50
  U2     AL25  DDR3_SB_DQ13  SOCKET4677_AZIFS054P001C01  I169

M_D_CPU0_SB_DQ<14>   @S9S_MB_2U_LIB.S9S_MB_2U(SCH_1):M_D_CPU0_SB_DQ<14>
  J7     263  DQ_B14  SCONN288_ADR50001P013C01  I12
  J8     263  DQ_B14  SCONN288_ADR50001P003C01  I50
  U2     AP26  DDR3_SB_DQ14  SOCKET4677_AZIFS054P001C01  I169

M_D_CPU0_SB_DQ<15>   @S9S_MB_2U_LIB.S9S_MB_2U(SCH_1):M_D_CPU0_SB_DQ<15>
  J7     265  DQ_B15  SCONN288_ADR50001P013C01  I12
  J8     265  DQ_B15  SCONN288_ADR50001P003C01  I50
  U2     AN25  DDR3_SB_DQ15  SOCKET4677_AZIFS054P001C01  I169

M_D_CPU0_SB_DQ<16>   @S9S_MB_2U_LIB.S9S_MB_2U(SCH_1):M_D_CPU0_SB_DQ<16>
  J7     122  DQ_B16  SCONN288_ADR50001P013C01  I12
  J8     122  DQ_B16  SCONN288_ADR50001P003C01  I50
  U2     AD26  DDR3_SB_DQ16  SOCKET4677_AZIFS054P001C01  I169

M_D_CPU0_SB_DQ<17>   @S9S_MB_2U_LIB.S9S_MB_2U(SCH_1):M_D_CPU0_SB_DQ<17>
  J7     124  DQ_B17  SCONN288_ADR50001P013C01  I12
  J8     124  DQ_B17  SCONN288_ADR50001P003C01  I50
  U2     AC25  DDR3_SB_DQ17  SOCKET4677_AZIFS054P001C01  I169

M_D_CPU0_SB_DQ<18>   @S9S_MB_2U_LIB.S9S_MB_2U(SCH_1):M_D_CPU0_SB_DQ<18>
  J7     267  DQ_B18  SCONN288_ADR50001P013C01  I12
  J8     267  DQ_B18  SCONN288_ADR50001P003C01  I50
  U2     AF26  DDR3_SB_DQ18  SOCKET4677_AZIFS054P001C01  I169

M_D_CPU0_SB_DQ<19>   @S9S_MB_2U_LIB.S9S_MB_2U(SCH_1):M_D_CPU0_SB_DQ<19>
  J7     269  DQ_B19  SCONN288_ADR50001P013C01  I12
  J8     269  DQ_B19  SCONN288_ADR50001P003C01  I50
  U2     AG25  DDR3_SB_DQ19  SOCKET4677_AZIFS054P001C01  I169

M_D_CPU0_SB_DQ<20>   @S9S_MB_2U_LIB.S9S_MB_2U(SCH_1):M_D_CPU0_SB_DQ<20>
  J7     129  DQ_B20  SCONN288_ADR50001P013C01  I12
  J8     129  DQ_B20  SCONN288_ADR50001P003C01  I50
  U2     AC23  DDR3_SB_DQ20  SOCKET4677_AZIFS054P001C01  I169

M_D_CPU0_SB_DQ<21>   @S9S_MB_2U_LIB.S9S_MB_2U(SCH_1):M_D_CPU0_SB_DQ<21>
  J7     131  DQ_B21  SCONN288_ADR50001P013C01  I12
  J8     131  DQ_B21  SCONN288_ADR50001P003C01  I50
  U2     AD22  DDR3_SB_DQ21  SOCKET4677_AZIFS054P001C01  I169

M_D_CPU0_SB_DQ<22>   @S9S_MB_2U_LIB.S9S_MB_2U(SCH_1):M_D_CPU0_SB_DQ<22>
  J7     274  DQ_B22  SCONN288_ADR50001P013C01  I12
  J8     274  DQ_B22  SCONN288_ADR50001P003C01  I50
  U2     AG23  DDR3_SB_DQ22  SOCKET4677_AZIFS054P001C01  I169

M_D_CPU0_SB_DQ<23>   @S9S_MB_2U_LIB.S9S_MB_2U(SCH_1):M_D_CPU0_SB_DQ<23>
  J7     276  DQ_B23  SCONN288_ADR50001P013C01  I12
  J8     276  DQ_B23  SCONN288_ADR50001P003C01  I50
  U2     AF22  DDR3_SB_DQ23  SOCKET4677_AZIFS054P001C01  I169

M_D_CPU0_SB_DQ<24>   @S9S_MB_2U_LIB.S9S_MB_2U(SCH_1):M_D_CPU0_SB_DQ<24>
  J7     133  DQ_B24  SCONN288_ADR50001P013C01  I12
  J8     133  DQ_B24  SCONN288_ADR50001P003C01  I50
  U2     AL23  DDR3_SB_DQ24  SOCKET4677_AZIFS054P001C01  I169

M_D_CPU0_SB_DQ<25>   @S9S_MB_2U_LIB.S9S_MB_2U(SCH_1):M_D_CPU0_SB_DQ<25>
  J7     135  DQ_B25  SCONN288_ADR50001P013C01  I12
  J8     135  DQ_B25  SCONN288_ADR50001P003C01  I50
  U2     AK22  DDR3_SB_DQ25  SOCKET4677_AZIFS054P001C01  I169

M_D_CPU0_SB_DQ<26>   @S9S_MB_2U_LIB.S9S_MB_2U(SCH_1):M_D_CPU0_SB_DQ<26>
  J7     278  DQ_B26  SCONN288_ADR50001P013C01  I12
  J8     278  DQ_B26  SCONN288_ADR50001P003C01  I50
  U2     AN23  DDR3_SB_DQ26  SOCKET4677_AZIFS054P001C01  I169

M_D_CPU0_SB_DQ<27>   @S9S_MB_2U_LIB.S9S_MB_2U(SCH_1):M_D_CPU0_SB_DQ<27>
  J7     280  DQ_B27  SCONN288_ADR50001P013C01  I12
  J8     280  DQ_B27  SCONN288_ADR50001P003C01  I50
  U2     AP22  DDR3_SB_DQ27  SOCKET4677_AZIFS054P001C01  I169

M_D_CPU0_SB_DQ<28>   @S9S_MB_2U_LIB.S9S_MB_2U(SCH_1):M_D_CPU0_SB_DQ<28>
  J7     140  DQ_B28  SCONN288_ADR50001P013C01  I12
  J8     140  DQ_B28  SCONN288_ADR50001P003C01  I50
  U2     AK20  DDR3_SB_DQ28  SOCKET4677_AZIFS054P001C01  I169

M_D_CPU0_SB_DQ<29>   @S9S_MB_2U_LIB.S9S_MB_2U(SCH_1):M_D_CPU0_SB_DQ<29>
  J7     142  DQ_B29  SCONN288_ADR50001P013C01  I12
  J8     142  DQ_B29  SCONN288_ADR50001P003C01  I50
  U2     AL19  DDR3_SB_DQ29  SOCKET4677_AZIFS054P001C01  I169

M_D_CPU0_SB_DQ<30>   @S9S_MB_2U_LIB.S9S_MB_2U(SCH_1):M_D_CPU0_SB_DQ<30>
  J7     285  DQ_B30  SCONN288_ADR50001P013C01  I12
  J8     285  DQ_B30  SCONN288_ADR50001P003C01  I50
  U2     AP20  DDR3_SB_DQ30  SOCKET4677_AZIFS054P001C01  I169

M_D_CPU0_SB_DQ<31>   @S9S_MB_2U_LIB.S9S_MB_2U(SCH_1):M_D_CPU0_SB_DQ<31>
  J7     287  DQ_B31  SCONN288_ADR50001P013C01  I12
  J8     287  DQ_B31  SCONN288_ADR50001P003C01  I50
  U2     AN19  DDR3_SB_DQ31  SOCKET4677_AZIFS054P001C01  I169

M_D_CPU0_SB_DQS_DN<0>   @S9S_MB_2U_LIB.S9S_MB_2U(SCH_1):M_D_CPU0_SB_DQS_DN<0>
  J7     105  DQS0_B_N  SCONN288_ADR50001P013C01  I125
  J8     105  DQS0_B_N  SCONN288_ADR50001P003C01  I124
  U2     AJ33  DDR3_SB_DQS_DN0  SOCKET4677_AZIFS054P001C01  I169

M_D_CPU0_SB_DQS_DN<1>   @S9S_MB_2U_LIB.S9S_MB_2U(SCH_1):M_D_CPU0_SB_DQS_DN<1>
  J7     116  DQS1_B_N  SCONN288_ADR50001P013C01  I125
  J8     116  DQS1_B_N  SCONN288_ADR50001P003C01  I124
  U2     AJ27  DDR3_SB_DQS_DN1  SOCKET4677_AZIFS054P001C01  I169

M_D_CPU0_SB_DQS_DN<2>   @S9S_MB_2U_LIB.S9S_MB_2U(SCH_1):M_D_CPU0_SB_DQS_DN<2>
  J7     127  DQS2_B_N  SCONN288_ADR50001P013C01  I125
  J8     127  DQS2_B_N  SCONN288_ADR50001P003C01  I124
  U2     AB24  DDR3_SB_DQS_DN2  SOCKET4677_AZIFS054P001C01  I169

M_D_CPU0_SB_DQS_DN<3>   @S9S_MB_2U_LIB.S9S_MB_2U(SCH_1):M_D_CPU0_SB_DQS_DN<3>
  J7     138  DQS3_B_N  SCONN288_ADR50001P013C01  I125
  J8     138  DQS3_B_N  SCONN288_ADR50001P003C01  I124
  U2     AJ21  DDR3_SB_DQS_DN3  SOCKET4677_AZIFS054P001C01  I169

M_D_CPU0_SB_DQS_DN<4>   @S9S_MB_2U_LIB.S9S_MB_2U(SCH_1):M_D_CPU0_SB_DQS_DN<4>
  J7     238  DQS4_B_N  SCONN288_ADR50001P013C01  I125
  J8     238  DQS4_B_N  SCONN288_ADR50001P003C01  I124
  U2     AR39  DDR3_SB_DQS_DN4  SOCKET4677_AZIFS054P001C01  I169

M_D_CPU0_SB_DQS_DN<5>   @S9S_MB_2U_LIB.S9S_MB_2U(SCH_1):M_D_CPU0_SB_DQS_DN<5>
  J7     249  DQS5_B_N  SCONN288_ADR50001P013C01  I125
  J8     249  DQS5_B_N  SCONN288_ADR50001P003C01  I124
  U2     AN33  DDR3_SB_DQS_DN5  SOCKET4677_AZIFS054P001C01  I169

M_D_CPU0_SB_DQS_DN<6>   @S9S_MB_2U_LIB.S9S_MB_2U(SCH_1):M_D_CPU0_SB_DQS_DN<6>
  J7     260  DQS6_B_N  SCONN288_ADR50001P013C01  I125
  J8     260  DQS6_B_N  SCONN288_ADR50001P003C01  I124
  U2     AN27  DDR3_SB_DQS_DN6  SOCKET4677_AZIFS054P001C01  I169

M_D_CPU0_SB_DQS_DN<7>   @S9S_MB_2U_LIB.S9S_MB_2U(SCH_1):M_D_CPU0_SB_DQS_DN<7>
  J7     271  DQS7_B_N  SCONN288_ADR50001P013C01  I125
  J8     271  DQS7_B_N  SCONN288_ADR50001P003C01  I124
  U2     AF24  DDR3_SB_DQS_DN7  SOCKET4677_AZIFS054P001C01  I169

M_D_CPU0_SB_DQS_DN<8>   @S9S_MB_2U_LIB.S9S_MB_2U(SCH_1):M_D_CPU0_SB_DQS_DN<8>
  J7     282  DQS8_B_N  SCONN288_ADR50001P013C01  I125
  J8     282  DQS8_B_N  SCONN288_ADR50001P003C01  I124
  U2     AN21  DDR3_SB_DQS_DN8  SOCKET4677_AZIFS054P001C01  I169

M_D_CPU0_SB_DQS_DN<9>   @S9S_MB_2U_LIB.S9S_MB_2U(SCH_1):M_D_CPU0_SB_DQS_DN<9>
  J7      94  DQS9_B_N  SCONN288_ADR50001P013C01  I125
  J8      94  DQS9_B_N  SCONN288_ADR50001P003C01  I124
  U2     AJ39  DDR3_SB_DQS_DN9  SOCKET4677_AZIFS054P001C01  I169

M_D_CPU0_SB_DQS_DP<0>   @S9S_MB_2U_LIB.S9S_MB_2U(SCH_1):M_D_CPU0_SB_DQS_DP<0>
  J7     104  DQS0_B_P  SCONN288_ADR50001P013C01  I125
  J8     104  DQS0_B_P  SCONN288_ADR50001P003C01  I124
  U2     AL33  DDR3_SB_DQS_DP0  SOCKET4677_AZIFS054P001C01  I169

M_D_CPU0_SB_DQS_DP<1>   @S9S_MB_2U_LIB.S9S_MB_2U(SCH_1):M_D_CPU0_SB_DQS_DP<1>
  J7     115  DQS1_B_P  SCONN288_ADR50001P013C01  I125
  J8     115  DQS1_B_P  SCONN288_ADR50001P003C01  I124
  U2     AL27  DDR3_SB_DQS_DP1  SOCKET4677_AZIFS054P001C01  I169

M_D_CPU0_SB_DQS_DP<2>   @S9S_MB_2U_LIB.S9S_MB_2U(SCH_1):M_D_CPU0_SB_DQS_DP<2>
  J7     126  DQS2_B_P  SCONN288_ADR50001P013C01  I125
  J8     126  DQS2_B_P  SCONN288_ADR50001P003C01  I124
  U2     AD24  DDR3_SB_DQS_DP2  SOCKET4677_AZIFS054P001C01  I169

M_D_CPU0_SB_DQS_DP<3>   @S9S_MB_2U_LIB.S9S_MB_2U(SCH_1):M_D_CPU0_SB_DQS_DP<3>
  J7     137  DQS3_B_P  SCONN288_ADR50001P013C01  I125
  J8     137  DQS3_B_P  SCONN288_ADR50001P003C01  I124
  U2     AL21  DDR3_SB_DQS_DP3  SOCKET4677_AZIFS054P001C01  I169

M_D_CPU0_SB_DQS_DP<4>   @S9S_MB_2U_LIB.S9S_MB_2U(SCH_1):M_D_CPU0_SB_DQS_DP<4>
  J7     239  DQS4_B_P  SCONN288_ADR50001P013C01  I125
  J8     239  DQS4_B_P  SCONN288_ADR50001P003C01  I124
  U2     AN39  DDR3_SB_DQS_DP4  SOCKET4677_AZIFS054P001C01  I169

M_D_CPU0_SB_DQS_DP<5>   @S9S_MB_2U_LIB.S9S_MB_2U(SCH_1):M_D_CPU0_SB_DQS_DP<5>
  J7     250  DQS5_B_P  SCONN288_ADR50001P013C01  I125
  J8     250  DQS5_B_P  SCONN288_ADR50001P003C01  I124
  U2     AR33  DDR3_SB_DQS_DP5  SOCKET4677_AZIFS054P001C01  I169

M_D_CPU0_SB_DQS_DP<6>   @S9S_MB_2U_LIB.S9S_MB_2U(SCH_1):M_D_CPU0_SB_DQS_DP<6>
  J7     261  DQS6_B_P  SCONN288_ADR50001P013C01  I125
  J8     261  DQS6_B_P  SCONN288_ADR50001P003C01  I124
  U2     AR27  DDR3_SB_DQS_DP6  SOCKET4677_AZIFS054P001C01  I169

M_D_CPU0_SB_DQS_DP<7>   @S9S_MB_2U_LIB.S9S_MB_2U(SCH_1):M_D_CPU0_SB_DQS_DP<7>
  J7     272  DQS7_B_P  SCONN288_ADR50001P013C01  I125
  J8     272  DQS7_B_P  SCONN288_ADR50001P003C01  I124
  U2     AH24  DDR3_SB_DQS_DP7  SOCKET4677_AZIFS054P001C01  I169

M_D_CPU0_SB_DQS_DP<8>   @S9S_MB_2U_LIB.S9S_MB_2U(SCH_1):M_D_CPU0_SB_DQS_DP<8>
  J7     283  DQS8_B_P  SCONN288_ADR50001P013C01  I125
  J8     283  DQS8_B_P  SCONN288_ADR50001P003C01  I124
  U2     AR21  DDR3_SB_DQS_DP8  SOCKET4677_AZIFS054P001C01  I169

M_D_CPU0_SB_DQS_DP<9>   @S9S_MB_2U_LIB.S9S_MB_2U(SCH_1):M_D_CPU0_SB_DQS_DP<9>
  J7      93  DQS9_B_P  SCONN288_ADR50001P013C01  I125
  J8      93  DQS9_B_P  SCONN288_ADR50001P003C01  I124
  U2     AL39  DDR3_SB_DQS_DP9  SOCKET4677_AZIFS054P001C01  I169

M_D_CPU0_SB_PAR   @S9S_MB_2U_LIB.S9S_MB_2U(SCH_1):M_D_CPU0_SB_PAR
  J7     227  PAR_B  SCONN288_ADR50001P013C01  I12
  J8     227  PAR_B  SCONN288_ADR50001P003C01  I50
  U2     AH42  DDR3_SB_PAR  SOCKET4677_AZIFS054P001C01  I169

M_D_CPU0_SB_RSP<0>   @S9S_MB_2U_LIB.S9S_MB_2U(SCH_1):M_D_CPU0_SB_RSP<0>
  J7      87  LBS||RSP_N_B  SCONN288_ADR50001P013C01  I12
  U2     AF51  DDR3_B_RSP0  SOCKET4677_AZIFS054P001C01  I169

M_D_CPU0_SB_RSP<1>   @S9S_MB_2U_LIB.S9S_MB_2U(SCH_1):M_D_CPU0_SB_RSP<1>
  J8      87  LBS||RSP_N_B  SCONN288_ADR50001P003C01  I50
  U2     AG50  DDR3_B_RSP1  SOCKET4677_AZIFS054P001C01  I169

M_D_CPU1_ALERT_N   @S9S_MB_2U_LIB.S9S_MB_2U(SCH_1):M_D_CPU1_ALERT_N
  J23     62  ALERT_N  SCONN288_ADR50001P013C01  I25
  J24     62  ALERT_N  SCONN288_ADR50001P003C01  I178
  U1     AV47  DDR3_ALERT_N  SOCKET4677_AZIFS054P001C01  I91

M_D_CPU1_CLK_DN<0>   @S9S_MB_2U_LIB.S9S_MB_2U(SCH_1):M_D_CPU1_CLK_DN<0>
  J23    218   CK_N  SCONN288_ADR50001P013C01  I25
  U1     AJ45  DDR3_CLK_DN0  SOCKET4677_AZIFS054P001C01  I91

M_D_CPU1_CLK_DN<1>   @S9S_MB_2U_LIB.S9S_MB_2U(SCH_1):M_D_CPU1_CLK_DN<1>
  J24    218   CK_N  SCONN288_ADR50001P003C01  I178
  U1     AN45  DDR3_CLK_DN1  SOCKET4677_AZIFS054P001C01  I91

M_D_CPU1_CLK_DP<0>   @S9S_MB_2U_LIB.S9S_MB_2U(SCH_1):M_D_CPU1_CLK_DP<0>
  J23    217   CK_P  SCONN288_ADR50001P013C01  I25
  U1     AL45  DDR3_CLK_DP0  SOCKET4677_AZIFS054P001C01  I91

M_D_CPU1_CLK_DP<1>   @S9S_MB_2U_LIB.S9S_MB_2U(SCH_1):M_D_CPU1_CLK_DP<1>
  J24    217   CK_P  SCONN288_ADR50001P003C01  I178
  U1     AR45  DDR3_CLK_DP1  SOCKET4677_AZIFS054P001C01  I91

M_D_CPU1_SA_CA<0>   @S9S_MB_2U_LIB.S9S_MB_2U(SCH_1):M_D_CPU1_SA_CA<0>
  J23     66  CA0_A  SCONN288_ADR50001P013C01  I25
  J24     66  CA0_A  SCONN288_ADR50001P003C01  I178
  U1     AJ52  DDR3_SA_CA0  SOCKET4677_AZIFS054P001C01  I91

M_D_CPU1_SA_CA<1>   @S9S_MB_2U_LIB.S9S_MB_2U(SCH_1):M_D_CPU1_SA_CA<1>
  J23    211  CA1_A  SCONN288_ADR50001P013C01  I25
  J24    211  CA1_A  SCONN288_ADR50001P003C01  I178
  U1     AR52  DDR3_SA_CA1  SOCKET4677_AZIFS054P001C01  I91

M_D_CPU1_SA_CA<2>   @S9S_MB_2U_LIB.S9S_MB_2U(SCH_1):M_D_CPU1_SA_CA<2>
  J23     68  CA2_A  SCONN288_ADR50001P013C01  I25
  J24     68  CA2_A  SCONN288_ADR50001P003C01  I178
  U1     AK51  DDR3_SA_CA2  SOCKET4677_AZIFS054P001C01  I91

M_D_CPU1_SA_CA<3>   @S9S_MB_2U_LIB.S9S_MB_2U(SCH_1):M_D_CPU1_SA_CA<3>
  J23    213  CA3_A  SCONN288_ADR50001P013C01  I25
  J24    213  CA3_A  SCONN288_ADR50001P003C01  I178
  U1     AP51  DDR3_SA_CA3  SOCKET4677_AZIFS054P001C01  I91

M_D_CPU1_SA_CA<4>   @S9S_MB_2U_LIB.S9S_MB_2U(SCH_1):M_D_CPU1_SA_CA<4>
  J23     70  CA4_A  SCONN288_ADR50001P013C01  I25
  J24     70  CA4_A  SCONN288_ADR50001P003C01  I178
  U1     AL50  DDR3_SA_CA4  SOCKET4677_AZIFS054P001C01  I91

M_D_CPU1_SA_CA<5>   @S9S_MB_2U_LIB.S9S_MB_2U(SCH_1):M_D_CPU1_SA_CA<5>
  J23    215  CA5_A  SCONN288_ADR50001P013C01  I25
  J24    215  CA5_A  SCONN288_ADR50001P003C01  I178
  U1     AN50  DDR3_SA_CA5  SOCKET4677_AZIFS054P001C01  I91

M_D_CPU1_SA_CA<6>   @S9S_MB_2U_LIB.S9S_MB_2U(SCH_1):M_D_CPU1_SA_CA<6>
  J23     72  CA6_A  SCONN288_ADR50001P013C01  I25
  J24     72  CA6_A  SCONN288_ADR50001P003C01  I178
  U1     AN43  DDR3_SA_CA6  SOCKET4677_AZIFS054P001C01  I91

M_D_CPU1_SA_CB<0>   @S9S_MB_2U_LIB.S9S_MB_2U(SCH_1):M_D_CPU1_SA_CB<0>
  J23     51  CB_A0  SCONN288_ADR50001P013C01  I25
  J24     51  CB_A0  SCONN288_ADR50001P003C01  I178
  U1     AL60  DDR3_SA_ECC0  SOCKET4677_AZIFS054P001C01  I91

M_D_CPU1_SA_CB<1>   @S9S_MB_2U_LIB.S9S_MB_2U(SCH_1):M_D_CPU1_SA_CB<1>
  J23     53  CB_A1  SCONN288_ADR50001P013C01  I25
  J24     53  CB_A1  SCONN288_ADR50001P003C01  I178
  U1     AK59  DDR3_SA_ECC1  SOCKET4677_AZIFS054P001C01  I91

M_D_CPU1_SA_CB<2>   @S9S_MB_2U_LIB.S9S_MB_2U(SCH_1):M_D_CPU1_SA_CB<2>
  J23    196  CB_A2  SCONN288_ADR50001P013C01  I25
  J24    196  CB_A2  SCONN288_ADR50001P003C01  I178
  U1     AN60  DDR3_SA_ECC2  SOCKET4677_AZIFS054P001C01  I91

M_D_CPU1_SA_CB<3>   @S9S_MB_2U_LIB.S9S_MB_2U(SCH_1):M_D_CPU1_SA_CB<3>
  J23    198  CB_A3  SCONN288_ADR50001P013C01  I25
  J24    198  CB_A3  SCONN288_ADR50001P003C01  I178
  U1     AP59  DDR3_SA_ECC3  SOCKET4677_AZIFS054P001C01  I91

M_D_CPU1_SA_CB<4>   @S9S_MB_2U_LIB.S9S_MB_2U(SCH_1):M_D_CPU1_SA_CB<4>
  J23     58  CB_A4  SCONN288_ADR50001P013C01  I25
  J24     58  CB_A4  SCONN288_ADR50001P003C01  I178
  U1     AK57  DDR3_SA_ECC4  SOCKET4677_AZIFS054P001C01  I91

M_D_CPU1_SA_CB<5>   @S9S_MB_2U_LIB.S9S_MB_2U(SCH_1):M_D_CPU1_SA_CB<5>
  J23     60  CB_A5  SCONN288_ADR50001P013C01  I25
  J24     60  CB_A5  SCONN288_ADR50001P003C01  I178
  U1     AL56  DDR3_SA_ECC5  SOCKET4677_AZIFS054P001C01  I91

M_D_CPU1_SA_CB<6>   @S9S_MB_2U_LIB.S9S_MB_2U(SCH_1):M_D_CPU1_SA_CB<6>
  J23    203  CB_A6  SCONN288_ADR50001P013C01  I25
  J24    203  CB_A6  SCONN288_ADR50001P003C01  I178
  U1     AP57  DDR3_SA_ECC6  SOCKET4677_AZIFS054P001C01  I91

M_D_CPU1_SA_CB<7>   @S9S_MB_2U_LIB.S9S_MB_2U(SCH_1):M_D_CPU1_SA_CB<7>
  J23    205  CB_A7  SCONN288_ADR50001P013C01  I25
  J24    205  CB_A7  SCONN288_ADR50001P003C01  I178
  U1     AN56  DDR3_SA_ECC7  SOCKET4677_AZIFS054P001C01  I91

M_D_CPU1_SA_CS_N<0>   @S9S_MB_2U_LIB.S9S_MB_2U(SCH_1):M_D_CPU1_SA_CS_N<0>
  J23     64  CS0_N_A  SCONN288_ADR50001P013C01  I25
  U1     AL54  DDR3_SA_CS0_N  SOCKET4677_AZIFS054P001C01  I91

M_D_CPU1_SA_CS_N<1>   @S9S_MB_2U_LIB.S9S_MB_2U(SCH_1):M_D_CPU1_SA_CS_N<1>
  J23    209  CS1_N_A  SCONN288_ADR50001P013C01  I25
  U1     AK53  DDR3_SA_CS1_N  SOCKET4677_AZIFS054P001C01  I91

M_D_CPU1_SA_CS_N<2>   @S9S_MB_2U_LIB.S9S_MB_2U(SCH_1):M_D_CPU1_SA_CS_N<2>
  J24     64  CS0_N_A  SCONN288_ADR50001P003C01  I178
  U1     AN54  DDR3_SA_CS2_N  SOCKET4677_AZIFS054P001C01  I91

M_D_CPU1_SA_CS_N<3>   @S9S_MB_2U_LIB.S9S_MB_2U(SCH_1):M_D_CPU1_SA_CS_N<3>
  J24    209  CS1_N_A  SCONN288_ADR50001P003C01  I178
  U1     AP53  DDR3_SA_CS3_N  SOCKET4677_AZIFS054P001C01  I91

M_D_CPU1_SA_DQ<0>   @S9S_MB_2U_LIB.S9S_MB_2U(SCH_1):M_D_CPU1_SA_DQ<0>
  J23      7  DQ_A0  SCONN288_ADR50001P013C01  I25
  J24      7  DQ_A0  SCONN288_ADR50001P003C01  I178
  U1     AD75  DDR3_SA_DQ0  SOCKET4677_AZIFS054P001C01  I91

M_D_CPU1_SA_DQ<1>   @S9S_MB_2U_LIB.S9S_MB_2U(SCH_1):M_D_CPU1_SA_DQ<1>
  J23      9  DQ_A1  SCONN288_ADR50001P013C01  I25
  J24      9  DQ_A1  SCONN288_ADR50001P003C01  I178
  U1     AC74  DDR3_SA_DQ1  SOCKET4677_AZIFS054P001C01  I91

M_D_CPU1_SA_DQ<2>   @S9S_MB_2U_LIB.S9S_MB_2U(SCH_1):M_D_CPU1_SA_DQ<2>
  J23    152  DQ_A2  SCONN288_ADR50001P013C01  I25
  J24    152  DQ_A2  SCONN288_ADR50001P003C01  I178
  U1     AF75  DDR3_SA_DQ2  SOCKET4677_AZIFS054P001C01  I91

M_D_CPU1_SA_DQ<3>   @S9S_MB_2U_LIB.S9S_MB_2U(SCH_1):M_D_CPU1_SA_DQ<3>
  J23    154  DQ_A3  SCONN288_ADR50001P013C01  I25
  J24    154  DQ_A3  SCONN288_ADR50001P003C01  I178
  U1     AG74  DDR3_SA_DQ3  SOCKET4677_AZIFS054P001C01  I91

M_D_CPU1_SA_DQ<4>   @S9S_MB_2U_LIB.S9S_MB_2U(SCH_1):M_D_CPU1_SA_DQ<4>
  J23     14  DQ_A4  SCONN288_ADR50001P013C01  I25
  J24     14  DQ_A4  SCONN288_ADR50001P003C01  I178
  U1     AC72  DDR3_SA_DQ4  SOCKET4677_AZIFS054P001C01  I91

M_D_CPU1_SA_DQ<5>   @S9S_MB_2U_LIB.S9S_MB_2U(SCH_1):M_D_CPU1_SA_DQ<5>
  J23     16  DQ_A5  SCONN288_ADR50001P013C01  I25
  J24     16  DQ_A5  SCONN288_ADR50001P003C01  I178
  U1     AD71  DDR3_SA_DQ5  SOCKET4677_AZIFS054P001C01  I91

M_D_CPU1_SA_DQ<6>   @S9S_MB_2U_LIB.S9S_MB_2U(SCH_1):M_D_CPU1_SA_DQ<6>
  J23    159  DQ_A6  SCONN288_ADR50001P013C01  I25
  J24    159  DQ_A6  SCONN288_ADR50001P003C01  I178
  U1     AG72  DDR3_SA_DQ6  SOCKET4677_AZIFS054P001C01  I91

M_D_CPU1_SA_DQ<7>   @S9S_MB_2U_LIB.S9S_MB_2U(SCH_1):M_D_CPU1_SA_DQ<7>
  J23    161  DQ_A7  SCONN288_ADR50001P013C01  I25
  J24    161  DQ_A7  SCONN288_ADR50001P003C01  I178
  U1     AF71  DDR3_SA_DQ7  SOCKET4677_AZIFS054P001C01  I91

M_D_CPU1_SA_DQ<8>   @S9S_MB_2U_LIB.S9S_MB_2U(SCH_1):M_D_CPU1_SA_DQ<8>
  J23     18  DQ_A8  SCONN288_ADR50001P013C01  I25
  J24     18  DQ_A8  SCONN288_ADR50001P003C01  I178
  U1     AL78  DDR3_SA_DQ8  SOCKET4677_AZIFS054P001C01  I91

M_D_CPU1_SA_DQ<9>   @S9S_MB_2U_LIB.S9S_MB_2U(SCH_1):M_D_CPU1_SA_DQ<9>
  J23     20  DQ_A9  SCONN288_ADR50001P013C01  I25
  J24     20  DQ_A9  SCONN288_ADR50001P003C01  I178
  U1     AK77  DDR3_SA_DQ9  SOCKET4677_AZIFS054P001C01  I91

M_D_CPU1_SA_DQ<10>   @S9S_MB_2U_LIB.S9S_MB_2U(SCH_1):M_D_CPU1_SA_DQ<10>
  J23    163  DQ_A10  SCONN288_ADR50001P013C01  I25
  J24    163  DQ_A10  SCONN288_ADR50001P003C01  I178
  U1     AN78  DDR3_SA_DQ10  SOCKET4677_AZIFS054P001C01  I91

M_D_CPU1_SA_DQ<11>   @S9S_MB_2U_LIB.S9S_MB_2U(SCH_1):M_D_CPU1_SA_DQ<11>
  J23    165  DQ_A11  SCONN288_ADR50001P013C01  I25
  J24    165  DQ_A11  SCONN288_ADR50001P003C01  I178
  U1     AP77  DDR3_SA_DQ11  SOCKET4677_AZIFS054P001C01  I91

M_D_CPU1_SA_DQ<12>   @S9S_MB_2U_LIB.S9S_MB_2U(SCH_1):M_D_CPU1_SA_DQ<12>
  J23     25  DQ_A12  SCONN288_ADR50001P013C01  I25
  J24     25  DQ_A12  SCONN288_ADR50001P003C01  I178
  U1     AK75  DDR3_SA_DQ12  SOCKET4677_AZIFS054P001C01  I91

M_D_CPU1_SA_DQ<13>   @S9S_MB_2U_LIB.S9S_MB_2U(SCH_1):M_D_CPU1_SA_DQ<13>
  J23     27  DQ_A13  SCONN288_ADR50001P013C01  I25
  J24     27  DQ_A13  SCONN288_ADR50001P003C01  I178
  U1     AL74  DDR3_SA_DQ13  SOCKET4677_AZIFS054P001C01  I91

M_D_CPU1_SA_DQ<14>   @S9S_MB_2U_LIB.S9S_MB_2U(SCH_1):M_D_CPU1_SA_DQ<14>
  J23    170  DQ_A14  SCONN288_ADR50001P013C01  I25
  J24    170  DQ_A14  SCONN288_ADR50001P003C01  I178
  U1     AP75  DDR3_SA_DQ14  SOCKET4677_AZIFS054P001C01  I91

M_D_CPU1_SA_DQ<15>   @S9S_MB_2U_LIB.S9S_MB_2U(SCH_1):M_D_CPU1_SA_DQ<15>
  J23    172  DQ_A15  SCONN288_ADR50001P013C01  I25
  J24    172  DQ_A15  SCONN288_ADR50001P003C01  I178
  U1     AN74  DDR3_SA_DQ15  SOCKET4677_AZIFS054P001C01  I91

M_D_CPU1_SA_DQ<16>   @S9S_MB_2U_LIB.S9S_MB_2U(SCH_1):M_D_CPU1_SA_DQ<16>
  J23     29  DQ_A16  SCONN288_ADR50001P013C01  I25
  J24     29  DQ_A16  SCONN288_ADR50001P003C01  I178
  U1     AL72  DDR3_SA_DQ16  SOCKET4677_AZIFS054P001C01  I91

M_D_CPU1_SA_DQ<17>   @S9S_MB_2U_LIB.S9S_MB_2U(SCH_1):M_D_CPU1_SA_DQ<17>
  J23     31  DQ_A17  SCONN288_ADR50001P013C01  I25
  J24     31  DQ_A17  SCONN288_ADR50001P003C01  I178
  U1     AK71  DDR3_SA_DQ17  SOCKET4677_AZIFS054P001C01  I91

M_D_CPU1_SA_DQ<18>   @S9S_MB_2U_LIB.S9S_MB_2U(SCH_1):M_D_CPU1_SA_DQ<18>
  J23    174  DQ_A18  SCONN288_ADR50001P013C01  I25
  J24    174  DQ_A18  SCONN288_ADR50001P003C01  I178
  U1     AN72  DDR3_SA_DQ18  SOCKET4677_AZIFS054P001C01  I91

M_D_CPU1_SA_DQ<19>   @S9S_MB_2U_LIB.S9S_MB_2U(SCH_1):M_D_CPU1_SA_DQ<19>
  J23    176  DQ_A19  SCONN288_ADR50001P013C01  I25
  J24    176  DQ_A19  SCONN288_ADR50001P003C01  I178
  U1     AP71  DDR3_SA_DQ19  SOCKET4677_AZIFS054P001C01  I91

M_D_CPU1_SA_DQ<20>   @S9S_MB_2U_LIB.S9S_MB_2U(SCH_1):M_D_CPU1_SA_DQ<20>
  J23     36  DQ_A20  SCONN288_ADR50001P013C01  I25
  J24     36  DQ_A20  SCONN288_ADR50001P003C01  I178
  U1     AK69  DDR3_SA_DQ20  SOCKET4677_AZIFS054P001C01  I91

M_D_CPU1_SA_DQ<21>   @S9S_MB_2U_LIB.S9S_MB_2U(SCH_1):M_D_CPU1_SA_DQ<21>
  J23     38  DQ_A21  SCONN288_ADR50001P013C01  I25
  J24     38  DQ_A21  SCONN288_ADR50001P003C01  I178
  U1     AL68  DDR3_SA_DQ21  SOCKET4677_AZIFS054P001C01  I91

M_D_CPU1_SA_DQ<22>   @S9S_MB_2U_LIB.S9S_MB_2U(SCH_1):M_D_CPU1_SA_DQ<22>
  J23    181  DQ_A22  SCONN288_ADR50001P013C01  I25
  J24    181  DQ_A22  SCONN288_ADR50001P003C01  I178
  U1     AP69  DDR3_SA_DQ22  SOCKET4677_AZIFS054P001C01  I91

M_D_CPU1_SA_DQ<23>   @S9S_MB_2U_LIB.S9S_MB_2U(SCH_1):M_D_CPU1_SA_DQ<23>
  J23    183  DQ_A23  SCONN288_ADR50001P013C01  I25
  J24    183  DQ_A23  SCONN288_ADR50001P003C01  I178
  U1     AN68  DDR3_SA_DQ23  SOCKET4677_AZIFS054P001C01  I91

M_D_CPU1_SA_DQ<24>   @S9S_MB_2U_LIB.S9S_MB_2U(SCH_1):M_D_CPU1_SA_DQ<24>
  J23     40  DQ_A24  SCONN288_ADR50001P013C01  I25
  J24     40  DQ_A24  SCONN288_ADR50001P003C01  I178
  U1     AL66  DDR3_SA_DQ24  SOCKET4677_AZIFS054P001C01  I91

M_D_CPU1_SA_DQ<25>   @S9S_MB_2U_LIB.S9S_MB_2U(SCH_1):M_D_CPU1_SA_DQ<25>
  J23     42  DQ_A25  SCONN288_ADR50001P013C01  I25
  J24     42  DQ_A25  SCONN288_ADR50001P003C01  I178
  U1     AK65  DDR3_SA_DQ25  SOCKET4677_AZIFS054P001C01  I91

M_D_CPU1_SA_DQ<26>   @S9S_MB_2U_LIB.S9S_MB_2U(SCH_1):M_D_CPU1_SA_DQ<26>
  J23    185  DQ_A26  SCONN288_ADR50001P013C01  I25
  J24    185  DQ_A26  SCONN288_ADR50001P003C01  I178
  U1     AN66  DDR3_SA_DQ26  SOCKET4677_AZIFS054P001C01  I91

M_D_CPU1_SA_DQ<27>   @S9S_MB_2U_LIB.S9S_MB_2U(SCH_1):M_D_CPU1_SA_DQ<27>
  J23    187  DQ_A27  SCONN288_ADR50001P013C01  I25
  J24    187  DQ_A27  SCONN288_ADR50001P003C01  I178
  U1     AP65  DDR3_SA_DQ27  SOCKET4677_AZIFS054P001C01  I91

M_D_CPU1_SA_DQ<28>   @S9S_MB_2U_LIB.S9S_MB_2U(SCH_1):M_D_CPU1_SA_DQ<28>
  J23     47  DQ_A28  SCONN288_ADR50001P013C01  I25
  J24     47  DQ_A28  SCONN288_ADR50001P003C01  I178
  U1     AK63  DDR3_SA_DQ28  SOCKET4677_AZIFS054P001C01  I91

M_D_CPU1_SA_DQ<29>   @S9S_MB_2U_LIB.S9S_MB_2U(SCH_1):M_D_CPU1_SA_DQ<29>
  J23     49  DQ_A29  SCONN288_ADR50001P013C01  I25
  J24     49  DQ_A29  SCONN288_ADR50001P003C01  I178
  U1     AL62  DDR3_SA_DQ29  SOCKET4677_AZIFS054P001C01  I91

M_D_CPU1_SA_DQ<30>   @S9S_MB_2U_LIB.S9S_MB_2U(SCH_1):M_D_CPU1_SA_DQ<30>
  J23    192  DQ_A30  SCONN288_ADR50001P013C01  I25
  J24    192  DQ_A30  SCONN288_ADR50001P003C01  I178
  U1     AP63  DDR3_SA_DQ30  SOCKET4677_AZIFS054P001C01  I91

M_D_CPU1_SA_DQ<31>   @S9S_MB_2U_LIB.S9S_MB_2U(SCH_1):M_D_CPU1_SA_DQ<31>
  J23    194  DQ_A31  SCONN288_ADR50001P013C01  I25
  J24    194  DQ_A31  SCONN288_ADR50001P003C01  I178
  U1     AN62  DDR3_SA_DQ31  SOCKET4677_AZIFS054P001C01  I91

M_D_CPU1_SA_DQS_DN<0>   @S9S_MB_2U_LIB.S9S_MB_2U(SCH_1):M_D_CPU1_SA_DQS_DN<0>
  J23     12  DQS0_A_N  SCONN288_ADR50001P013C01  I126
  J24     12  DQS0_A_N  SCONN288_ADR50001P003C01  I179
  U1     AB73  DDR3_SA_DQS_DN0  SOCKET4677_AZIFS054P001C01  I91

M_D_CPU1_SA_DQS_DN<1>   @S9S_MB_2U_LIB.S9S_MB_2U(SCH_1):M_D_CPU1_SA_DQS_DN<1>
  J23     23  DQS1_A_N  SCONN288_ADR50001P013C01  I126
  J24     23  DQS1_A_N  SCONN288_ADR50001P003C01  I179
  U1     AJ76  DDR3_SA_DQS_DN1  SOCKET4677_AZIFS054P001C01  I91

M_D_CPU1_SA_DQS_DN<2>   @S9S_MB_2U_LIB.S9S_MB_2U(SCH_1):M_D_CPU1_SA_DQS_DN<2>
  J23     34  DQS2_A_N  SCONN288_ADR50001P013C01  I126
  J24     34  DQS2_A_N  SCONN288_ADR50001P003C01  I179
  U1     AJ70  DDR3_SA_DQS_DN2  SOCKET4677_AZIFS054P001C01  I91

M_D_CPU1_SA_DQS_DN<3>   @S9S_MB_2U_LIB.S9S_MB_2U(SCH_1):M_D_CPU1_SA_DQS_DN<3>
  J23     45  DQS3_A_N  SCONN288_ADR50001P013C01  I126
  J24     45  DQS3_A_N  SCONN288_ADR50001P003C01  I179
  U1     AJ64  DDR3_SA_DQS_DN3  SOCKET4677_AZIFS054P001C01  I91

M_D_CPU1_SA_DQS_DN<4>   @S9S_MB_2U_LIB.S9S_MB_2U(SCH_1):M_D_CPU1_SA_DQS_DN<4>
  J23     56  DQS4_A_N  SCONN288_ADR50001P013C01  I126
  J24     56  DQS4_A_N  SCONN288_ADR50001P003C01  I179
  U1     AJ58  DDR3_SA_DQS_DN4  SOCKET4677_AZIFS054P001C01  I91

M_D_CPU1_SA_DQS_DN<5>   @S9S_MB_2U_LIB.S9S_MB_2U(SCH_1):M_D_CPU1_SA_DQS_DN<5>
  J23    156  DQS5_A_N  SCONN288_ADR50001P013C01  I126
  J24    156  DQS5_A_N  SCONN288_ADR50001P003C01  I179
  U1     AH73  DDR3_SA_DQS_DN5  SOCKET4677_AZIFS054P001C01  I91

M_D_CPU1_SA_DQS_DN<6>   @S9S_MB_2U_LIB.S9S_MB_2U(SCH_1):M_D_CPU1_SA_DQS_DN<6>
  J23    167  DQS6_A_N  SCONN288_ADR50001P013C01  I126
  J24    167  DQS6_A_N  SCONN288_ADR50001P003C01  I179
  U1     AN76  DDR3_SA_DQS_DN6  SOCKET4677_AZIFS054P001C01  I91

M_D_CPU1_SA_DQS_DN<7>   @S9S_MB_2U_LIB.S9S_MB_2U(SCH_1):M_D_CPU1_SA_DQS_DN<7>
  J23    178  DQS7_A_N  SCONN288_ADR50001P013C01  I126
  J24    178  DQS7_A_N  SCONN288_ADR50001P003C01  I179
  U1     AN70  DDR3_SA_DQS_DN7  SOCKET4677_AZIFS054P001C01  I91

M_D_CPU1_SA_DQS_DN<8>   @S9S_MB_2U_LIB.S9S_MB_2U(SCH_1):M_D_CPU1_SA_DQS_DN<8>
  J23    189  DQS8_A_N  SCONN288_ADR50001P013C01  I126
  J24    189  DQS8_A_N  SCONN288_ADR50001P003C01  I179
  U1     AN64  DDR3_SA_DQS_DN8  SOCKET4677_AZIFS054P001C01  I91

M_D_CPU1_SA_DQS_DN<9>   @S9S_MB_2U_LIB.S9S_MB_2U(SCH_1):M_D_CPU1_SA_DQS_DN<9>
  J23    200  DQS9_A_N  SCONN288_ADR50001P013C01  I126
  J24    200  DQS9_A_N  SCONN288_ADR50001P003C01  I179
  U1     AN58  DDR3_SA_DQS_DN9  SOCKET4677_AZIFS054P001C01  I91

M_D_CPU1_SA_DQS_DP<0>   @S9S_MB_2U_LIB.S9S_MB_2U(SCH_1):M_D_CPU1_SA_DQS_DP<0>
  J23     11  DQS0_A_P  SCONN288_ADR50001P013C01  I126
  J24     11  DQS0_A_P  SCONN288_ADR50001P003C01  I179
  U1     AD73  DDR3_SA_DQS_DP0  SOCKET4677_AZIFS054P001C01  I91

M_D_CPU1_SA_DQS_DP<1>   @S9S_MB_2U_LIB.S9S_MB_2U(SCH_1):M_D_CPU1_SA_DQS_DP<1>
  J23     22  DQS1_A_P  SCONN288_ADR50001P013C01  I126
  J24     22  DQS1_A_P  SCONN288_ADR50001P003C01  I179
  U1     AL76  DDR3_SA_DQS_DP1  SOCKET4677_AZIFS054P001C01  I91

M_D_CPU1_SA_DQS_DP<2>   @S9S_MB_2U_LIB.S9S_MB_2U(SCH_1):M_D_CPU1_SA_DQS_DP<2>
  J23     33  DQS2_A_P  SCONN288_ADR50001P013C01  I126
  J24     33  DQS2_A_P  SCONN288_ADR50001P003C01  I179
  U1     AL70  DDR3_SA_DQS_DP2  SOCKET4677_AZIFS054P001C01  I91

M_D_CPU1_SA_DQS_DP<3>   @S9S_MB_2U_LIB.S9S_MB_2U(SCH_1):M_D_CPU1_SA_DQS_DP<3>
  J23     44  DQS3_A_P  SCONN288_ADR50001P013C01  I126
  J24     44  DQS3_A_P  SCONN288_ADR50001P003C01  I179
  U1     AL64  DDR3_SA_DQS_DP3  SOCKET4677_AZIFS054P001C01  I91

M_D_CPU1_SA_DQS_DP<4>   @S9S_MB_2U_LIB.S9S_MB_2U(SCH_1):M_D_CPU1_SA_DQS_DP<4>
  J23     55  DQS4_A_P  SCONN288_ADR50001P013C01  I126
  J24     55  DQS4_A_P  SCONN288_ADR50001P003C01  I179
  U1     AL58  DDR3_SA_DQS_DP4  SOCKET4677_AZIFS054P001C01  I91

M_D_CPU1_SA_DQS_DP<5>   @S9S_MB_2U_LIB.S9S_MB_2U(SCH_1):M_D_CPU1_SA_DQS_DP<5>
  J23    157  DQS5_A_P  SCONN288_ADR50001P013C01  I126
  J24    157  DQS5_A_P  SCONN288_ADR50001P003C01  I179
  U1     AF73  DDR3_SA_DQS_DP5  SOCKET4677_AZIFS054P001C01  I91

M_D_CPU1_SA_DQS_DP<6>   @S9S_MB_2U_LIB.S9S_MB_2U(SCH_1):M_D_CPU1_SA_DQS_DP<6>
  J23    168  DQS6_A_P  SCONN288_ADR50001P013C01  I126
  J24    168  DQS6_A_P  SCONN288_ADR50001P003C01  I179
  U1     AR76  DDR3_SA_DQS_DP6  SOCKET4677_AZIFS054P001C01  I91

M_D_CPU1_SA_DQS_DP<7>   @S9S_MB_2U_LIB.S9S_MB_2U(SCH_1):M_D_CPU1_SA_DQS_DP<7>
  J23    179  DQS7_A_P  SCONN288_ADR50001P013C01  I126
  J24    179  DQS7_A_P  SCONN288_ADR50001P003C01  I179
  U1     AR70  DDR3_SA_DQS_DP7  SOCKET4677_AZIFS054P001C01  I91

M_D_CPU1_SA_DQS_DP<8>   @S9S_MB_2U_LIB.S9S_MB_2U(SCH_1):M_D_CPU1_SA_DQS_DP<8>
  J23    190  DQS8_A_P  SCONN288_ADR50001P013C01  I126
  J24    190  DQS8_A_P  SCONN288_ADR50001P003C01  I179
  U1     AR64  DDR3_SA_DQS_DP8  SOCKET4677_AZIFS054P001C01  I91

M_D_CPU1_SA_DQS_DP<9>   @S9S_MB_2U_LIB.S9S_MB_2U(SCH_1):M_D_CPU1_SA_DQS_DP<9>
  J23    201  DQS9_A_P  SCONN288_ADR50001P013C01  I126
  J24    201  DQS9_A_P  SCONN288_ADR50001P003C01  I179
  U1     AR58  DDR3_SA_DQS_DP9  SOCKET4677_AZIFS054P001C01  I91

M_D_CPU1_SA_PAR   @S9S_MB_2U_LIB.S9S_MB_2U(SCH_1):M_D_CPU1_SA_PAR
  J23     74  PAR_A  SCONN288_ADR50001P013C01  I25
  J24     74  PAR_A  SCONN288_ADR50001P003C01  I178
  U1     AP44  DDR3_SA_PAR  SOCKET4677_AZIFS054P001C01  I91

M_D_CPU1_SA_RSP<0>   @S9S_MB_2U_LIB.S9S_MB_2U(SCH_1):M_D_CPU1_SA_RSP<0>
  J23     86  LBD||RSP_N_A  SCONN288_ADR50001P013C01  I25
  U1     AD51  DDR3_A_RSP0  SOCKET4677_AZIFS054P001C01  I91

M_D_CPU1_SA_RSP<1>   @S9S_MB_2U_LIB.S9S_MB_2U(SCH_1):M_D_CPU1_SA_RSP<1>
  J24     86  LBD||RSP_N_A  SCONN288_ADR50001P003C01  I178
  U1     AC50  DDR3_A_RSP1  SOCKET4677_AZIFS054P001C01  I91

M_D_CPU1_SB_CA<0>   @S9S_MB_2U_LIB.S9S_MB_2U(SCH_1):M_D_CPU1_SB_CA<0>
  J23     76  CA0_B  SCONN288_ADR50001P013C01  I25
  J24     76  CA0_B  SCONN288_ADR50001P003C01  I178
  U1     AK44  DDR3_SB_CA0  SOCKET4677_AZIFS054P001C01  I91

M_D_CPU1_SB_CA<1>   @S9S_MB_2U_LIB.S9S_MB_2U(SCH_1):M_D_CPU1_SB_CA<1>
  J23    221  CA1_B  SCONN288_ADR50001P013C01  I25
  J24    221  CA1_B  SCONN288_ADR50001P003C01  I178
  U1     AL43  DDR3_SB_CA1  SOCKET4677_AZIFS054P001C01  I91

M_D_CPU1_SB_CA<2>   @S9S_MB_2U_LIB.S9S_MB_2U(SCH_1):M_D_CPU1_SB_CA<2>
  J23     78  CA2_B  SCONN288_ADR50001P013C01  I25
  J24     78  CA2_B  SCONN288_ADR50001P003C01  I178
  U1     AD44  DDR3_SB_CA2  SOCKET4677_AZIFS054P001C01  I91

M_D_CPU1_SB_CA<3>   @S9S_MB_2U_LIB.S9S_MB_2U(SCH_1):M_D_CPU1_SB_CA<3>
  J23    223  CA3_B  SCONN288_ADR50001P013C01  I25
  J24    223  CA3_B  SCONN288_ADR50001P003C01  I178
  U1     AF44  DDR3_SB_CA3  SOCKET4677_AZIFS054P001C01  I91

M_D_CPU1_SB_CA<4>   @S9S_MB_2U_LIB.S9S_MB_2U(SCH_1):M_D_CPU1_SB_CA<4>
  J23     80  CA4_B  SCONN288_ADR50001P013C01  I25
  J24     80  CA4_B  SCONN288_ADR50001P003C01  I178
  U1     AC43  DDR3_SB_CA4  SOCKET4677_AZIFS054P001C01  I91

M_D_CPU1_SB_CA<5>   @S9S_MB_2U_LIB.S9S_MB_2U(SCH_1):M_D_CPU1_SB_CA<5>
  J23    225  CA5_B  SCONN288_ADR50001P013C01  I25
  J24    225  CA5_B  SCONN288_ADR50001P003C01  I178
  U1     AG43  DDR3_SB_CA5  SOCKET4677_AZIFS054P001C01  I91

M_D_CPU1_SB_CA<6>   @S9S_MB_2U_LIB.S9S_MB_2U(SCH_1):M_D_CPU1_SB_CA<6>
  J23     82  CA6_B  SCONN288_ADR50001P013C01  I25
  J24     82  CA6_B  SCONN288_ADR50001P003C01  I178
  U1     AB42  DDR3_SB_CA6  SOCKET4677_AZIFS054P001C01  I91

M_D_CPU1_SB_CB<0>   @S9S_MB_2U_LIB.S9S_MB_2U(SCH_1):M_D_CPU1_SB_CB<0>
  J23     96  CB_B0  SCONN288_ADR50001P013C01  I25
  J24     96  CB_B0  SCONN288_ADR50001P003C01  I178
  U1     AK38  DDR3_SB_ECC0  SOCKET4677_AZIFS054P001C01  I91

M_D_CPU1_SB_CB<1>   @S9S_MB_2U_LIB.S9S_MB_2U(SCH_1):M_D_CPU1_SB_CB<1>
  J23     98  CB_B1  SCONN288_ADR50001P013C01  I25
  J24     98  CB_B1  SCONN288_ADR50001P003C01  I178
  U1     AL37  DDR3_SB_ECC1  SOCKET4677_AZIFS054P001C01  I91

M_D_CPU1_SB_CB<2>   @S9S_MB_2U_LIB.S9S_MB_2U(SCH_1):M_D_CPU1_SB_CB<2>
  J23    241  CB_B2  SCONN288_ADR50001P013C01  I25
  J24    241  CB_B2  SCONN288_ADR50001P003C01  I178
  U1     AP38  DDR3_SB_ECC2  SOCKET4677_AZIFS054P001C01  I91

M_D_CPU1_SB_CB<3>   @S9S_MB_2U_LIB.S9S_MB_2U(SCH_1):M_D_CPU1_SB_CB<3>
  J23    243  CB_B3  SCONN288_ADR50001P013C01  I25
  J24    243  CB_B3  SCONN288_ADR50001P003C01  I178
  U1     AN37  DDR3_SB_ECC3  SOCKET4677_AZIFS054P001C01  I91

M_D_CPU1_SB_CB<4>   @S9S_MB_2U_LIB.S9S_MB_2U(SCH_1):M_D_CPU1_SB_CB<4>
  J23     89  CB_B4  SCONN288_ADR50001P013C01  I25
  J24     89  CB_B4  SCONN288_ADR50001P003C01  I178
  U1     AL41  DDR3_SB_ECC4  SOCKET4677_AZIFS054P001C01  I91

M_D_CPU1_SB_CB<5>   @S9S_MB_2U_LIB.S9S_MB_2U(SCH_1):M_D_CPU1_SB_CB<5>
  J23     91  CB_B5  SCONN288_ADR50001P013C01  I25
  J24     91  CB_B5  SCONN288_ADR50001P003C01  I178
  U1     AK40  DDR3_SB_ECC5  SOCKET4677_AZIFS054P001C01  I91

M_D_CPU1_SB_CB<6>   @S9S_MB_2U_LIB.S9S_MB_2U(SCH_1):M_D_CPU1_SB_CB<6>
  J23    234  CB_B6  SCONN288_ADR50001P013C01  I25
  J24    234  CB_B6  SCONN288_ADR50001P003C01  I178
  U1     AN41  DDR3_SB_ECC6  SOCKET4677_AZIFS054P001C01  I91

M_D_CPU1_SB_CB<7>   @S9S_MB_2U_LIB.S9S_MB_2U(SCH_1):M_D_CPU1_SB_CB<7>
  J23    236  CB_B7  SCONN288_ADR50001P013C01  I25
  J24    236  CB_B7  SCONN288_ADR50001P003C01  I178
  U1     AP40  DDR3_SB_ECC7  SOCKET4677_AZIFS054P001C01  I91

M_D_CPU1_SB_CS_N<0>   @S9S_MB_2U_LIB.S9S_MB_2U(SCH_1):M_D_CPU1_SB_CS_N<0>
  J23     84  CS0_N_B  SCONN288_ADR50001P013C01  I25
  U1     AC41  DDR3_SB_CS0_N  SOCKET4677_AZIFS054P001C01  I91

M_D_CPU1_SB_CS_N<1>   @S9S_MB_2U_LIB.S9S_MB_2U(SCH_1):M_D_CPU1_SB_CS_N<1>
  J23    229  CS1_N_B  SCONN288_ADR50001P013C01  I25
  U1     AG41  DDR3_SB_CS1_N  SOCKET4677_AZIFS054P001C01  I91

M_D_CPU1_SB_CS_N<2>   @S9S_MB_2U_LIB.S9S_MB_2U(SCH_1):M_D_CPU1_SB_CS_N<2>
  J24     84  CS0_N_B  SCONN288_ADR50001P003C01  I178
  U1     AF40  DDR3_SB_CS2_N  SOCKET4677_AZIFS054P001C01  I91

M_D_CPU1_SB_CS_N<3>   @S9S_MB_2U_LIB.S9S_MB_2U(SCH_1):M_D_CPU1_SB_CS_N<3>
  J24    229  CS1_N_B  SCONN288_ADR50001P003C01  I178
  U1     AD40  DDR3_SB_CS3_N  SOCKET4677_AZIFS054P001C01  I91

M_D_CPU1_SB_DQ<0>   @S9S_MB_2U_LIB.S9S_MB_2U(SCH_1):M_D_CPU1_SB_DQ<0>
  J23    100  DQ_B0  SCONN288_ADR50001P013C01  I25
  J24    100  DQ_B0  SCONN288_ADR50001P003C01  I178
  U1     AL35  DDR3_SB_DQ0  SOCKET4677_AZIFS054P001C01  I91

M_D_CPU1_SB_DQ<1>   @S9S_MB_2U_LIB.S9S_MB_2U(SCH_1):M_D_CPU1_SB_DQ<1>
  J23    102  DQ_B1  SCONN288_ADR50001P013C01  I25
  J24    102  DQ_B1  SCONN288_ADR50001P003C01  I178
  U1     AK34  DDR3_SB_DQ1  SOCKET4677_AZIFS054P001C01  I91

M_D_CPU1_SB_DQ<2>   @S9S_MB_2U_LIB.S9S_MB_2U(SCH_1):M_D_CPU1_SB_DQ<2>
  J23    245  DQ_B2  SCONN288_ADR50001P013C01  I25
  J24    245  DQ_B2  SCONN288_ADR50001P003C01  I178
  U1     AN35  DDR3_SB_DQ2  SOCKET4677_AZIFS054P001C01  I91

M_D_CPU1_SB_DQ<3>   @S9S_MB_2U_LIB.S9S_MB_2U(SCH_1):M_D_CPU1_SB_DQ<3>
  J23    247  DQ_B3  SCONN288_ADR50001P013C01  I25
  J24    247  DQ_B3  SCONN288_ADR50001P003C01  I178
  U1     AP34  DDR3_SB_DQ3  SOCKET4677_AZIFS054P001C01  I91

M_D_CPU1_SB_DQ<4>   @S9S_MB_2U_LIB.S9S_MB_2U(SCH_1):M_D_CPU1_SB_DQ<4>
  J23    107  DQ_B4  SCONN288_ADR50001P013C01  I25
  J24    107  DQ_B4  SCONN288_ADR50001P003C01  I178
  U1     AK32  DDR3_SB_DQ4  SOCKET4677_AZIFS054P001C01  I91

M_D_CPU1_SB_DQ<5>   @S9S_MB_2U_LIB.S9S_MB_2U(SCH_1):M_D_CPU1_SB_DQ<5>
  J23    109  DQ_B5  SCONN288_ADR50001P013C01  I25
  J24    109  DQ_B5  SCONN288_ADR50001P003C01  I178
  U1     AL31  DDR3_SB_DQ5  SOCKET4677_AZIFS054P001C01  I91

M_D_CPU1_SB_DQ<6>   @S9S_MB_2U_LIB.S9S_MB_2U(SCH_1):M_D_CPU1_SB_DQ<6>
  J23    252  DQ_B6  SCONN288_ADR50001P013C01  I25
  J24    252  DQ_B6  SCONN288_ADR50001P003C01  I178
  U1     AP32  DDR3_SB_DQ6  SOCKET4677_AZIFS054P001C01  I91

M_D_CPU1_SB_DQ<7>   @S9S_MB_2U_LIB.S9S_MB_2U(SCH_1):M_D_CPU1_SB_DQ<7>
  J23    254  DQ_B7  SCONN288_ADR50001P013C01  I25
  J24    254  DQ_B7  SCONN288_ADR50001P003C01  I178
  U1     AN31  DDR3_SB_DQ7  SOCKET4677_AZIFS054P001C01  I91

M_D_CPU1_SB_DQ<8>   @S9S_MB_2U_LIB.S9S_MB_2U(SCH_1):M_D_CPU1_SB_DQ<8>
  J23    111  DQ_B8  SCONN288_ADR50001P013C01  I25
  J24    111  DQ_B8  SCONN288_ADR50001P003C01  I178
  U1     AL29  DDR3_SB_DQ8  SOCKET4677_AZIFS054P001C01  I91

M_D_CPU1_SB_DQ<9>   @S9S_MB_2U_LIB.S9S_MB_2U(SCH_1):M_D_CPU1_SB_DQ<9>
  J23    113  DQ_B9  SCONN288_ADR50001P013C01  I25
  J24    113  DQ_B9  SCONN288_ADR50001P003C01  I178
  U1     AK28  DDR3_SB_DQ9  SOCKET4677_AZIFS054P001C01  I91

M_D_CPU1_SB_DQ<10>   @S9S_MB_2U_LIB.S9S_MB_2U(SCH_1):M_D_CPU1_SB_DQ<10>
  J23    256  DQ_B10  SCONN288_ADR50001P013C01  I25
  J24    256  DQ_B10  SCONN288_ADR50001P003C01  I178
  U1     AN29  DDR3_SB_DQ10  SOCKET4677_AZIFS054P001C01  I91

M_D_CPU1_SB_DQ<11>   @S9S_MB_2U_LIB.S9S_MB_2U(SCH_1):M_D_CPU1_SB_DQ<11>
  J23    258  DQ_B11  SCONN288_ADR50001P013C01  I25
  J24    258  DQ_B11  SCONN288_ADR50001P003C01  I178
  U1     AP28  DDR3_SB_DQ11  SOCKET4677_AZIFS054P001C01  I91

M_D_CPU1_SB_DQ<12>   @S9S_MB_2U_LIB.S9S_MB_2U(SCH_1):M_D_CPU1_SB_DQ<12>
  J23    118  DQ_B12  SCONN288_ADR50001P013C01  I25
  J24    118  DQ_B12  SCONN288_ADR50001P003C01  I178
  U1     AK26  DDR3_SB_DQ12  SOCKET4677_AZIFS054P001C01  I91

M_D_CPU1_SB_DQ<13>   @S9S_MB_2U_LIB.S9S_MB_2U(SCH_1):M_D_CPU1_SB_DQ<13>
  J23    120  DQ_B13  SCONN288_ADR50001P013C01  I25
  J24    120  DQ_B13  SCONN288_ADR50001P003C01  I178
  U1     AL25  DDR3_SB_DQ13  SOCKET4677_AZIFS054P001C01  I91

M_D_CPU1_SB_DQ<14>   @S9S_MB_2U_LIB.S9S_MB_2U(SCH_1):M_D_CPU1_SB_DQ<14>
  J23    263  DQ_B14  SCONN288_ADR50001P013C01  I25
  J24    263  DQ_B14  SCONN288_ADR50001P003C01  I178
  U1     AP26  DDR3_SB_DQ14  SOCKET4677_AZIFS054P001C01  I91

M_D_CPU1_SB_DQ<15>   @S9S_MB_2U_LIB.S9S_MB_2U(SCH_1):M_D_CPU1_SB_DQ<15>
  J23    265  DQ_B15  SCONN288_ADR50001P013C01  I25
  J24    265  DQ_B15  SCONN288_ADR50001P003C01  I178
  U1     AN25  DDR3_SB_DQ15  SOCKET4677_AZIFS054P001C01  I91

M_D_CPU1_SB_DQ<16>   @S9S_MB_2U_LIB.S9S_MB_2U(SCH_1):M_D_CPU1_SB_DQ<16>
  J23    122  DQ_B16  SCONN288_ADR50001P013C01  I25
  J24    122  DQ_B16  SCONN288_ADR50001P003C01  I178
  U1     AD26  DDR3_SB_DQ16  SOCKET4677_AZIFS054P001C01  I91

M_D_CPU1_SB_DQ<17>   @S9S_MB_2U_LIB.S9S_MB_2U(SCH_1):M_D_CPU1_SB_DQ<17>
  J23    124  DQ_B17  SCONN288_ADR50001P013C01  I25
  J24    124  DQ_B17  SCONN288_ADR50001P003C01  I178
  U1     AC25  DDR3_SB_DQ17  SOCKET4677_AZIFS054P001C01  I91

M_D_CPU1_SB_DQ<18>   @S9S_MB_2U_LIB.S9S_MB_2U(SCH_1):M_D_CPU1_SB_DQ<18>
  J23    267  DQ_B18  SCONN288_ADR50001P013C01  I25
  J24    267  DQ_B18  SCONN288_ADR50001P003C01  I178
  U1     AF26  DDR3_SB_DQ18  SOCKET4677_AZIFS054P001C01  I91

M_D_CPU1_SB_DQ<19>   @S9S_MB_2U_LIB.S9S_MB_2U(SCH_1):M_D_CPU1_SB_DQ<19>
  J23    269  DQ_B19  SCONN288_ADR50001P013C01  I25
  J24    269  DQ_B19  SCONN288_ADR50001P003C01  I178
  U1     AG25  DDR3_SB_DQ19  SOCKET4677_AZIFS054P001C01  I91

M_D_CPU1_SB_DQ<20>   @S9S_MB_2U_LIB.S9S_MB_2U(SCH_1):M_D_CPU1_SB_DQ<20>
  J23    129  DQ_B20  SCONN288_ADR50001P013C01  I25
  J24    129  DQ_B20  SCONN288_ADR50001P003C01  I178
  U1     AC23  DDR3_SB_DQ20  SOCKET4677_AZIFS054P001C01  I91

M_D_CPU1_SB_DQ<21>   @S9S_MB_2U_LIB.S9S_MB_2U(SCH_1):M_D_CPU1_SB_DQ<21>
  J23    131  DQ_B21  SCONN288_ADR50001P013C01  I25
  J24    131  DQ_B21  SCONN288_ADR50001P003C01  I178
  U1     AD22  DDR3_SB_DQ21  SOCKET4677_AZIFS054P001C01  I91

M_D_CPU1_SB_DQ<22>   @S9S_MB_2U_LIB.S9S_MB_2U(SCH_1):M_D_CPU1_SB_DQ<22>
  J23    274  DQ_B22  SCONN288_ADR50001P013C01  I25
  J24    274  DQ_B22  SCONN288_ADR50001P003C01  I178
  U1     AG23  DDR3_SB_DQ22  SOCKET4677_AZIFS054P001C01  I91

M_D_CPU1_SB_DQ<23>   @S9S_MB_2U_LIB.S9S_MB_2U(SCH_1):M_D_CPU1_SB_DQ<23>
  J23    276  DQ_B23  SCONN288_ADR50001P013C01  I25
  J24    276  DQ_B23  SCONN288_ADR50001P003C01  I178
  U1     AF22  DDR3_SB_DQ23  SOCKET4677_AZIFS054P001C01  I91

M_D_CPU1_SB_DQ<24>   @S9S_MB_2U_LIB.S9S_MB_2U(SCH_1):M_D_CPU1_SB_DQ<24>
  J23    133  DQ_B24  SCONN288_ADR50001P013C01  I25
  J24    133  DQ_B24  SCONN288_ADR50001P003C01  I178
  U1     AL23  DDR3_SB_DQ24  SOCKET4677_AZIFS054P001C01  I91

M_D_CPU1_SB_DQ<25>   @S9S_MB_2U_LIB.S9S_MB_2U(SCH_1):M_D_CPU1_SB_DQ<25>
  J23    135  DQ_B25  SCONN288_ADR50001P013C01  I25
  J24    135  DQ_B25  SCONN288_ADR50001P003C01  I178
  U1     AK22  DDR3_SB_DQ25  SOCKET4677_AZIFS054P001C01  I91

M_D_CPU1_SB_DQ<26>   @S9S_MB_2U_LIB.S9S_MB_2U(SCH_1):M_D_CPU1_SB_DQ<26>
  J23    278  DQ_B26  SCONN288_ADR50001P013C01  I25
  J24    278  DQ_B26  SCONN288_ADR50001P003C01  I178
  U1     AN23  DDR3_SB_DQ26  SOCKET4677_AZIFS054P001C01  I91

M_D_CPU1_SB_DQ<27>   @S9S_MB_2U_LIB.S9S_MB_2U(SCH_1):M_D_CPU1_SB_DQ<27>
  J23    280  DQ_B27  SCONN288_ADR50001P013C01  I25
  J24    280  DQ_B27  SCONN288_ADR50001P003C01  I178
  U1     AP22  DDR3_SB_DQ27  SOCKET4677_AZIFS054P001C01  I91

M_D_CPU1_SB_DQ<28>   @S9S_MB_2U_LIB.S9S_MB_2U(SCH_1):M_D_CPU1_SB_DQ<28>
  J23    140  DQ_B28  SCONN288_ADR50001P013C01  I25
  J24    140  DQ_B28  SCONN288_ADR50001P003C01  I178
  U1     AK20  DDR3_SB_DQ28  SOCKET4677_AZIFS054P001C01  I91

M_D_CPU1_SB_DQ<29>   @S9S_MB_2U_LIB.S9S_MB_2U(SCH_1):M_D_CPU1_SB_DQ<29>
  J23    142  DQ_B29  SCONN288_ADR50001P013C01  I25
  J24    142  DQ_B29  SCONN288_ADR50001P003C01  I178
  U1     AL19  DDR3_SB_DQ29  SOCKET4677_AZIFS054P001C01  I91

M_D_CPU1_SB_DQ<30>   @S9S_MB_2U_LIB.S9S_MB_2U(SCH_1):M_D_CPU1_SB_DQ<30>
  J23    285  DQ_B30  SCONN288_ADR50001P013C01  I25
  J24    285  DQ_B30  SCONN288_ADR50001P003C01  I178
  U1     AP20  DDR3_SB_DQ30  SOCKET4677_AZIFS054P001C01  I91

M_D_CPU1_SB_DQ<31>   @S9S_MB_2U_LIB.S9S_MB_2U(SCH_1):M_D_CPU1_SB_DQ<31>
  J23    287  DQ_B31  SCONN288_ADR50001P013C01  I25
  J24    287  DQ_B31  SCONN288_ADR50001P003C01  I178
  U1     AN19  DDR3_SB_DQ31  SOCKET4677_AZIFS054P001C01  I91

M_D_CPU1_SB_DQS_DN<0>   @S9S_MB_2U_LIB.S9S_MB_2U(SCH_1):M_D_CPU1_SB_DQS_DN<0>
  J23    105  DQS0_B_N  SCONN288_ADR50001P013C01  I126
  J24    105  DQS0_B_N  SCONN288_ADR50001P003C01  I179
  U1     AJ33  DDR3_SB_DQS_DN0  SOCKET4677_AZIFS054P001C01  I91

M_D_CPU1_SB_DQS_DN<1>   @S9S_MB_2U_LIB.S9S_MB_2U(SCH_1):M_D_CPU1_SB_DQS_DN<1>
  J23    116  DQS1_B_N  SCONN288_ADR50001P013C01  I126
  J24    116  DQS1_B_N  SCONN288_ADR50001P003C01  I179
  U1     AJ27  DDR3_SB_DQS_DN1  SOCKET4677_AZIFS054P001C01  I91

M_D_CPU1_SB_DQS_DN<2>   @S9S_MB_2U_LIB.S9S_MB_2U(SCH_1):M_D_CPU1_SB_DQS_DN<2>
  J23    127  DQS2_B_N  SCONN288_ADR50001P013C01  I126
  J24    127  DQS2_B_N  SCONN288_ADR50001P003C01  I179
  U1     AB24  DDR3_SB_DQS_DN2  SOCKET4677_AZIFS054P001C01  I91

M_D_CPU1_SB_DQS_DN<3>   @S9S_MB_2U_LIB.S9S_MB_2U(SCH_1):M_D_CPU1_SB_DQS_DN<3>
  J23    138  DQS3_B_N  SCONN288_ADR50001P013C01  I126
  J24    138  DQS3_B_N  SCONN288_ADR50001P003C01  I179
  U1     AJ21  DDR3_SB_DQS_DN3  SOCKET4677_AZIFS054P001C01  I91

M_D_CPU1_SB_DQS_DN<4>   @S9S_MB_2U_LIB.S9S_MB_2U(SCH_1):M_D_CPU1_SB_DQS_DN<4>
  J23    238  DQS4_B_N  SCONN288_ADR50001P013C01  I126
  J24    238  DQS4_B_N  SCONN288_ADR50001P003C01  I179
  U1     AR39  DDR3_SB_DQS_DN4  SOCKET4677_AZIFS054P001C01  I91

M_D_CPU1_SB_DQS_DN<5>   @S9S_MB_2U_LIB.S9S_MB_2U(SCH_1):M_D_CPU1_SB_DQS_DN<5>
  J23    249  DQS5_B_N  SCONN288_ADR50001P013C01  I126
  J24    249  DQS5_B_N  SCONN288_ADR50001P003C01  I179
  U1     AN33  DDR3_SB_DQS_DN5  SOCKET4677_AZIFS054P001C01  I91

M_D_CPU1_SB_DQS_DN<6>   @S9S_MB_2U_LIB.S9S_MB_2U(SCH_1):M_D_CPU1_SB_DQS_DN<6>
  J23    260  DQS6_B_N  SCONN288_ADR50001P013C01  I126
  J24    260  DQS6_B_N  SCONN288_ADR50001P003C01  I179
  U1     AN27  DDR3_SB_DQS_DN6  SOCKET4677_AZIFS054P001C01  I91

M_D_CPU1_SB_DQS_DN<7>   @S9S_MB_2U_LIB.S9S_MB_2U(SCH_1):M_D_CPU1_SB_DQS_DN<7>
  J23    271  DQS7_B_N  SCONN288_ADR50001P013C01  I126
  J24    271  DQS7_B_N  SCONN288_ADR50001P003C01  I179
  U1     AF24  DDR3_SB_DQS_DN7  SOCKET4677_AZIFS054P001C01  I91

M_D_CPU1_SB_DQS_DN<8>   @S9S_MB_2U_LIB.S9S_MB_2U(SCH_1):M_D_CPU1_SB_DQS_DN<8>
  J23    282  DQS8_B_N  SCONN288_ADR50001P013C01  I126
  J24    282  DQS8_B_N  SCONN288_ADR50001P003C01  I179
  U1     AN21  DDR3_SB_DQS_DN8  SOCKET4677_AZIFS054P001C01  I91

M_D_CPU1_SB_DQS_DN<9>   @S9S_MB_2U_LIB.S9S_MB_2U(SCH_1):M_D_CPU1_SB_DQS_DN<9>
  J23     94  DQS9_B_N  SCONN288_ADR50001P013C01  I126
  J24     94  DQS9_B_N  SCONN288_ADR50001P003C01  I179
  U1     AJ39  DDR3_SB_DQS_DN9  SOCKET4677_AZIFS054P001C01  I91

M_D_CPU1_SB_DQS_DP<0>   @S9S_MB_2U_LIB.S9S_MB_2U(SCH_1):M_D_CPU1_SB_DQS_DP<0>
  J23    104  DQS0_B_P  SCONN288_ADR50001P013C01  I126
  J24    104  DQS0_B_P  SCONN288_ADR50001P003C01  I179
  U1     AL33  DDR3_SB_DQS_DP0  SOCKET4677_AZIFS054P001C01  I91

M_D_CPU1_SB_DQS_DP<1>   @S9S_MB_2U_LIB.S9S_MB_2U(SCH_1):M_D_CPU1_SB_DQS_DP<1>
  J23    115  DQS1_B_P  SCONN288_ADR50001P013C01  I126
  J24    115  DQS1_B_P  SCONN288_ADR50001P003C01  I179
  U1     AL27  DDR3_SB_DQS_DP1  SOCKET4677_AZIFS054P001C01  I91

M_D_CPU1_SB_DQS_DP<2>   @S9S_MB_2U_LIB.S9S_MB_2U(SCH_1):M_D_CPU1_SB_DQS_DP<2>
  J23    126  DQS2_B_P  SCONN288_ADR50001P013C01  I126
  J24    126  DQS2_B_P  SCONN288_ADR50001P003C01  I179
  U1     AD24  DDR3_SB_DQS_DP2  SOCKET4677_AZIFS054P001C01  I91

M_D_CPU1_SB_DQS_DP<3>   @S9S_MB_2U_LIB.S9S_MB_2U(SCH_1):M_D_CPU1_SB_DQS_DP<3>
  J23    137  DQS3_B_P  SCONN288_ADR50001P013C01  I126
  J24    137  DQS3_B_P  SCONN288_ADR50001P003C01  I179
  U1     AL21  DDR3_SB_DQS_DP3  SOCKET4677_AZIFS054P001C01  I91

M_D_CPU1_SB_DQS_DP<4>   @S9S_MB_2U_LIB.S9S_MB_2U(SCH_1):M_D_CPU1_SB_DQS_DP<4>
  J23    239  DQS4_B_P  SCONN288_ADR50001P013C01  I126
  J24    239  DQS4_B_P  SCONN288_ADR50001P003C01  I179
  U1     AN39  DDR3_SB_DQS_DP4  SOCKET4677_AZIFS054P001C01  I91

M_D_CPU1_SB_DQS_DP<5>   @S9S_MB_2U_LIB.S9S_MB_2U(SCH_1):M_D_CPU1_SB_DQS_DP<5>
  J23    250  DQS5_B_P  SCONN288_ADR50001P013C01  I126
  J24    250  DQS5_B_P  SCONN288_ADR50001P003C01  I179
  U1     AR33  DDR3_SB_DQS_DP5  SOCKET4677_AZIFS054P001C01  I91

M_D_CPU1_SB_DQS_DP<6>   @S9S_MB_2U_LIB.S9S_MB_2U(SCH_1):M_D_CPU1_SB_DQS_DP<6>
  J23    261  DQS6_B_P  SCONN288_ADR50001P013C01  I126
  J24    261  DQS6_B_P  SCONN288_ADR50001P003C01  I179
  U1     AR27  DDR3_SB_DQS_DP6  SOCKET4677_AZIFS054P001C01  I91

M_D_CPU1_SB_DQS_DP<7>   @S9S_MB_2U_LIB.S9S_MB_2U(SCH_1):M_D_CPU1_SB_DQS_DP<7>
  J23    272  DQS7_B_P  SCONN288_ADR50001P013C01  I126
  J24    272  DQS7_B_P  SCONN288_ADR50001P003C01  I179
  U1     AH24  DDR3_SB_DQS_DP7  SOCKET4677_AZIFS054P001C01  I91

M_D_CPU1_SB_DQS_DP<8>   @S9S_MB_2U_LIB.S9S_MB_2U(SCH_1):M_D_CPU1_SB_DQS_DP<8>
  J23    283  DQS8_B_P  SCONN288_ADR50001P013C01  I126
  J24    283  DQS8_B_P  SCONN288_ADR50001P003C01  I179
  U1     AR21  DDR3_SB_DQS_DP8  SOCKET4677_AZIFS054P001C01  I91

M_D_CPU1_SB_DQS_DP<9>   @S9S_MB_2U_LIB.S9S_MB_2U(SCH_1):M_D_CPU1_SB_DQS_DP<9>
  J23     93  DQS9_B_P  SCONN288_ADR50001P013C01  I126
  J24     93  DQS9_B_P  SCONN288_ADR50001P003C01  I179
  U1     AL39  DDR3_SB_DQS_DP9  SOCKET4677_AZIFS054P001C01  I91

M_D_CPU1_SB_PAR   @S9S_MB_2U_LIB.S9S_MB_2U(SCH_1):M_D_CPU1_SB_PAR
  J23    227  PAR_B  SCONN288_ADR50001P013C01  I25
  J24    227  PAR_B  SCONN288_ADR50001P003C01  I178
  U1     AH42  DDR3_SB_PAR  SOCKET4677_AZIFS054P001C01  I91

M_D_CPU1_SB_RSP<0>   @S9S_MB_2U_LIB.S9S_MB_2U(SCH_1):M_D_CPU1_SB_RSP<0>
  J23     87  LBS||RSP_N_B  SCONN288_ADR50001P013C01  I25
  U1     AF51  DDR3_B_RSP0  SOCKET4677_AZIFS054P001C01  I91

M_D_CPU1_SB_RSP<1>   @S9S_MB_2U_LIB.S9S_MB_2U(SCH_1):M_D_CPU1_SB_RSP<1>
  J24     87  LBS||RSP_N_B  SCONN288_ADR50001P003C01  I178
  U1     AG50  DDR3_B_RSP1  SOCKET4677_AZIFS054P001C01  I91

M_E_CPU0_ALERT_N   @S9S_MB_2U_LIB.S9S_MB_2U(SCH_1):M_E_CPU0_ALERT_N
  J9      62  ALERT_N  SCONN288_ADR50001P013C01  I12
  J10     62  ALERT_N  SCONN288_ADR50001P003C01  I13
  U2     CY47  DDR4_ALERT_N  SOCKET4677_AZIFS054P001C01  I169

M_E_CPU0_CLK_DN<0>   @S9S_MB_2U_LIB.S9S_MB_2U(SCH_1):M_E_CPU0_CLK_DN<0>
  J9     218   CK_N  SCONN288_ADR50001P013C01  I12
  U2     EJ45  DDR4_CLK_DN0  SOCKET4677_AZIFS054P001C01  I169

M_E_CPU0_CLK_DN<1>   @S9S_MB_2U_LIB.S9S_MB_2U(SCH_1):M_E_CPU0_CLK_DN<1>
  J10    218   CK_N  SCONN288_ADR50001P003C01  I13
  U2     EE45  DDR4_CLK_DN1  SOCKET4677_AZIFS054P001C01  I169

M_E_CPU0_CLK_DP<0>   @S9S_MB_2U_LIB.S9S_MB_2U(SCH_1):M_E_CPU0_CLK_DP<0>
  J9     217   CK_P  SCONN288_ADR50001P013C01  I12
  U2     EG45  DDR4_CLK_DP0  SOCKET4677_AZIFS054P001C01  I169

M_E_CPU0_CLK_DP<1>   @S9S_MB_2U_LIB.S9S_MB_2U(SCH_1):M_E_CPU0_CLK_DP<1>
  J10    217   CK_P  SCONN288_ADR50001P003C01  I13
  U2     EC45  DDR4_CLK_DP1  SOCKET4677_AZIFS054P001C01  I169

M_E_CPU0_SA_CA<0>   @S9S_MB_2U_LIB.S9S_MB_2U(SCH_1):M_E_CPU0_SA_CA<0>
  J9      66  CA0_A  SCONN288_ADR50001P013C01  I12
  J10     66  CA0_A  SCONN288_ADR50001P003C01  I13
  U2     EP49  DDR4_SA_CA0  SOCKET4677_AZIFS054P001C01  I169

M_E_CPU0_SA_CA<1>   @S9S_MB_2U_LIB.S9S_MB_2U(SCH_1):M_E_CPU0_SA_CA<1>
  J9     211  CA1_A  SCONN288_ADR50001P013C01  I12
  J10    211  CA1_A  SCONN288_ADR50001P003C01  I13
  U2     ET49  DDR4_SA_CA1  SOCKET4677_AZIFS054P001C01  I169

M_E_CPU0_SA_CA<2>   @S9S_MB_2U_LIB.S9S_MB_2U(SCH_1):M_E_CPU0_SA_CA<2>
  J9      68  CA2_A  SCONN288_ADR50001P013C01  I12
  J10     68  CA2_A  SCONN288_ADR50001P003C01  I13
  U2     EK49  DDR4_SA_CA2  SOCKET4677_AZIFS054P001C01  I169

M_E_CPU0_SA_CA<3>   @S9S_MB_2U_LIB.S9S_MB_2U(SCH_1):M_E_CPU0_SA_CA<3>
  J9     213  CA3_A  SCONN288_ADR50001P013C01  I12
  J10    213  CA3_A  SCONN288_ADR50001P003C01  I13
  U2     EL48  DDR4_SA_CA3  SOCKET4677_AZIFS054P001C01  I169

M_E_CPU0_SA_CA<4>   @S9S_MB_2U_LIB.S9S_MB_2U(SCH_1):M_E_CPU0_SA_CA<4>
  J9      70  CA4_A  SCONN288_ADR50001P013C01  I12
  J10     70  CA4_A  SCONN288_ADR50001P003C01  I13
  U2     EM47  DDR4_SA_CA4  SOCKET4677_AZIFS054P001C01  I169

M_E_CPU0_SA_CA<5>   @S9S_MB_2U_LIB.S9S_MB_2U(SCH_1):M_E_CPU0_SA_CA<5>
  J9     215  CA5_A  SCONN288_ADR50001P013C01  I12
  J10    215  CA5_A  SCONN288_ADR50001P003C01  I13
  U2     EP47  DDR4_SA_CA5  SOCKET4677_AZIFS054P001C01  I169

M_E_CPU0_SA_CA<6>   @S9S_MB_2U_LIB.S9S_MB_2U(SCH_1):M_E_CPU0_SA_CA<6>
  J9      72  CA6_A  SCONN288_ADR50001P013C01  I12
  J10     72  CA6_A  SCONN288_ADR50001P003C01  I13
  U2     ED44  DDR4_SA_CA6  SOCKET4677_AZIFS054P001C01  I169

M_E_CPU0_SA_CB<0>   @S9S_MB_2U_LIB.S9S_MB_2U(SCH_1):M_E_CPU0_SA_CB<0>
  J9      51  CB_A0  SCONN288_ADR50001P013C01  I12
  J10     51  CB_A0  SCONN288_ADR50001P003C01  I13
  U2     EM57  DDR4_SA_ECC0  SOCKET4677_AZIFS054P001C01  I169

M_E_CPU0_SA_CB<1>   @S9S_MB_2U_LIB.S9S_MB_2U(SCH_1):M_E_CPU0_SA_CB<1>
  J9      53  CB_A1  SCONN288_ADR50001P013C01  I12
  J10     53  CB_A1  SCONN288_ADR50001P003C01  I13
  U2     EL56  DDR4_SA_ECC1  SOCKET4677_AZIFS054P001C01  I169

M_E_CPU0_SA_CB<2>   @S9S_MB_2U_LIB.S9S_MB_2U(SCH_1):M_E_CPU0_SA_CB<2>
  J9     196  CB_A2  SCONN288_ADR50001P013C01  I12
  J10    196  CB_A2  SCONN288_ADR50001P003C01  I13
  U2     EP57  DDR4_SA_ECC2  SOCKET4677_AZIFS054P001C01  I169

M_E_CPU0_SA_CB<3>   @S9S_MB_2U_LIB.S9S_MB_2U(SCH_1):M_E_CPU0_SA_CB<3>
  J9     198  CB_A3  SCONN288_ADR50001P013C01  I12
  J10    198  CB_A3  SCONN288_ADR50001P003C01  I13
  U2     ER56  DDR4_SA_ECC3  SOCKET4677_AZIFS054P001C01  I169

M_E_CPU0_SA_CB<4>   @S9S_MB_2U_LIB.S9S_MB_2U(SCH_1):M_E_CPU0_SA_CB<4>
  J9      58  CB_A4  SCONN288_ADR50001P013C01  I12
  J10     58  CB_A4  SCONN288_ADR50001P003C01  I13
  U2     EL54  DDR4_SA_ECC4  SOCKET4677_AZIFS054P001C01  I169

M_E_CPU0_SA_CB<5>   @S9S_MB_2U_LIB.S9S_MB_2U(SCH_1):M_E_CPU0_SA_CB<5>
  J9      60  CB_A5  SCONN288_ADR50001P013C01  I12
  J10     60  CB_A5  SCONN288_ADR50001P003C01  I13
  U2     EM53  DDR4_SA_ECC5  SOCKET4677_AZIFS054P001C01  I169

M_E_CPU0_SA_CB<6>   @S9S_MB_2U_LIB.S9S_MB_2U(SCH_1):M_E_CPU0_SA_CB<6>
  J9     203  CB_A6  SCONN288_ADR50001P013C01  I12
  J10    203  CB_A6  SCONN288_ADR50001P003C01  I13
  U2     ER54  DDR4_SA_ECC6  SOCKET4677_AZIFS054P001C01  I169

M_E_CPU0_SA_CB<7>   @S9S_MB_2U_LIB.S9S_MB_2U(SCH_1):M_E_CPU0_SA_CB<7>
  J9     205  CB_A7  SCONN288_ADR50001P013C01  I12
  J10    205  CB_A7  SCONN288_ADR50001P003C01  I13
  U2     EP53  DDR4_SA_ECC7  SOCKET4677_AZIFS054P001C01  I169

M_E_CPU0_SA_CS_N<0>   @S9S_MB_2U_LIB.S9S_MB_2U(SCH_1):M_E_CPU0_SA_CS_N<0>
  J9      64  CS0_N_A  SCONN288_ADR50001P013C01  I12
  U2     EP51  DDR4_SA_CS0_N  SOCKET4677_AZIFS054P001C01  I169

M_E_CPU0_SA_CS_N<1>   @S9S_MB_2U_LIB.S9S_MB_2U(SCH_1):M_E_CPU0_SA_CS_N<1>
  J9     209  CS1_N_A  SCONN288_ADR50001P013C01  I12
  U2     ET51  DDR4_SA_CS1_N  SOCKET4677_AZIFS054P001C01  I169

M_E_CPU0_SA_CS_N<2>   @S9S_MB_2U_LIB.S9S_MB_2U(SCH_1):M_E_CPU0_SA_CS_N<2>
  J10     64  CS0_N_A  SCONN288_ADR50001P003C01  I13
  U2     EM51  DDR4_SA_CS2_N  SOCKET4677_AZIFS054P001C01  I169

M_E_CPU0_SA_CS_N<3>   @S9S_MB_2U_LIB.S9S_MB_2U(SCH_1):M_E_CPU0_SA_CS_N<3>
  J10    209  CS1_N_A  SCONN288_ADR50001P003C01  I13
  U2     EL50  DDR4_SA_CS3_N  SOCKET4677_AZIFS054P001C01  I169

M_E_CPU0_SA_DQ<0>   @S9S_MB_2U_LIB.S9S_MB_2U(SCH_1):M_E_CPU0_SA_DQ<0>
  J9       7  DQ_A0  SCONN288_ADR50001P013C01  I12
  J10      7  DQ_A0  SCONN288_ADR50001P003C01  I13
  U2     EL78  DDR4_SA_DQ0  SOCKET4677_AZIFS054P001C01  I169

M_E_CPU0_SA_DQ<1>   @S9S_MB_2U_LIB.S9S_MB_2U(SCH_1):M_E_CPU0_SA_DQ<1>
  J9       9  DQ_A1  SCONN288_ADR50001P013C01  I12
  J10      9  DQ_A1  SCONN288_ADR50001P003C01  I13
  U2     EM77  DDR4_SA_DQ1  SOCKET4677_AZIFS054P001C01  I169

M_E_CPU0_SA_DQ<2>   @S9S_MB_2U_LIB.S9S_MB_2U(SCH_1):M_E_CPU0_SA_DQ<2>
  J9     152  DQ_A2  SCONN288_ADR50001P013C01  I12
  J10    152  DQ_A2  SCONN288_ADR50001P003C01  I13
  U2     EP79  DDR4_SA_DQ2  SOCKET4677_AZIFS054P001C01  I169

M_E_CPU0_SA_DQ<3>   @S9S_MB_2U_LIB.S9S_MB_2U(SCH_1):M_E_CPU0_SA_DQ<3>
  J9     154  DQ_A3  SCONN288_ADR50001P013C01  I12
  J10    154  DQ_A3  SCONN288_ADR50001P003C01  I13
  U2     ER76  DDR4_SA_DQ3  SOCKET4677_AZIFS054P001C01  I169

M_E_CPU0_SA_DQ<4>   @S9S_MB_2U_LIB.S9S_MB_2U(SCH_1):M_E_CPU0_SA_DQ<4>
  J9      14  DQ_A4  SCONN288_ADR50001P013C01  I12
  J10     14  DQ_A4  SCONN288_ADR50001P003C01  I13
  U2     EL74  DDR4_SA_DQ4  SOCKET4677_AZIFS054P001C01  I169

M_E_CPU0_SA_DQ<5>   @S9S_MB_2U_LIB.S9S_MB_2U(SCH_1):M_E_CPU0_SA_DQ<5>
  J9      16  DQ_A5  SCONN288_ADR50001P013C01  I12
  J10     16  DQ_A5  SCONN288_ADR50001P003C01  I13
  U2     EK73  DDR4_SA_DQ5  SOCKET4677_AZIFS054P001C01  I169

M_E_CPU0_SA_DQ<6>   @S9S_MB_2U_LIB.S9S_MB_2U(SCH_1):M_E_CPU0_SA_DQ<6>
  J9     159  DQ_A6  SCONN288_ADR50001P013C01  I12
  J10    159  DQ_A6  SCONN288_ADR50001P003C01  I13
  U2     EP73  DDR4_SA_DQ6  SOCKET4677_AZIFS054P001C01  I169

M_E_CPU0_SA_DQ<7>   @S9S_MB_2U_LIB.S9S_MB_2U(SCH_1):M_E_CPU0_SA_DQ<7>
  J9     161  DQ_A7  SCONN288_ADR50001P013C01  I12
  J10    161  DQ_A7  SCONN288_ADR50001P003C01  I13
  U2     ER72  DDR4_SA_DQ7  SOCKET4677_AZIFS054P001C01  I169

M_E_CPU0_SA_DQ<8>   @S9S_MB_2U_LIB.S9S_MB_2U(SCH_1):M_E_CPU0_SA_DQ<8>
  J9      18  DQ_A8  SCONN288_ADR50001P013C01  I12
  J10     18  DQ_A8  SCONN288_ADR50001P003C01  I13
  U2     EE72  DDR4_SA_DQ8  SOCKET4677_AZIFS054P001C01  I169

M_E_CPU0_SA_DQ<9>   @S9S_MB_2U_LIB.S9S_MB_2U(SCH_1):M_E_CPU0_SA_DQ<9>
  J9      20  DQ_A9  SCONN288_ADR50001P013C01  I12
  J10     20  DQ_A9  SCONN288_ADR50001P003C01  I13
  U2     ED71  DDR4_SA_DQ9  SOCKET4677_AZIFS054P001C01  I169

M_E_CPU0_SA_DQ<10>   @S9S_MB_2U_LIB.S9S_MB_2U(SCH_1):M_E_CPU0_SA_DQ<10>
  J9     163  DQ_A10  SCONN288_ADR50001P013C01  I12
  J10    163  DQ_A10  SCONN288_ADR50001P003C01  I13
  U2     EG72  DDR4_SA_DQ10  SOCKET4677_AZIFS054P001C01  I169

M_E_CPU0_SA_DQ<11>   @S9S_MB_2U_LIB.S9S_MB_2U(SCH_1):M_E_CPU0_SA_DQ<11>
  J9     165  DQ_A11  SCONN288_ADR50001P013C01  I12
  J10    165  DQ_A11  SCONN288_ADR50001P003C01  I13
  U2     EH71  DDR4_SA_DQ11  SOCKET4677_AZIFS054P001C01  I169

M_E_CPU0_SA_DQ<12>   @S9S_MB_2U_LIB.S9S_MB_2U(SCH_1):M_E_CPU0_SA_DQ<12>
  J9      25  DQ_A12  SCONN288_ADR50001P013C01  I12
  J10     25  DQ_A12  SCONN288_ADR50001P003C01  I13
  U2     ED69  DDR4_SA_DQ12  SOCKET4677_AZIFS054P001C01  I169

M_E_CPU0_SA_DQ<13>   @S9S_MB_2U_LIB.S9S_MB_2U(SCH_1):M_E_CPU0_SA_DQ<13>
  J9      27  DQ_A13  SCONN288_ADR50001P013C01  I12
  J10     27  DQ_A13  SCONN288_ADR50001P003C01  I13
  U2     EE68  DDR4_SA_DQ13  SOCKET4677_AZIFS054P001C01  I169

M_E_CPU0_SA_DQ<14>   @S9S_MB_2U_LIB.S9S_MB_2U(SCH_1):M_E_CPU0_SA_DQ<14>
  J9     170  DQ_A14  SCONN288_ADR50001P013C01  I12
  J10    170  DQ_A14  SCONN288_ADR50001P003C01  I13
  U2     EH69  DDR4_SA_DQ14  SOCKET4677_AZIFS054P001C01  I169

M_E_CPU0_SA_DQ<15>   @S9S_MB_2U_LIB.S9S_MB_2U(SCH_1):M_E_CPU0_SA_DQ<15>
  J9     172  DQ_A15  SCONN288_ADR50001P013C01  I12
  J10    172  DQ_A15  SCONN288_ADR50001P003C01  I13
  U2     EG68  DDR4_SA_DQ15  SOCKET4677_AZIFS054P001C01  I169

M_E_CPU0_SA_DQ<16>   @S9S_MB_2U_LIB.S9S_MB_2U(SCH_1):M_E_CPU0_SA_DQ<16>
  J9      29  DQ_A16  SCONN288_ADR50001P013C01  I12
  J10     29  DQ_A16  SCONN288_ADR50001P003C01  I13
  U2     EM71  DDR4_SA_DQ16  SOCKET4677_AZIFS054P001C01  I169

M_E_CPU0_SA_DQ<17>   @S9S_MB_2U_LIB.S9S_MB_2U(SCH_1):M_E_CPU0_SA_DQ<17>
  J9      31  DQ_A17  SCONN288_ADR50001P013C01  I12
  J10     31  DQ_A17  SCONN288_ADR50001P003C01  I13
  U2     EM69  DDR4_SA_DQ17  SOCKET4677_AZIFS054P001C01  I169

M_E_CPU0_SA_DQ<18>   @S9S_MB_2U_LIB.S9S_MB_2U(SCH_1):M_E_CPU0_SA_DQ<18>
  J9     174  DQ_A18  SCONN288_ADR50001P013C01  I12
  J10    174  DQ_A18  SCONN288_ADR50001P003C01  I13
  U2     EN70  DDR4_SA_DQ18  SOCKET4677_AZIFS054P001C01  I169

M_E_CPU0_SA_DQ<19>   @S9S_MB_2U_LIB.S9S_MB_2U(SCH_1):M_E_CPU0_SA_DQ<19>
  J9     176  DQ_A19  SCONN288_ADR50001P013C01  I12
  J10    176  DQ_A19  SCONN288_ADR50001P003C01  I13
  U2     ER68  DDR4_SA_DQ19  SOCKET4677_AZIFS054P001C01  I169

M_E_CPU0_SA_DQ<20>   @S9S_MB_2U_LIB.S9S_MB_2U(SCH_1):M_E_CPU0_SA_DQ<20>
  J9      36  DQ_A20  SCONN288_ADR50001P013C01  I12
  J10     36  DQ_A20  SCONN288_ADR50001P003C01  I13
  U2     ER66  DDR4_SA_DQ20  SOCKET4677_AZIFS054P001C01  I169

M_E_CPU0_SA_DQ<21>   @S9S_MB_2U_LIB.S9S_MB_2U(SCH_1):M_E_CPU0_SA_DQ<21>
  J9      38  DQ_A21  SCONN288_ADR50001P013C01  I12
  J10     38  DQ_A21  SCONN288_ADR50001P003C01  I13
  U2     EM65  DDR4_SA_DQ21  SOCKET4677_AZIFS054P001C01  I169

M_E_CPU0_SA_DQ<22>   @S9S_MB_2U_LIB.S9S_MB_2U(SCH_1):M_E_CPU0_SA_DQ<22>
  J9     181  DQ_A22  SCONN288_ADR50001P013C01  I12
  J10    181  DQ_A22  SCONN288_ADR50001P003C01  I13
  U2     EL66  DDR4_SA_DQ22  SOCKET4677_AZIFS054P001C01  I169

M_E_CPU0_SA_DQ<23>   @S9S_MB_2U_LIB.S9S_MB_2U(SCH_1):M_E_CPU0_SA_DQ<23>
  J9     183  DQ_A23  SCONN288_ADR50001P013C01  I12
  J10    183  DQ_A23  SCONN288_ADR50001P003C01  I13
  U2     EP65  DDR4_SA_DQ23  SOCKET4677_AZIFS054P001C01  I169

M_E_CPU0_SA_DQ<24>   @S9S_MB_2U_LIB.S9S_MB_2U(SCH_1):M_E_CPU0_SA_DQ<24>
  J9      40  DQ_A24  SCONN288_ADR50001P013C01  I12
  J10     40  DQ_A24  SCONN288_ADR50001P003C01  I13
  U2     EM63  DDR4_SA_DQ24  SOCKET4677_AZIFS054P001C01  I169

M_E_CPU0_SA_DQ<25>   @S9S_MB_2U_LIB.S9S_MB_2U(SCH_1):M_E_CPU0_SA_DQ<25>
  J9      42  DQ_A25  SCONN288_ADR50001P013C01  I12
  J10     42  DQ_A25  SCONN288_ADR50001P003C01  I13
  U2     EL62  DDR4_SA_DQ25  SOCKET4677_AZIFS054P001C01  I169

M_E_CPU0_SA_DQ<26>   @S9S_MB_2U_LIB.S9S_MB_2U(SCH_1):M_E_CPU0_SA_DQ<26>
  J9     185  DQ_A26  SCONN288_ADR50001P013C01  I12
  J10    185  DQ_A26  SCONN288_ADR50001P003C01  I13
  U2     EP63  DDR4_SA_DQ26  SOCKET4677_AZIFS054P001C01  I169

M_E_CPU0_SA_DQ<27>   @S9S_MB_2U_LIB.S9S_MB_2U(SCH_1):M_E_CPU0_SA_DQ<27>
  J9     187  DQ_A27  SCONN288_ADR50001P013C01  I12
  J10    187  DQ_A27  SCONN288_ADR50001P003C01  I13
  U2     ER62  DDR4_SA_DQ27  SOCKET4677_AZIFS054P001C01  I169

M_E_CPU0_SA_DQ<28>   @S9S_MB_2U_LIB.S9S_MB_2U(SCH_1):M_E_CPU0_SA_DQ<28>
  J9      47  DQ_A28  SCONN288_ADR50001P013C01  I12
  J10     47  DQ_A28  SCONN288_ADR50001P003C01  I13
  U2     EL60  DDR4_SA_DQ28  SOCKET4677_AZIFS054P001C01  I169

M_E_CPU0_SA_DQ<29>   @S9S_MB_2U_LIB.S9S_MB_2U(SCH_1):M_E_CPU0_SA_DQ<29>
  J9      49  DQ_A29  SCONN288_ADR50001P013C01  I12
  J10     49  DQ_A29  SCONN288_ADR50001P003C01  I13
  U2     EM59  DDR4_SA_DQ29  SOCKET4677_AZIFS054P001C01  I169

M_E_CPU0_SA_DQ<30>   @S9S_MB_2U_LIB.S9S_MB_2U(SCH_1):M_E_CPU0_SA_DQ<30>
  J9     192  DQ_A30  SCONN288_ADR50001P013C01  I12
  J10    192  DQ_A30  SCONN288_ADR50001P003C01  I13
  U2     ER60  DDR4_SA_DQ30  SOCKET4677_AZIFS054P001C01  I169

M_E_CPU0_SA_DQ<31>   @S9S_MB_2U_LIB.S9S_MB_2U(SCH_1):M_E_CPU0_SA_DQ<31>
  J9     194  DQ_A31  SCONN288_ADR50001P013C01  I12
  J10    194  DQ_A31  SCONN288_ADR50001P003C01  I13
  U2     EP59  DDR4_SA_DQ31  SOCKET4677_AZIFS054P001C01  I169

M_E_CPU0_SA_DQS_DN<0>   @S9S_MB_2U_LIB.S9S_MB_2U(SCH_1):M_E_CPU0_SA_DQS_DN<0>
  J9      12  DQS0_A_N  SCONN288_ADR50001P013C01  I126
  J10     12  DQS0_A_N  SCONN288_ADR50001P003C01  I127
  U2     EP75  DDR4_SA_DQS_DN0  SOCKET4677_AZIFS054P001C01  I169

M_E_CPU0_SA_DQS_DN<1>   @S9S_MB_2U_LIB.S9S_MB_2U(SCH_1):M_E_CPU0_SA_DQS_DN<1>
  J9      23  DQS1_A_N  SCONN288_ADR50001P013C01  I126
  J10     23  DQS1_A_N  SCONN288_ADR50001P003C01  I127
  U2     EC70  DDR4_SA_DQS_DN1  SOCKET4677_AZIFS054P001C01  I169

M_E_CPU0_SA_DQS_DN<2>   @S9S_MB_2U_LIB.S9S_MB_2U(SCH_1):M_E_CPU0_SA_DQS_DN<2>
  J9      34  DQS2_A_N  SCONN288_ADR50001P013C01  I126
  J10     34  DQS2_A_N  SCONN288_ADR50001P003C01  I127
  U2     EK67  DDR4_SA_DQS_DN2  SOCKET4677_AZIFS054P001C01  I169

M_E_CPU0_SA_DQS_DN<3>   @S9S_MB_2U_LIB.S9S_MB_2U(SCH_1):M_E_CPU0_SA_DQS_DN<3>
  J9      45  DQS3_A_N  SCONN288_ADR50001P013C01  I126
  J10     45  DQS3_A_N  SCONN288_ADR50001P003C01  I127
  U2     EK61  DDR4_SA_DQS_DN3  SOCKET4677_AZIFS054P001C01  I169

M_E_CPU0_SA_DQS_DN<4>   @S9S_MB_2U_LIB.S9S_MB_2U(SCH_1):M_E_CPU0_SA_DQS_DN<4>
  J9      56  DQS4_A_N  SCONN288_ADR50001P013C01  I126
  J10     56  DQS4_A_N  SCONN288_ADR50001P003C01  I127
  U2     EM55  DDR4_SA_DQS_DN4  SOCKET4677_AZIFS054P001C01  I169

M_E_CPU0_SA_DQS_DN<5>   @S9S_MB_2U_LIB.S9S_MB_2U(SCH_1):M_E_CPU0_SA_DQS_DN<5>
  J9     156  DQS5_A_N  SCONN288_ADR50001P013C01  I126
  J10    156  DQS5_A_N  SCONN288_ADR50001P003C01  I127
  U2     EM75  DDR4_SA_DQS_DN5  SOCKET4677_AZIFS054P001C01  I169

M_E_CPU0_SA_DQS_DN<6>   @S9S_MB_2U_LIB.S9S_MB_2U(SCH_1):M_E_CPU0_SA_DQS_DN<6>
  J9     167  DQS6_A_N  SCONN288_ADR50001P013C01  I126
  J10    167  DQS6_A_N  SCONN288_ADR50001P003C01  I127
  U2     EJ70  DDR4_SA_DQS_DN6  SOCKET4677_AZIFS054P001C01  I169

M_E_CPU0_SA_DQS_DN<7>   @S9S_MB_2U_LIB.S9S_MB_2U(SCH_1):M_E_CPU0_SA_DQS_DN<7>
  J9     178  DQS7_A_N  SCONN288_ADR50001P013C01  I126
  J10    178  DQS7_A_N  SCONN288_ADR50001P003C01  I127
  U2     EN68  DDR4_SA_DQS_DN7  SOCKET4677_AZIFS054P001C01  I169

M_E_CPU0_SA_DQS_DN<8>   @S9S_MB_2U_LIB.S9S_MB_2U(SCH_1):M_E_CPU0_SA_DQS_DN<8>
  J9     189  DQS8_A_N  SCONN288_ADR50001P013C01  I126
  J10    189  DQS8_A_N  SCONN288_ADR50001P003C01  I127
  U2     ET61  DDR4_SA_DQS_DN8  SOCKET4677_AZIFS054P001C01  I169

M_E_CPU0_SA_DQS_DN<9>   @S9S_MB_2U_LIB.S9S_MB_2U(SCH_1):M_E_CPU0_SA_DQS_DN<9>
  J9     200  DQS9_A_N  SCONN288_ADR50001P013C01  I126
  J10    200  DQS9_A_N  SCONN288_ADR50001P003C01  I127
  U2     ET55  DDR4_SA_DQS_DN9  SOCKET4677_AZIFS054P001C01  I169

M_E_CPU0_SA_DQS_DP<0>   @S9S_MB_2U_LIB.S9S_MB_2U(SCH_1):M_E_CPU0_SA_DQS_DP<0>
  J9      11  DQS0_A_P  SCONN288_ADR50001P013C01  I126
  J10     11  DQS0_A_P  SCONN288_ADR50001P003C01  I127
  U2     EN76  DDR4_SA_DQS_DP0  SOCKET4677_AZIFS054P001C01  I169

M_E_CPU0_SA_DQS_DP<1>   @S9S_MB_2U_LIB.S9S_MB_2U(SCH_1):M_E_CPU0_SA_DQS_DP<1>
  J9      22  DQS1_A_P  SCONN288_ADR50001P013C01  I126
  J10     22  DQS1_A_P  SCONN288_ADR50001P003C01  I127
  U2     EE70  DDR4_SA_DQS_DP1  SOCKET4677_AZIFS054P001C01  I169

M_E_CPU0_SA_DQS_DP<2>   @S9S_MB_2U_LIB.S9S_MB_2U(SCH_1):M_E_CPU0_SA_DQS_DP<2>
  J9      33  DQS2_A_P  SCONN288_ADR50001P013C01  I126
  J10     33  DQS2_A_P  SCONN288_ADR50001P003C01  I127
  U2     EL68  DDR4_SA_DQS_DP2  SOCKET4677_AZIFS054P001C01  I169

M_E_CPU0_SA_DQS_DP<3>   @S9S_MB_2U_LIB.S9S_MB_2U(SCH_1):M_E_CPU0_SA_DQS_DP<3>
  J9      44  DQS3_A_P  SCONN288_ADR50001P013C01  I126
  J10     44  DQS3_A_P  SCONN288_ADR50001P003C01  I127
  U2     EM61  DDR4_SA_DQS_DP3  SOCKET4677_AZIFS054P001C01  I169

M_E_CPU0_SA_DQS_DP<4>   @S9S_MB_2U_LIB.S9S_MB_2U(SCH_1):M_E_CPU0_SA_DQS_DP<4>
  J9      55  DQS4_A_P  SCONN288_ADR50001P013C01  I126
  J10     55  DQS4_A_P  SCONN288_ADR50001P003C01  I127
  U2     EK55  DDR4_SA_DQS_DP4  SOCKET4677_AZIFS054P001C01  I169

M_E_CPU0_SA_DQS_DP<5>   @S9S_MB_2U_LIB.S9S_MB_2U(SCH_1):M_E_CPU0_SA_DQS_DP<5>
  J9     157  DQS5_A_P  SCONN288_ADR50001P013C01  I126
  J10    157  DQS5_A_P  SCONN288_ADR50001P003C01  I127
  U2     EN74  DDR4_SA_DQS_DP5  SOCKET4677_AZIFS054P001C01  I169

M_E_CPU0_SA_DQS_DP<6>   @S9S_MB_2U_LIB.S9S_MB_2U(SCH_1):M_E_CPU0_SA_DQS_DP<6>
  J9     168  DQS6_A_P  SCONN288_ADR50001P013C01  I126
  J10    168  DQS6_A_P  SCONN288_ADR50001P003C01  I127
  U2     EG70  DDR4_SA_DQS_DP6  SOCKET4677_AZIFS054P001C01  I169

M_E_CPU0_SA_DQS_DP<7>   @S9S_MB_2U_LIB.S9S_MB_2U(SCH_1):M_E_CPU0_SA_DQS_DP<7>
  J9     179  DQS7_A_P  SCONN288_ADR50001P013C01  I126
  J10    179  DQS7_A_P  SCONN288_ADR50001P003C01  I127
  U2     EM67  DDR4_SA_DQS_DP7  SOCKET4677_AZIFS054P001C01  I169

M_E_CPU0_SA_DQS_DP<8>   @S9S_MB_2U_LIB.S9S_MB_2U(SCH_1):M_E_CPU0_SA_DQS_DP<8>
  J9     190  DQS8_A_P  SCONN288_ADR50001P013C01  I126
  J10    190  DQS8_A_P  SCONN288_ADR50001P003C01  I127
  U2     EP61  DDR4_SA_DQS_DP8  SOCKET4677_AZIFS054P001C01  I169

M_E_CPU0_SA_DQS_DP<9>   @S9S_MB_2U_LIB.S9S_MB_2U(SCH_1):M_E_CPU0_SA_DQS_DP<9>
  J9     201  DQS9_A_P  SCONN288_ADR50001P013C01  I126
  J10    201  DQS9_A_P  SCONN288_ADR50001P003C01  I127
  U2     EP55  DDR4_SA_DQS_DP9  SOCKET4677_AZIFS054P001C01  I169

M_E_CPU0_SA_PAR   @S9S_MB_2U_LIB.S9S_MB_2U(SCH_1):M_E_CPU0_SA_PAR
  J9      74  PAR_A  SCONN288_ADR50001P013C01  I12
  J10     74  PAR_A  SCONN288_ADR50001P003C01  I13
  U2     EE43  DDR4_SA_PAR  SOCKET4677_AZIFS054P001C01  I169

M_E_CPU0_SA_RSP<0>   @S9S_MB_2U_LIB.S9S_MB_2U(SCH_1):M_E_CPU0_SA_RSP<0>
  J9      86  LBD||RSP_N_A  SCONN288_ADR50001P013C01  I12
  U2     DD44  DDR4_A_RSP0  SOCKET4677_AZIFS054P001C01  I169

M_E_CPU0_SA_RSP<1>   @S9S_MB_2U_LIB.S9S_MB_2U(SCH_1):M_E_CPU0_SA_RSP<1>
  J10     86  LBD||RSP_N_A  SCONN288_ADR50001P003C01  I13
  U2     DC43  DDR4_A_RSP1  SOCKET4677_AZIFS054P001C01  I169

M_E_CPU0_SB_CA<0>   @S9S_MB_2U_LIB.S9S_MB_2U(SCH_1):M_E_CPU0_SB_CA<0>
  J9      76  CA0_B  SCONN288_ADR50001P013C01  I12
  J10     76  CA0_B  SCONN288_ADR50001P003C01  I13
  U2     EG43  DDR4_SB_CA0  SOCKET4677_AZIFS054P001C01  I169

M_E_CPU0_SB_CA<1>   @S9S_MB_2U_LIB.S9S_MB_2U(SCH_1):M_E_CPU0_SB_CA<1>
  J9     221  CA1_B  SCONN288_ADR50001P013C01  I12
  J10    221  CA1_B  SCONN288_ADR50001P003C01  I13
  U2     EH44  DDR4_SB_CA1  SOCKET4677_AZIFS054P001C01  I169

M_E_CPU0_SB_CA<2>   @S9S_MB_2U_LIB.S9S_MB_2U(SCH_1):M_E_CPU0_SB_CA<2>
  J9      78  CA2_B  SCONN288_ADR50001P013C01  I12
  J10     78  CA2_B  SCONN288_ADR50001P003C01  I13
  U2     EM44  DDR4_SB_CA2  SOCKET4677_AZIFS054P001C01  I169

M_E_CPU0_SB_CA<3>   @S9S_MB_2U_LIB.S9S_MB_2U(SCH_1):M_E_CPU0_SB_CA<3>
  J9     223  CA3_B  SCONN288_ADR50001P013C01  I12
  J10    223  CA3_B  SCONN288_ADR50001P003C01  I13
  U2     EP44  DDR4_SB_CA3  SOCKET4677_AZIFS054P001C01  I169

M_E_CPU0_SB_CA<4>   @S9S_MB_2U_LIB.S9S_MB_2U(SCH_1):M_E_CPU0_SB_CA<4>
  J9      80  CA4_B  SCONN288_ADR50001P013C01  I12
  J10     80  CA4_B  SCONN288_ADR50001P003C01  I13
  U2     EL43  DDR4_SB_CA4  SOCKET4677_AZIFS054P001C01  I169

M_E_CPU0_SB_CA<5>   @S9S_MB_2U_LIB.S9S_MB_2U(SCH_1):M_E_CPU0_SB_CA<5>
  J9     225  CA5_B  SCONN288_ADR50001P013C01  I12
  J10    225  CA5_B  SCONN288_ADR50001P003C01  I13
  U2     ET42  DDR4_SB_CA5  SOCKET4677_AZIFS054P001C01  I169

M_E_CPU0_SB_CA<6>   @S9S_MB_2U_LIB.S9S_MB_2U(SCH_1):M_E_CPU0_SB_CA<6>
  J9      82  CA6_B  SCONN288_ADR50001P013C01  I12
  J10     82  CA6_B  SCONN288_ADR50001P003C01  I13
  U2     EK42  DDR4_SB_CA6  SOCKET4677_AZIFS054P001C01  I169

M_E_CPU0_SB_CB<0>   @S9S_MB_2U_LIB.S9S_MB_2U(SCH_1):M_E_CPU0_SB_CB<0>
  J9      96  CB_B0  SCONN288_ADR50001P013C01  I12
  J10     96  CB_B0  SCONN288_ADR50001P003C01  I13
  U2     EL35  DDR4_SB_ECC0  SOCKET4677_AZIFS054P001C01  I169

M_E_CPU0_SB_CB<1>   @S9S_MB_2U_LIB.S9S_MB_2U(SCH_1):M_E_CPU0_SB_CB<1>
  J9      98  CB_B1  SCONN288_ADR50001P013C01  I12
  J10     98  CB_B1  SCONN288_ADR50001P003C01  I13
  U2     EM34  DDR4_SB_ECC1  SOCKET4677_AZIFS054P001C01  I169

M_E_CPU0_SB_CB<2>   @S9S_MB_2U_LIB.S9S_MB_2U(SCH_1):M_E_CPU0_SB_CB<2>
  J9     241  CB_B2  SCONN288_ADR50001P013C01  I12
  J10    241  CB_B2  SCONN288_ADR50001P003C01  I13
  U2     ER35  DDR4_SB_ECC2  SOCKET4677_AZIFS054P001C01  I169

M_E_CPU0_SB_CB<3>   @S9S_MB_2U_LIB.S9S_MB_2U(SCH_1):M_E_CPU0_SB_CB<3>
  J9     243  CB_B3  SCONN288_ADR50001P013C01  I12
  J10    243  CB_B3  SCONN288_ADR50001P003C01  I13
  U2     EP34  DDR4_SB_ECC3  SOCKET4677_AZIFS054P001C01  I169

M_E_CPU0_SB_CB<4>   @S9S_MB_2U_LIB.S9S_MB_2U(SCH_1):M_E_CPU0_SB_CB<4>
  J9      89  CB_B4  SCONN288_ADR50001P013C01  I12
  J10     89  CB_B4  SCONN288_ADR50001P003C01  I13
  U2     EM38  DDR4_SB_ECC4  SOCKET4677_AZIFS054P001C01  I169

M_E_CPU0_SB_CB<5>   @S9S_MB_2U_LIB.S9S_MB_2U(SCH_1):M_E_CPU0_SB_CB<5>
  J9      91  CB_B5  SCONN288_ADR50001P013C01  I12
  J10     91  CB_B5  SCONN288_ADR50001P003C01  I13
  U2     EL37  DDR4_SB_ECC5  SOCKET4677_AZIFS054P001C01  I169

M_E_CPU0_SB_CB<6>   @S9S_MB_2U_LIB.S9S_MB_2U(SCH_1):M_E_CPU0_SB_CB<6>
  J9     234  CB_B6  SCONN288_ADR50001P013C01  I12
  J10    234  CB_B6  SCONN288_ADR50001P003C01  I13
  U2     EP38  DDR4_SB_ECC6  SOCKET4677_AZIFS054P001C01  I169

M_E_CPU0_SB_CB<7>   @S9S_MB_2U_LIB.S9S_MB_2U(SCH_1):M_E_CPU0_SB_CB<7>
  J9     236  CB_B7  SCONN288_ADR50001P013C01  I12
  J10    236  CB_B7  SCONN288_ADR50001P003C01  I13
  U2     ER37  DDR4_SB_ECC7  SOCKET4677_AZIFS054P001C01  I169

M_E_CPU0_SB_CS_N<0>   @S9S_MB_2U_LIB.S9S_MB_2U(SCH_1):M_E_CPU0_SB_CS_N<0>
  J9      84  CS0_N_B  SCONN288_ADR50001P013C01  I12
  U2     EP40  DDR4_SB_CS0_N  SOCKET4677_AZIFS054P001C01  I169

M_E_CPU0_SB_CS_N<1>   @S9S_MB_2U_LIB.S9S_MB_2U(SCH_1):M_E_CPU0_SB_CS_N<1>
  J9     229  CS1_N_B  SCONN288_ADR50001P013C01  I12
  U2     ET40  DDR4_SB_CS1_N  SOCKET4677_AZIFS054P001C01  I169

M_E_CPU0_SB_CS_N<2>   @S9S_MB_2U_LIB.S9S_MB_2U(SCH_1):M_E_CPU0_SB_CS_N<2>
  J10     84  CS0_N_B  SCONN288_ADR50001P003C01  I13
  U2     EM40  DDR4_SB_CS2_N  SOCKET4677_AZIFS054P001C01  I169

M_E_CPU0_SB_CS_N<3>   @S9S_MB_2U_LIB.S9S_MB_2U(SCH_1):M_E_CPU0_SB_CS_N<3>
  J10    229  CS1_N_B  SCONN288_ADR50001P003C01  I13
  U2     EL41  DDR4_SB_CS3_N  SOCKET4677_AZIFS054P001C01  I169

M_E_CPU0_SB_DQ<0>   @S9S_MB_2U_LIB.S9S_MB_2U(SCH_1):M_E_CPU0_SB_DQ<0>
  J9     100  DQ_B0  SCONN288_ADR50001P013C01  I12
  J10    100  DQ_B0  SCONN288_ADR50001P003C01  I13
  U2     EE29  DDR4_SB_DQ0  SOCKET4677_AZIFS054P001C01  I169

M_E_CPU0_SB_DQ<1>   @S9S_MB_2U_LIB.S9S_MB_2U(SCH_1):M_E_CPU0_SB_DQ<1>
  J9     102  DQ_B1  SCONN288_ADR50001P013C01  I12
  J10    102  DQ_B1  SCONN288_ADR50001P003C01  I13
  U2     ED28  DDR4_SB_DQ1  SOCKET4677_AZIFS054P001C01  I169

M_E_CPU0_SB_DQ<2>   @S9S_MB_2U_LIB.S9S_MB_2U(SCH_1):M_E_CPU0_SB_DQ<2>
  J9     245  DQ_B2  SCONN288_ADR50001P013C01  I12
  J10    245  DQ_B2  SCONN288_ADR50001P003C01  I13
  U2     EG29  DDR4_SB_DQ2  SOCKET4677_AZIFS054P001C01  I169

M_E_CPU0_SB_DQ<3>   @S9S_MB_2U_LIB.S9S_MB_2U(SCH_1):M_E_CPU0_SB_DQ<3>
  J9     247  DQ_B3  SCONN288_ADR50001P013C01  I12
  J10    247  DQ_B3  SCONN288_ADR50001P003C01  I13
  U2     EH28  DDR4_SB_DQ3  SOCKET4677_AZIFS054P001C01  I169

M_E_CPU0_SB_DQ<4>   @S9S_MB_2U_LIB.S9S_MB_2U(SCH_1):M_E_CPU0_SB_DQ<4>
  J9     107  DQ_B4  SCONN288_ADR50001P013C01  I12
  J10    107  DQ_B4  SCONN288_ADR50001P003C01  I13
  U2     ED26  DDR4_SB_DQ4  SOCKET4677_AZIFS054P001C01  I169

M_E_CPU0_SB_DQ<5>   @S9S_MB_2U_LIB.S9S_MB_2U(SCH_1):M_E_CPU0_SB_DQ<5>
  J9     109  DQ_B5  SCONN288_ADR50001P013C01  I12
  J10    109  DQ_B5  SCONN288_ADR50001P003C01  I13
  U2     EE25  DDR4_SB_DQ5  SOCKET4677_AZIFS054P001C01  I169

M_E_CPU0_SB_DQ<6>   @S9S_MB_2U_LIB.S9S_MB_2U(SCH_1):M_E_CPU0_SB_DQ<6>
  J9     252  DQ_B6  SCONN288_ADR50001P013C01  I12
  J10    252  DQ_B6  SCONN288_ADR50001P003C01  I13
  U2     EH26  DDR4_SB_DQ6  SOCKET4677_AZIFS054P001C01  I169

M_E_CPU0_SB_DQ<7>   @S9S_MB_2U_LIB.S9S_MB_2U(SCH_1):M_E_CPU0_SB_DQ<7>
  J9     254  DQ_B7  SCONN288_ADR50001P013C01  I12
  J10    254  DQ_B7  SCONN288_ADR50001P003C01  I13
  U2     EG25  DDR4_SB_DQ7  SOCKET4677_AZIFS054P001C01  I169

M_E_CPU0_SB_DQ<8>   @S9S_MB_2U_LIB.S9S_MB_2U(SCH_1):M_E_CPU0_SB_DQ<8>
  J9     111  DQ_B8  SCONN288_ADR50001P013C01  I12
  J10    111  DQ_B8  SCONN288_ADR50001P003C01  I13
  U2     EM32  DDR4_SB_DQ8  SOCKET4677_AZIFS054P001C01  I169

M_E_CPU0_SB_DQ<9>   @S9S_MB_2U_LIB.S9S_MB_2U(SCH_1):M_E_CPU0_SB_DQ<9>
  J9     113  DQ_B9  SCONN288_ADR50001P013C01  I12
  J10    113  DQ_B9  SCONN288_ADR50001P003C01  I13
  U2     EL31  DDR4_SB_DQ9  SOCKET4677_AZIFS054P001C01  I169

M_E_CPU0_SB_DQ<10>   @S9S_MB_2U_LIB.S9S_MB_2U(SCH_1):M_E_CPU0_SB_DQ<10>
  J9     256  DQ_B10  SCONN288_ADR50001P013C01  I12
  J10    256  DQ_B10  SCONN288_ADR50001P003C01  I13
  U2     EP32  DDR4_SB_DQ10  SOCKET4677_AZIFS054P001C01  I169

M_E_CPU0_SB_DQ<11>   @S9S_MB_2U_LIB.S9S_MB_2U(SCH_1):M_E_CPU0_SB_DQ<11>
  J9     258  DQ_B11  SCONN288_ADR50001P013C01  I12
  J10    258  DQ_B11  SCONN288_ADR50001P003C01  I13
  U2     ER31  DDR4_SB_DQ11  SOCKET4677_AZIFS054P001C01  I169

M_E_CPU0_SB_DQ<12>   @S9S_MB_2U_LIB.S9S_MB_2U(SCH_1):M_E_CPU0_SB_DQ<12>
  J9     118  DQ_B12  SCONN288_ADR50001P013C01  I12
  J10    118  DQ_B12  SCONN288_ADR50001P003C01  I13
  U2     EL29  DDR4_SB_DQ12  SOCKET4677_AZIFS054P001C01  I169

M_E_CPU0_SB_DQ<13>   @S9S_MB_2U_LIB.S9S_MB_2U(SCH_1):M_E_CPU0_SB_DQ<13>
  J9     120  DQ_B13  SCONN288_ADR50001P013C01  I12
  J10    120  DQ_B13  SCONN288_ADR50001P003C01  I13
  U2     EM28  DDR4_SB_DQ13  SOCKET4677_AZIFS054P001C01  I169

M_E_CPU0_SB_DQ<14>   @S9S_MB_2U_LIB.S9S_MB_2U(SCH_1):M_E_CPU0_SB_DQ<14>
  J9     263  DQ_B14  SCONN288_ADR50001P013C01  I12
  J10    263  DQ_B14  SCONN288_ADR50001P003C01  I13
  U2     ER29  DDR4_SB_DQ14  SOCKET4677_AZIFS054P001C01  I169

M_E_CPU0_SB_DQ<15>   @S9S_MB_2U_LIB.S9S_MB_2U(SCH_1):M_E_CPU0_SB_DQ<15>
  J9     265  DQ_B15  SCONN288_ADR50001P013C01  I12
  J10    265  DQ_B15  SCONN288_ADR50001P003C01  I13
  U2     EP28  DDR4_SB_DQ15  SOCKET4677_AZIFS054P001C01  I169

M_E_CPU0_SB_DQ<16>   @S9S_MB_2U_LIB.S9S_MB_2U(SCH_1):M_E_CPU0_SB_DQ<16>
  J9     122  DQ_B16  SCONN288_ADR50001P013C01  I12
  J10    122  DQ_B16  SCONN288_ADR50001P003C01  I13
  U2     EM26  DDR4_SB_DQ16  SOCKET4677_AZIFS054P001C01  I169

M_E_CPU0_SB_DQ<17>   @S9S_MB_2U_LIB.S9S_MB_2U(SCH_1):M_E_CPU0_SB_DQ<17>
  J9     124  DQ_B17  SCONN288_ADR50001P013C01  I12
  J10    124  DQ_B17  SCONN288_ADR50001P003C01  I13
  U2     EL25  DDR4_SB_DQ17  SOCKET4677_AZIFS054P001C01  I169

M_E_CPU0_SB_DQ<18>   @S9S_MB_2U_LIB.S9S_MB_2U(SCH_1):M_E_CPU0_SB_DQ<18>
  J9     267  DQ_B18  SCONN288_ADR50001P013C01  I12
  J10    267  DQ_B18  SCONN288_ADR50001P003C01  I13
  U2     EP26  DDR4_SB_DQ18  SOCKET4677_AZIFS054P001C01  I169

M_E_CPU0_SB_DQ<19>   @S9S_MB_2U_LIB.S9S_MB_2U(SCH_1):M_E_CPU0_SB_DQ<19>
  J9     269  DQ_B19  SCONN288_ADR50001P013C01  I12
  J10    269  DQ_B19  SCONN288_ADR50001P003C01  I13
  U2     ER25  DDR4_SB_DQ19  SOCKET4677_AZIFS054P001C01  I169

M_E_CPU0_SB_DQ<20>   @S9S_MB_2U_LIB.S9S_MB_2U(SCH_1):M_E_CPU0_SB_DQ<20>
  J9     129  DQ_B20  SCONN288_ADR50001P013C01  I12
  J10    129  DQ_B20  SCONN288_ADR50001P003C01  I13
  U2     EL23  DDR4_SB_DQ20  SOCKET4677_AZIFS054P001C01  I169

M_E_CPU0_SB_DQ<21>   @S9S_MB_2U_LIB.S9S_MB_2U(SCH_1):M_E_CPU0_SB_DQ<21>
  J9     131  DQ_B21  SCONN288_ADR50001P013C01  I12
  J10    131  DQ_B21  SCONN288_ADR50001P003C01  I13
  U2     EM22  DDR4_SB_DQ21  SOCKET4677_AZIFS054P001C01  I169

M_E_CPU0_SB_DQ<22>   @S9S_MB_2U_LIB.S9S_MB_2U(SCH_1):M_E_CPU0_SB_DQ<22>
  J9     274  DQ_B22  SCONN288_ADR50001P013C01  I12
  J10    274  DQ_B22  SCONN288_ADR50001P003C01  I13
  U2     ER23  DDR4_SB_DQ22  SOCKET4677_AZIFS054P001C01  I169

M_E_CPU0_SB_DQ<23>   @S9S_MB_2U_LIB.S9S_MB_2U(SCH_1):M_E_CPU0_SB_DQ<23>
  J9     276  DQ_B23  SCONN288_ADR50001P013C01  I12
  J10    276  DQ_B23  SCONN288_ADR50001P003C01  I13
  U2     EP22  DDR4_SB_DQ23  SOCKET4677_AZIFS054P001C01  I169

M_E_CPU0_SB_DQ<24>   @S9S_MB_2U_LIB.S9S_MB_2U(SCH_1):M_E_CPU0_SB_DQ<24>
  J9     133  DQ_B24  SCONN288_ADR50001P013C01  I12
  J10    133  DQ_B24  SCONN288_ADR50001P003C01  I13
  U2     EM20  DDR4_SB_DQ24  SOCKET4677_AZIFS054P001C01  I169

M_E_CPU0_SB_DQ<25>   @S9S_MB_2U_LIB.S9S_MB_2U(SCH_1):M_E_CPU0_SB_DQ<25>
  J9     135  DQ_B25  SCONN288_ADR50001P013C01  I12
  J10    135  DQ_B25  SCONN288_ADR50001P003C01  I13
  U2     EL19  DDR4_SB_DQ25  SOCKET4677_AZIFS054P001C01  I169

M_E_CPU0_SB_DQ<26>   @S9S_MB_2U_LIB.S9S_MB_2U(SCH_1):M_E_CPU0_SB_DQ<26>
  J9     278  DQ_B26  SCONN288_ADR50001P013C01  I12
  J10    278  DQ_B26  SCONN288_ADR50001P003C01  I13
  U2     EP20  DDR4_SB_DQ26  SOCKET4677_AZIFS054P001C01  I169

M_E_CPU0_SB_DQ<27>   @S9S_MB_2U_LIB.S9S_MB_2U(SCH_1):M_E_CPU0_SB_DQ<27>
  J9     280  DQ_B27  SCONN288_ADR50001P013C01  I12
  J10    280  DQ_B27  SCONN288_ADR50001P003C01  I13
  U2     ER19  DDR4_SB_DQ27  SOCKET4677_AZIFS054P001C01  I169

M_E_CPU0_SB_DQ<28>   @S9S_MB_2U_LIB.S9S_MB_2U(SCH_1):M_E_CPU0_SB_DQ<28>
  J9     140  DQ_B28  SCONN288_ADR50001P013C01  I12
  J10    140  DQ_B28  SCONN288_ADR50001P003C01  I13
  U2     EL17  DDR4_SB_DQ28  SOCKET4677_AZIFS054P001C01  I169

M_E_CPU0_SB_DQ<29>   @S9S_MB_2U_LIB.S9S_MB_2U(SCH_1):M_E_CPU0_SB_DQ<29>
  J9     142  DQ_B29  SCONN288_ADR50001P013C01  I12
  J10    142  DQ_B29  SCONN288_ADR50001P003C01  I13
  U2     EM16  DDR4_SB_DQ29  SOCKET4677_AZIFS054P001C01  I169

M_E_CPU0_SB_DQ<30>   @S9S_MB_2U_LIB.S9S_MB_2U(SCH_1):M_E_CPU0_SB_DQ<30>
  J9     285  DQ_B30  SCONN288_ADR50001P013C01  I12
  J10    285  DQ_B30  SCONN288_ADR50001P003C01  I13
  U2     ER17  DDR4_SB_DQ30  SOCKET4677_AZIFS054P001C01  I169

M_E_CPU0_SB_DQ<31>   @S9S_MB_2U_LIB.S9S_MB_2U(SCH_1):M_E_CPU0_SB_DQ<31>
  J9     287  DQ_B31  SCONN288_ADR50001P013C01  I12
  J10    287  DQ_B31  SCONN288_ADR50001P003C01  I13
  U2     EP16  DDR4_SB_DQ31  SOCKET4677_AZIFS054P001C01  I169

M_E_CPU0_SB_DQS_DN<0>   @S9S_MB_2U_LIB.S9S_MB_2U(SCH_1):M_E_CPU0_SB_DQS_DN<0>
  J9     105  DQS0_B_N  SCONN288_ADR50001P013C01  I126
  J10    105  DQS0_B_N  SCONN288_ADR50001P003C01  I127
  U2     EE27  DDR4_SB_DQS_DN0  SOCKET4677_AZIFS054P001C01  I169

M_E_CPU0_SB_DQS_DN<1>   @S9S_MB_2U_LIB.S9S_MB_2U(SCH_1):M_E_CPU0_SB_DQS_DN<1>
  J9     116  DQS1_B_N  SCONN288_ADR50001P013C01  I126
  J10    116  DQS1_B_N  SCONN288_ADR50001P003C01  I127
  U2     EK30  DDR4_SB_DQS_DN1  SOCKET4677_AZIFS054P001C01  I169

M_E_CPU0_SB_DQS_DN<2>   @S9S_MB_2U_LIB.S9S_MB_2U(SCH_1):M_E_CPU0_SB_DQS_DN<2>
  J9     127  DQS2_B_N  SCONN288_ADR50001P013C01  I126
  J10    127  DQS2_B_N  SCONN288_ADR50001P003C01  I127
  U2     EK24  DDR4_SB_DQS_DN2  SOCKET4677_AZIFS054P001C01  I169

M_E_CPU0_SB_DQS_DN<3>   @S9S_MB_2U_LIB.S9S_MB_2U(SCH_1):M_E_CPU0_SB_DQS_DN<3>
  J9     138  DQS3_B_N  SCONN288_ADR50001P013C01  I126
  J10    138  DQS3_B_N  SCONN288_ADR50001P003C01  I127
  U2     EK18  DDR4_SB_DQS_DN3  SOCKET4677_AZIFS054P001C01  I169

M_E_CPU0_SB_DQS_DN<4>   @S9S_MB_2U_LIB.S9S_MB_2U(SCH_1):M_E_CPU0_SB_DQS_DN<4>
  J9     238  DQS4_B_N  SCONN288_ADR50001P013C01  I126
  J10    238  DQS4_B_N  SCONN288_ADR50001P003C01  I127
  U2     ET36  DDR4_SB_DQS_DN4  SOCKET4677_AZIFS054P001C01  I169

M_E_CPU0_SB_DQS_DN<5>   @S9S_MB_2U_LIB.S9S_MB_2U(SCH_1):M_E_CPU0_SB_DQS_DN<5>
  J9     249  DQS5_B_N  SCONN288_ADR50001P013C01  I126
  J10    249  DQS5_B_N  SCONN288_ADR50001P003C01  I127
  U2     EJ27  DDR4_SB_DQS_DN5  SOCKET4677_AZIFS054P001C01  I169

M_E_CPU0_SB_DQS_DN<6>   @S9S_MB_2U_LIB.S9S_MB_2U(SCH_1):M_E_CPU0_SB_DQS_DN<6>
  J9     260  DQS6_B_N  SCONN288_ADR50001P013C01  I126
  J10    260  DQS6_B_N  SCONN288_ADR50001P003C01  I127
  U2     ET30  DDR4_SB_DQS_DN6  SOCKET4677_AZIFS054P001C01  I169

M_E_CPU0_SB_DQS_DN<7>   @S9S_MB_2U_LIB.S9S_MB_2U(SCH_1):M_E_CPU0_SB_DQS_DN<7>
  J9     271  DQS7_B_N  SCONN288_ADR50001P013C01  I126
  J10    271  DQS7_B_N  SCONN288_ADR50001P003C01  I127
  U2     ET24  DDR4_SB_DQS_DN7  SOCKET4677_AZIFS054P001C01  I169

M_E_CPU0_SB_DQS_DN<8>   @S9S_MB_2U_LIB.S9S_MB_2U(SCH_1):M_E_CPU0_SB_DQS_DN<8>
  J9     282  DQS8_B_N  SCONN288_ADR50001P013C01  I126
  J10    282  DQS8_B_N  SCONN288_ADR50001P003C01  I127
  U2     ET18  DDR4_SB_DQS_DN8  SOCKET4677_AZIFS054P001C01  I169

M_E_CPU0_SB_DQS_DN<9>   @S9S_MB_2U_LIB.S9S_MB_2U(SCH_1):M_E_CPU0_SB_DQS_DN<9>
  J9      94  DQS9_B_N  SCONN288_ADR50001P013C01  I126
  J10     94  DQS9_B_N  SCONN288_ADR50001P003C01  I127
  U2     EK36  DDR4_SB_DQS_DN9  SOCKET4677_AZIFS054P001C01  I169

M_E_CPU0_SB_DQS_DP<0>   @S9S_MB_2U_LIB.S9S_MB_2U(SCH_1):M_E_CPU0_SB_DQS_DP<0>
  J9     104  DQS0_B_P  SCONN288_ADR50001P013C01  I126
  J10    104  DQS0_B_P  SCONN288_ADR50001P003C01  I127
  U2     EC27  DDR4_SB_DQS_DP0  SOCKET4677_AZIFS054P001C01  I169

M_E_CPU0_SB_DQS_DP<1>   @S9S_MB_2U_LIB.S9S_MB_2U(SCH_1):M_E_CPU0_SB_DQS_DP<1>
  J9     115  DQS1_B_P  SCONN288_ADR50001P013C01  I126
  J10    115  DQS1_B_P  SCONN288_ADR50001P003C01  I127
  U2     EM30  DDR4_SB_DQS_DP1  SOCKET4677_AZIFS054P001C01  I169

M_E_CPU0_SB_DQS_DP<2>   @S9S_MB_2U_LIB.S9S_MB_2U(SCH_1):M_E_CPU0_SB_DQS_DP<2>
  J9     126  DQS2_B_P  SCONN288_ADR50001P013C01  I126
  J10    126  DQS2_B_P  SCONN288_ADR50001P003C01  I127
  U2     EM24  DDR4_SB_DQS_DP2  SOCKET4677_AZIFS054P001C01  I169

M_E_CPU0_SB_DQS_DP<3>   @S9S_MB_2U_LIB.S9S_MB_2U(SCH_1):M_E_CPU0_SB_DQS_DP<3>
  J9     137  DQS3_B_P  SCONN288_ADR50001P013C01  I126
  J10    137  DQS3_B_P  SCONN288_ADR50001P003C01  I127
  U2     EM18  DDR4_SB_DQS_DP3  SOCKET4677_AZIFS054P001C01  I169

M_E_CPU0_SB_DQS_DP<4>   @S9S_MB_2U_LIB.S9S_MB_2U(SCH_1):M_E_CPU0_SB_DQS_DP<4>
  J9     239  DQS4_B_P  SCONN288_ADR50001P013C01  I126
  J10    239  DQS4_B_P  SCONN288_ADR50001P003C01  I127
  U2     EP36  DDR4_SB_DQS_DP4  SOCKET4677_AZIFS054P001C01  I169

M_E_CPU0_SB_DQS_DP<5>   @S9S_MB_2U_LIB.S9S_MB_2U(SCH_1):M_E_CPU0_SB_DQS_DP<5>
  J9     250  DQS5_B_P  SCONN288_ADR50001P013C01  I126
  J10    250  DQS5_B_P  SCONN288_ADR50001P003C01  I127
  U2     EG27  DDR4_SB_DQS_DP5  SOCKET4677_AZIFS054P001C01  I169

M_E_CPU0_SB_DQS_DP<6>   @S9S_MB_2U_LIB.S9S_MB_2U(SCH_1):M_E_CPU0_SB_DQS_DP<6>
  J9     261  DQS6_B_P  SCONN288_ADR50001P013C01  I126
  J10    261  DQS6_B_P  SCONN288_ADR50001P003C01  I127
  U2     EP30  DDR4_SB_DQS_DP6  SOCKET4677_AZIFS054P001C01  I169

M_E_CPU0_SB_DQS_DP<7>   @S9S_MB_2U_LIB.S9S_MB_2U(SCH_1):M_E_CPU0_SB_DQS_DP<7>
  J9     272  DQS7_B_P  SCONN288_ADR50001P013C01  I126
  J10    272  DQS7_B_P  SCONN288_ADR50001P003C01  I127
  U2     EP24  DDR4_SB_DQS_DP7  SOCKET4677_AZIFS054P001C01  I169

M_E_CPU0_SB_DQS_DP<8>   @S9S_MB_2U_LIB.S9S_MB_2U(SCH_1):M_E_CPU0_SB_DQS_DP<8>
  J9     283  DQS8_B_P  SCONN288_ADR50001P013C01  I126
  J10    283  DQS8_B_P  SCONN288_ADR50001P003C01  I127
  U2     EP18  DDR4_SB_DQS_DP8  SOCKET4677_AZIFS054P001C01  I169

M_E_CPU0_SB_DQS_DP<9>   @S9S_MB_2U_LIB.S9S_MB_2U(SCH_1):M_E_CPU0_SB_DQS_DP<9>
  J9      93  DQS9_B_P  SCONN288_ADR50001P013C01  I126
  J10     93  DQS9_B_P  SCONN288_ADR50001P003C01  I127
  U2     EM36  DDR4_SB_DQS_DP9  SOCKET4677_AZIFS054P001C01  I169

M_E_CPU0_SB_PAR   @S9S_MB_2U_LIB.S9S_MB_2U(SCH_1):M_E_CPU0_SB_PAR
  J9     227  PAR_B  SCONN288_ADR50001P013C01  I12
  J10    227  PAR_B  SCONN288_ADR50001P003C01  I13
  U2     EP42  DDR4_SB_PAR  SOCKET4677_AZIFS054P001C01  I169

M_E_CPU0_SB_RSP<0>   @S9S_MB_2U_LIB.S9S_MB_2U(SCH_1):M_E_CPU0_SB_RSP<0>
  J9      87  LBS||RSP_N_B  SCONN288_ADR50001P013C01  I12
  U2     DF44  DDR4_B_RSP0  SOCKET4677_AZIFS054P001C01  I169

M_E_CPU0_SB_RSP<1>   @S9S_MB_2U_LIB.S9S_MB_2U(SCH_1):M_E_CPU0_SB_RSP<1>
  J10     87  LBS||RSP_N_B  SCONN288_ADR50001P003C01  I13
  U2     DG43  DDR4_B_RSP1  SOCKET4677_AZIFS054P001C01  I169

M_E_CPU1_ALERT_N   @S9S_MB_2U_LIB.S9S_MB_2U(SCH_1):M_E_CPU1_ALERT_N
  J25     62  ALERT_N  SCONN288_ADR50001P013C01  I180
  J26     62  ALERT_N  SCONN288_ADR50001P003C01  I180
  U1     CY47  DDR4_ALERT_N  SOCKET4677_AZIFS054P001C01   I7

M_E_CPU1_CLK_DN<0>   @S9S_MB_2U_LIB.S9S_MB_2U(SCH_1):M_E_CPU1_CLK_DN<0>
  J25    218   CK_N  SCONN288_ADR50001P013C01  I180
  U1     EJ45  DDR4_CLK_DN0  SOCKET4677_AZIFS054P001C01   I7

M_E_CPU1_CLK_DN<1>   @S9S_MB_2U_LIB.S9S_MB_2U(SCH_1):M_E_CPU1_CLK_DN<1>
  J26    218   CK_N  SCONN288_ADR50001P003C01  I180
  U1     EE45  DDR4_CLK_DN1  SOCKET4677_AZIFS054P001C01   I7

M_E_CPU1_CLK_DP<0>   @S9S_MB_2U_LIB.S9S_MB_2U(SCH_1):M_E_CPU1_CLK_DP<0>
  J25    217   CK_P  SCONN288_ADR50001P013C01  I180
  U1     EG45  DDR4_CLK_DP0  SOCKET4677_AZIFS054P001C01   I7

M_E_CPU1_CLK_DP<1>   @S9S_MB_2U_LIB.S9S_MB_2U(SCH_1):M_E_CPU1_CLK_DP<1>
  J26    217   CK_P  SCONN288_ADR50001P003C01  I180
  U1     EC45  DDR4_CLK_DP1  SOCKET4677_AZIFS054P001C01   I7

M_E_CPU1_SA_CA<0>   @S9S_MB_2U_LIB.S9S_MB_2U(SCH_1):M_E_CPU1_SA_CA<0>
  J25     66  CA0_A  SCONN288_ADR50001P013C01  I180
  J26     66  CA0_A  SCONN288_ADR50001P003C01  I180
  U1     EP49  DDR4_SA_CA0  SOCKET4677_AZIFS054P001C01   I7

M_E_CPU1_SA_CA<1>   @S9S_MB_2U_LIB.S9S_MB_2U(SCH_1):M_E_CPU1_SA_CA<1>
  J25    211  CA1_A  SCONN288_ADR50001P013C01  I180
  J26    211  CA1_A  SCONN288_ADR50001P003C01  I180
  U1     ET49  DDR4_SA_CA1  SOCKET4677_AZIFS054P001C01   I7

M_E_CPU1_SA_CA<2>   @S9S_MB_2U_LIB.S9S_MB_2U(SCH_1):M_E_CPU1_SA_CA<2>
  J25     68  CA2_A  SCONN288_ADR50001P013C01  I180
  J26     68  CA2_A  SCONN288_ADR50001P003C01  I180
  U1     EK49  DDR4_SA_CA2  SOCKET4677_AZIFS054P001C01   I7

M_E_CPU1_SA_CA<3>   @S9S_MB_2U_LIB.S9S_MB_2U(SCH_1):M_E_CPU1_SA_CA<3>
  J25    213  CA3_A  SCONN288_ADR50001P013C01  I180
  J26    213  CA3_A  SCONN288_ADR50001P003C01  I180
  U1     EL48  DDR4_SA_CA3  SOCKET4677_AZIFS054P001C01   I7

M_E_CPU1_SA_CA<4>   @S9S_MB_2U_LIB.S9S_MB_2U(SCH_1):M_E_CPU1_SA_CA<4>
  J25     70  CA4_A  SCONN288_ADR50001P013C01  I180
  J26     70  CA4_A  SCONN288_ADR50001P003C01  I180
  U1     EM47  DDR4_SA_CA4  SOCKET4677_AZIFS054P001C01   I7

M_E_CPU1_SA_CA<5>   @S9S_MB_2U_LIB.S9S_MB_2U(SCH_1):M_E_CPU1_SA_CA<5>
  J25    215  CA5_A  SCONN288_ADR50001P013C01  I180
  J26    215  CA5_A  SCONN288_ADR50001P003C01  I180
  U1     EP47  DDR4_SA_CA5  SOCKET4677_AZIFS054P001C01   I7

M_E_CPU1_SA_CA<6>   @S9S_MB_2U_LIB.S9S_MB_2U(SCH_1):M_E_CPU1_SA_CA<6>
  J25     72  CA6_A  SCONN288_ADR50001P013C01  I180
  J26     72  CA6_A  SCONN288_ADR50001P003C01  I180
  U1     ED44  DDR4_SA_CA6  SOCKET4677_AZIFS054P001C01   I7

M_E_CPU1_SA_CB<0>   @S9S_MB_2U_LIB.S9S_MB_2U(SCH_1):M_E_CPU1_SA_CB<0>
  J25     51  CB_A0  SCONN288_ADR50001P013C01  I180
  J26     51  CB_A0  SCONN288_ADR50001P003C01  I180
  U1     EM57  DDR4_SA_ECC0  SOCKET4677_AZIFS054P001C01   I7

M_E_CPU1_SA_CB<1>   @S9S_MB_2U_LIB.S9S_MB_2U(SCH_1):M_E_CPU1_SA_CB<1>
  J25     53  CB_A1  SCONN288_ADR50001P013C01  I180
  J26     53  CB_A1  SCONN288_ADR50001P003C01  I180
  U1     EL56  DDR4_SA_ECC1  SOCKET4677_AZIFS054P001C01   I7

M_E_CPU1_SA_CB<2>   @S9S_MB_2U_LIB.S9S_MB_2U(SCH_1):M_E_CPU1_SA_CB<2>
  J25    196  CB_A2  SCONN288_ADR50001P013C01  I180
  J26    196  CB_A2  SCONN288_ADR50001P003C01  I180
  U1     EP57  DDR4_SA_ECC2  SOCKET4677_AZIFS054P001C01   I7

M_E_CPU1_SA_CB<3>   @S9S_MB_2U_LIB.S9S_MB_2U(SCH_1):M_E_CPU1_SA_CB<3>
  J25    198  CB_A3  SCONN288_ADR50001P013C01  I180
  J26    198  CB_A3  SCONN288_ADR50001P003C01  I180
  U1     ER56  DDR4_SA_ECC3  SOCKET4677_AZIFS054P001C01   I7

M_E_CPU1_SA_CB<4>   @S9S_MB_2U_LIB.S9S_MB_2U(SCH_1):M_E_CPU1_SA_CB<4>
  J25     58  CB_A4  SCONN288_ADR50001P013C01  I180
  J26     58  CB_A4  SCONN288_ADR50001P003C01  I180
  U1     EL54  DDR4_SA_ECC4  SOCKET4677_AZIFS054P001C01   I7

M_E_CPU1_SA_CB<5>   @S9S_MB_2U_LIB.S9S_MB_2U(SCH_1):M_E_CPU1_SA_CB<5>
  J25     60  CB_A5  SCONN288_ADR50001P013C01  I180
  J26     60  CB_A5  SCONN288_ADR50001P003C01  I180
  U1     EM53  DDR4_SA_ECC5  SOCKET4677_AZIFS054P001C01   I7

M_E_CPU1_SA_CB<6>   @S9S_MB_2U_LIB.S9S_MB_2U(SCH_1):M_E_CPU1_SA_CB<6>
  J25    203  CB_A6  SCONN288_ADR50001P013C01  I180
  J26    203  CB_A6  SCONN288_ADR50001P003C01  I180
  U1     ER54  DDR4_SA_ECC6  SOCKET4677_AZIFS054P001C01   I7

M_E_CPU1_SA_CB<7>   @S9S_MB_2U_LIB.S9S_MB_2U(SCH_1):M_E_CPU1_SA_CB<7>
  J25    205  CB_A7  SCONN288_ADR50001P013C01  I180
  J26    205  CB_A7  SCONN288_ADR50001P003C01  I180
  U1     EP53  DDR4_SA_ECC7  SOCKET4677_AZIFS054P001C01   I7

M_E_CPU1_SA_CS_N<0>   @S9S_MB_2U_LIB.S9S_MB_2U(SCH_1):M_E_CPU1_SA_CS_N<0>
  J25     64  CS0_N_A  SCONN288_ADR50001P013C01  I180
  U1     EP51  DDR4_SA_CS0_N  SOCKET4677_AZIFS054P001C01   I7

M_E_CPU1_SA_CS_N<1>   @S9S_MB_2U_LIB.S9S_MB_2U(SCH_1):M_E_CPU1_SA_CS_N<1>
  J25    209  CS1_N_A  SCONN288_ADR50001P013C01  I180
  U1     ET51  DDR4_SA_CS1_N  SOCKET4677_AZIFS054P001C01   I7

M_E_CPU1_SA_CS_N<2>   @S9S_MB_2U_LIB.S9S_MB_2U(SCH_1):M_E_CPU1_SA_CS_N<2>
  J26     64  CS0_N_A  SCONN288_ADR50001P003C01  I180
  U1     EM51  DDR4_SA_CS2_N  SOCKET4677_AZIFS054P001C01   I7

M_E_CPU1_SA_CS_N<3>   @S9S_MB_2U_LIB.S9S_MB_2U(SCH_1):M_E_CPU1_SA_CS_N<3>
  J26    209  CS1_N_A  SCONN288_ADR50001P003C01  I180
  U1     EL50  DDR4_SA_CS3_N  SOCKET4677_AZIFS054P001C01   I7

M_E_CPU1_SA_DQ<0>   @S9S_MB_2U_LIB.S9S_MB_2U(SCH_1):M_E_CPU1_SA_DQ<0>
  J25      7  DQ_A0  SCONN288_ADR50001P013C01  I180
  J26      7  DQ_A0  SCONN288_ADR50001P003C01  I180
  U1     EL78  DDR4_SA_DQ0  SOCKET4677_AZIFS054P001C01   I7

M_E_CPU1_SA_DQ<1>   @S9S_MB_2U_LIB.S9S_MB_2U(SCH_1):M_E_CPU1_SA_DQ<1>
  J25      9  DQ_A1  SCONN288_ADR50001P013C01  I180
  J26      9  DQ_A1  SCONN288_ADR50001P003C01  I180
  U1     EM77  DDR4_SA_DQ1  SOCKET4677_AZIFS054P001C01   I7

M_E_CPU1_SA_DQ<2>   @S9S_MB_2U_LIB.S9S_MB_2U(SCH_1):M_E_CPU1_SA_DQ<2>
  J25    152  DQ_A2  SCONN288_ADR50001P013C01  I180
  J26    152  DQ_A2  SCONN288_ADR50001P003C01  I180
  U1     EP79  DDR4_SA_DQ2  SOCKET4677_AZIFS054P001C01   I7

M_E_CPU1_SA_DQ<3>   @S9S_MB_2U_LIB.S9S_MB_2U(SCH_1):M_E_CPU1_SA_DQ<3>
  J25    154  DQ_A3  SCONN288_ADR50001P013C01  I180
  J26    154  DQ_A3  SCONN288_ADR50001P003C01  I180
  U1     ER76  DDR4_SA_DQ3  SOCKET4677_AZIFS054P001C01   I7

M_E_CPU1_SA_DQ<4>   @S9S_MB_2U_LIB.S9S_MB_2U(SCH_1):M_E_CPU1_SA_DQ<4>
  J25     14  DQ_A4  SCONN288_ADR50001P013C01  I180
  J26     14  DQ_A4  SCONN288_ADR50001P003C01  I180
  U1     EL74  DDR4_SA_DQ4  SOCKET4677_AZIFS054P001C01   I7

M_E_CPU1_SA_DQ<5>   @S9S_MB_2U_LIB.S9S_MB_2U(SCH_1):M_E_CPU1_SA_DQ<5>
  J25     16  DQ_A5  SCONN288_ADR50001P013C01  I180
  J26     16  DQ_A5  SCONN288_ADR50001P003C01  I180
  U1     EK73  DDR4_SA_DQ5  SOCKET4677_AZIFS054P001C01   I7

M_E_CPU1_SA_DQ<6>   @S9S_MB_2U_LIB.S9S_MB_2U(SCH_1):M_E_CPU1_SA_DQ<6>
  J25    159  DQ_A6  SCONN288_ADR50001P013C01  I180
  J26    159  DQ_A6  SCONN288_ADR50001P003C01  I180
  U1     EP73  DDR4_SA_DQ6  SOCKET4677_AZIFS054P001C01   I7

M_E_CPU1_SA_DQ<7>   @S9S_MB_2U_LIB.S9S_MB_2U(SCH_1):M_E_CPU1_SA_DQ<7>
  J25    161  DQ_A7  SCONN288_ADR50001P013C01  I180
  J26    161  DQ_A7  SCONN288_ADR50001P003C01  I180
  U1     ER72  DDR4_SA_DQ7  SOCKET4677_AZIFS054P001C01   I7

M_E_CPU1_SA_DQ<8>   @S9S_MB_2U_LIB.S9S_MB_2U(SCH_1):M_E_CPU1_SA_DQ<8>
  J25     18  DQ_A8  SCONN288_ADR50001P013C01  I180
  J26     18  DQ_A8  SCONN288_ADR50001P003C01  I180
  U1     EE72  DDR4_SA_DQ8  SOCKET4677_AZIFS054P001C01   I7

M_E_CPU1_SA_DQ<9>   @S9S_MB_2U_LIB.S9S_MB_2U(SCH_1):M_E_CPU1_SA_DQ<9>
  J25     20  DQ_A9  SCONN288_ADR50001P013C01  I180
  J26     20  DQ_A9  SCONN288_ADR50001P003C01  I180
  U1     ED71  DDR4_SA_DQ9  SOCKET4677_AZIFS054P001C01   I7

M_E_CPU1_SA_DQ<10>   @S9S_MB_2U_LIB.S9S_MB_2U(SCH_1):M_E_CPU1_SA_DQ<10>
  J25    163  DQ_A10  SCONN288_ADR50001P013C01  I180
  J26    163  DQ_A10  SCONN288_ADR50001P003C01  I180
  U1     EG72  DDR4_SA_DQ10  SOCKET4677_AZIFS054P001C01   I7

M_E_CPU1_SA_DQ<11>   @S9S_MB_2U_LIB.S9S_MB_2U(SCH_1):M_E_CPU1_SA_DQ<11>
  J25    165  DQ_A11  SCONN288_ADR50001P013C01  I180
  J26    165  DQ_A11  SCONN288_ADR50001P003C01  I180
  U1     EH71  DDR4_SA_DQ11  SOCKET4677_AZIFS054P001C01   I7

M_E_CPU1_SA_DQ<12>   @S9S_MB_2U_LIB.S9S_MB_2U(SCH_1):M_E_CPU1_SA_DQ<12>
  J25     25  DQ_A12  SCONN288_ADR50001P013C01  I180
  J26     25  DQ_A12  SCONN288_ADR50001P003C01  I180
  U1     ED69  DDR4_SA_DQ12  SOCKET4677_AZIFS054P001C01   I7

M_E_CPU1_SA_DQ<13>   @S9S_MB_2U_LIB.S9S_MB_2U(SCH_1):M_E_CPU1_SA_DQ<13>
  J25     27  DQ_A13  SCONN288_ADR50001P013C01  I180
  J26     27  DQ_A13  SCONN288_ADR50001P003C01  I180
  U1     EE68  DDR4_SA_DQ13  SOCKET4677_AZIFS054P001C01   I7

M_E_CPU1_SA_DQ<14>   @S9S_MB_2U_LIB.S9S_MB_2U(SCH_1):M_E_CPU1_SA_DQ<14>
  J25    170  DQ_A14  SCONN288_ADR50001P013C01  I180
  J26    170  DQ_A14  SCONN288_ADR50001P003C01  I180
  U1     EH69  DDR4_SA_DQ14  SOCKET4677_AZIFS054P001C01   I7

M_E_CPU1_SA_DQ<15>   @S9S_MB_2U_LIB.S9S_MB_2U(SCH_1):M_E_CPU1_SA_DQ<15>
  J25    172  DQ_A15  SCONN288_ADR50001P013C01  I180
  J26    172  DQ_A15  SCONN288_ADR50001P003C01  I180
  U1     EG68  DDR4_SA_DQ15  SOCKET4677_AZIFS054P001C01   I7

M_E_CPU1_SA_DQ<16>   @S9S_MB_2U_LIB.S9S_MB_2U(SCH_1):M_E_CPU1_SA_DQ<16>
  J25     29  DQ_A16  SCONN288_ADR50001P013C01  I180
  J26     29  DQ_A16  SCONN288_ADR50001P003C01  I180
  U1     EM71  DDR4_SA_DQ16  SOCKET4677_AZIFS054P001C01   I7

M_E_CPU1_SA_DQ<17>   @S9S_MB_2U_LIB.S9S_MB_2U(SCH_1):M_E_CPU1_SA_DQ<17>
  J25     31  DQ_A17  SCONN288_ADR50001P013C01  I180
  J26     31  DQ_A17  SCONN288_ADR50001P003C01  I180
  U1     EM69  DDR4_SA_DQ17  SOCKET4677_AZIFS054P001C01   I7

M_E_CPU1_SA_DQ<18>   @S9S_MB_2U_LIB.S9S_MB_2U(SCH_1):M_E_CPU1_SA_DQ<18>
  J25    174  DQ_A18  SCONN288_ADR50001P013C01  I180
  J26    174  DQ_A18  SCONN288_ADR50001P003C01  I180
  U1     EN70  DDR4_SA_DQ18  SOCKET4677_AZIFS054P001C01   I7

M_E_CPU1_SA_DQ<19>   @S9S_MB_2U_LIB.S9S_MB_2U(SCH_1):M_E_CPU1_SA_DQ<19>
  J25    176  DQ_A19  SCONN288_ADR50001P013C01  I180
  J26    176  DQ_A19  SCONN288_ADR50001P003C01  I180
  U1     ER68  DDR4_SA_DQ19  SOCKET4677_AZIFS054P001C01   I7

M_E_CPU1_SA_DQ<20>   @S9S_MB_2U_LIB.S9S_MB_2U(SCH_1):M_E_CPU1_SA_DQ<20>
  J25     36  DQ_A20  SCONN288_ADR50001P013C01  I180
  J26     36  DQ_A20  SCONN288_ADR50001P003C01  I180
  U1     ER66  DDR4_SA_DQ20  SOCKET4677_AZIFS054P001C01   I7

M_E_CPU1_SA_DQ<21>   @S9S_MB_2U_LIB.S9S_MB_2U(SCH_1):M_E_CPU1_SA_DQ<21>
  J25     38  DQ_A21  SCONN288_ADR50001P013C01  I180
  J26     38  DQ_A21  SCONN288_ADR50001P003C01  I180
  U1     EM65  DDR4_SA_DQ21  SOCKET4677_AZIFS054P001C01   I7

M_E_CPU1_SA_DQ<22>   @S9S_MB_2U_LIB.S9S_MB_2U(SCH_1):M_E_CPU1_SA_DQ<22>
  J25    181  DQ_A22  SCONN288_ADR50001P013C01  I180
  J26    181  DQ_A22  SCONN288_ADR50001P003C01  I180
  U1     EL66  DDR4_SA_DQ22  SOCKET4677_AZIFS054P001C01   I7

M_E_CPU1_SA_DQ<23>   @S9S_MB_2U_LIB.S9S_MB_2U(SCH_1):M_E_CPU1_SA_DQ<23>
  J25    183  DQ_A23  SCONN288_ADR50001P013C01  I180
  J26    183  DQ_A23  SCONN288_ADR50001P003C01  I180
  U1     EP65  DDR4_SA_DQ23  SOCKET4677_AZIFS054P001C01   I7

M_E_CPU1_SA_DQ<24>   @S9S_MB_2U_LIB.S9S_MB_2U(SCH_1):M_E_CPU1_SA_DQ<24>
  J25     40  DQ_A24  SCONN288_ADR50001P013C01  I180
  J26     40  DQ_A24  SCONN288_ADR50001P003C01  I180
  U1     EM63  DDR4_SA_DQ24  SOCKET4677_AZIFS054P001C01   I7

M_E_CPU1_SA_DQ<25>   @S9S_MB_2U_LIB.S9S_MB_2U(SCH_1):M_E_CPU1_SA_DQ<25>
  J25     42  DQ_A25  SCONN288_ADR50001P013C01  I180
  J26     42  DQ_A25  SCONN288_ADR50001P003C01  I180
  U1     EL62  DDR4_SA_DQ25  SOCKET4677_AZIFS054P001C01   I7

M_E_CPU1_SA_DQ<26>   @S9S_MB_2U_LIB.S9S_MB_2U(SCH_1):M_E_CPU1_SA_DQ<26>
  J25    185  DQ_A26  SCONN288_ADR50001P013C01  I180
  J26    185  DQ_A26  SCONN288_ADR50001P003C01  I180
  U1     EP63  DDR4_SA_DQ26  SOCKET4677_AZIFS054P001C01   I7

M_E_CPU1_SA_DQ<27>   @S9S_MB_2U_LIB.S9S_MB_2U(SCH_1):M_E_CPU1_SA_DQ<27>
  J25    187  DQ_A27  SCONN288_ADR50001P013C01  I180
  J26    187  DQ_A27  SCONN288_ADR50001P003C01  I180
  U1     ER62  DDR4_SA_DQ27  SOCKET4677_AZIFS054P001C01   I7

M_E_CPU1_SA_DQ<28>   @S9S_MB_2U_LIB.S9S_MB_2U(SCH_1):M_E_CPU1_SA_DQ<28>
  J25     47  DQ_A28  SCONN288_ADR50001P013C01  I180
  J26     47  DQ_A28  SCONN288_ADR50001P003C01  I180
  U1     EL60  DDR4_SA_DQ28  SOCKET4677_AZIFS054P001C01   I7

M_E_CPU1_SA_DQ<29>   @S9S_MB_2U_LIB.S9S_MB_2U(SCH_1):M_E_CPU1_SA_DQ<29>
  J25     49  DQ_A29  SCONN288_ADR50001P013C01  I180
  J26     49  DQ_A29  SCONN288_ADR50001P003C01  I180
  U1     EM59  DDR4_SA_DQ29  SOCKET4677_AZIFS054P001C01   I7

M_E_CPU1_SA_DQ<30>   @S9S_MB_2U_LIB.S9S_MB_2U(SCH_1):M_E_CPU1_SA_DQ<30>
  J25    192  DQ_A30  SCONN288_ADR50001P013C01  I180
  J26    192  DQ_A30  SCONN288_ADR50001P003C01  I180
  U1     ER60  DDR4_SA_DQ30  SOCKET4677_AZIFS054P001C01   I7

M_E_CPU1_SA_DQ<31>   @S9S_MB_2U_LIB.S9S_MB_2U(SCH_1):M_E_CPU1_SA_DQ<31>
  J25    194  DQ_A31  SCONN288_ADR50001P013C01  I180
  J26    194  DQ_A31  SCONN288_ADR50001P003C01  I180
  U1     EP59  DDR4_SA_DQ31  SOCKET4677_AZIFS054P001C01   I7

M_E_CPU1_SA_DQS_DN<0>   @S9S_MB_2U_LIB.S9S_MB_2U(SCH_1):M_E_CPU1_SA_DQS_DN<0>
  J25     12  DQS0_A_N  SCONN288_ADR50001P013C01  I179
  J26     12  DQS0_A_N  SCONN288_ADR50001P003C01  I178
  U1     EP75  DDR4_SA_DQS_DN0  SOCKET4677_AZIFS054P001C01   I7

M_E_CPU1_SA_DQS_DN<1>   @S9S_MB_2U_LIB.S9S_MB_2U(SCH_1):M_E_CPU1_SA_DQS_DN<1>
  J25     23  DQS1_A_N  SCONN288_ADR50001P013C01  I179
  J26     23  DQS1_A_N  SCONN288_ADR50001P003C01  I178
  U1     EC70  DDR4_SA_DQS_DN1  SOCKET4677_AZIFS054P001C01   I7

M_E_CPU1_SA_DQS_DN<2>   @S9S_MB_2U_LIB.S9S_MB_2U(SCH_1):M_E_CPU1_SA_DQS_DN<2>
  J25     34  DQS2_A_N  SCONN288_ADR50001P013C01  I179
  J26     34  DQS2_A_N  SCONN288_ADR50001P003C01  I178
  U1     EK67  DDR4_SA_DQS_DN2  SOCKET4677_AZIFS054P001C01   I7

M_E_CPU1_SA_DQS_DN<3>   @S9S_MB_2U_LIB.S9S_MB_2U(SCH_1):M_E_CPU1_SA_DQS_DN<3>
  J25     45  DQS3_A_N  SCONN288_ADR50001P013C01  I179
  J26     45  DQS3_A_N  SCONN288_ADR50001P003C01  I178
  U1     EK61  DDR4_SA_DQS_DN3  SOCKET4677_AZIFS054P001C01   I7

M_E_CPU1_SA_DQS_DN<4>   @S9S_MB_2U_LIB.S9S_MB_2U(SCH_1):M_E_CPU1_SA_DQS_DN<4>
  J25     56  DQS4_A_N  SCONN288_ADR50001P013C01  I179
  J26     56  DQS4_A_N  SCONN288_ADR50001P003C01  I178
  U1     EM55  DDR4_SA_DQS_DN4  SOCKET4677_AZIFS054P001C01   I7

M_E_CPU1_SA_DQS_DN<5>   @S9S_MB_2U_LIB.S9S_MB_2U(SCH_1):M_E_CPU1_SA_DQS_DN<5>
  J25    156  DQS5_A_N  SCONN288_ADR50001P013C01  I179
  J26    156  DQS5_A_N  SCONN288_ADR50001P003C01  I178
  U1     EM75  DDR4_SA_DQS_DN5  SOCKET4677_AZIFS054P001C01   I7

M_E_CPU1_SA_DQS_DN<6>   @S9S_MB_2U_LIB.S9S_MB_2U(SCH_1):M_E_CPU1_SA_DQS_DN<6>
  J25    167  DQS6_A_N  SCONN288_ADR50001P013C01  I179
  J26    167  DQS6_A_N  SCONN288_ADR50001P003C01  I178
  U1     EJ70  DDR4_SA_DQS_DN6  SOCKET4677_AZIFS054P001C01   I7

M_E_CPU1_SA_DQS_DN<7>   @S9S_MB_2U_LIB.S9S_MB_2U(SCH_1):M_E_CPU1_SA_DQS_DN<7>
  J25    178  DQS7_A_N  SCONN288_ADR50001P013C01  I179
  J26    178  DQS7_A_N  SCONN288_ADR50001P003C01  I178
  U1     EN68  DDR4_SA_DQS_DN7  SOCKET4677_AZIFS054P001C01   I7

M_E_CPU1_SA_DQS_DN<8>   @S9S_MB_2U_LIB.S9S_MB_2U(SCH_1):M_E_CPU1_SA_DQS_DN<8>
  J25    189  DQS8_A_N  SCONN288_ADR50001P013C01  I179
  J26    189  DQS8_A_N  SCONN288_ADR50001P003C01  I178
  U1     ET61  DDR4_SA_DQS_DN8  SOCKET4677_AZIFS054P001C01   I7

M_E_CPU1_SA_DQS_DN<9>   @S9S_MB_2U_LIB.S9S_MB_2U(SCH_1):M_E_CPU1_SA_DQS_DN<9>
  J25    200  DQS9_A_N  SCONN288_ADR50001P013C01  I179
  J26    200  DQS9_A_N  SCONN288_ADR50001P003C01  I178
  U1     ET55  DDR4_SA_DQS_DN9  SOCKET4677_AZIFS054P001C01   I7

M_E_CPU1_SA_DQS_DP<0>   @S9S_MB_2U_LIB.S9S_MB_2U(SCH_1):M_E_CPU1_SA_DQS_DP<0>
  J25     11  DQS0_A_P  SCONN288_ADR50001P013C01  I179
  J26     11  DQS0_A_P  SCONN288_ADR50001P003C01  I178
  U1     EN76  DDR4_SA_DQS_DP0  SOCKET4677_AZIFS054P001C01   I7

M_E_CPU1_SA_DQS_DP<1>   @S9S_MB_2U_LIB.S9S_MB_2U(SCH_1):M_E_CPU1_SA_DQS_DP<1>
  J25     22  DQS1_A_P  SCONN288_ADR50001P013C01  I179
  J26     22  DQS1_A_P  SCONN288_ADR50001P003C01  I178
  U1     EE70  DDR4_SA_DQS_DP1  SOCKET4677_AZIFS054P001C01   I7

M_E_CPU1_SA_DQS_DP<2>   @S9S_MB_2U_LIB.S9S_MB_2U(SCH_1):M_E_CPU1_SA_DQS_DP<2>
  J25     33  DQS2_A_P  SCONN288_ADR50001P013C01  I179
  J26     33  DQS2_A_P  SCONN288_ADR50001P003C01  I178
  U1     EL68  DDR4_SA_DQS_DP2  SOCKET4677_AZIFS054P001C01   I7

M_E_CPU1_SA_DQS_DP<3>   @S9S_MB_2U_LIB.S9S_MB_2U(SCH_1):M_E_CPU1_SA_DQS_DP<3>
  J25     44  DQS3_A_P  SCONN288_ADR50001P013C01  I179
  J26     44  DQS3_A_P  SCONN288_ADR50001P003C01  I178
  U1     EM61  DDR4_SA_DQS_DP3  SOCKET4677_AZIFS054P001C01   I7

M_E_CPU1_SA_DQS_DP<4>   @S9S_MB_2U_LIB.S9S_MB_2U(SCH_1):M_E_CPU1_SA_DQS_DP<4>
  J25     55  DQS4_A_P  SCONN288_ADR50001P013C01  I179
  J26     55  DQS4_A_P  SCONN288_ADR50001P003C01  I178
  U1     EK55  DDR4_SA_DQS_DP4  SOCKET4677_AZIFS054P001C01   I7

M_E_CPU1_SA_DQS_DP<5>   @S9S_MB_2U_LIB.S9S_MB_2U(SCH_1):M_E_CPU1_SA_DQS_DP<5>
  J25    157  DQS5_A_P  SCONN288_ADR50001P013C01  I179
  J26    157  DQS5_A_P  SCONN288_ADR50001P003C01  I178
  U1     EN74  DDR4_SA_DQS_DP5  SOCKET4677_AZIFS054P001C01   I7

M_E_CPU1_SA_DQS_DP<6>   @S9S_MB_2U_LIB.S9S_MB_2U(SCH_1):M_E_CPU1_SA_DQS_DP<6>
  J25    168  DQS6_A_P  SCONN288_ADR50001P013C01  I179
  J26    168  DQS6_A_P  SCONN288_ADR50001P003C01  I178
  U1     EG70  DDR4_SA_DQS_DP6  SOCKET4677_AZIFS054P001C01   I7

M_E_CPU1_SA_DQS_DP<7>   @S9S_MB_2U_LIB.S9S_MB_2U(SCH_1):M_E_CPU1_SA_DQS_DP<7>
  J25    179  DQS7_A_P  SCONN288_ADR50001P013C01  I179
  J26    179  DQS7_A_P  SCONN288_ADR50001P003C01  I178
  U1     EM67  DDR4_SA_DQS_DP7  SOCKET4677_AZIFS054P001C01   I7

M_E_CPU1_SA_DQS_DP<8>   @S9S_MB_2U_LIB.S9S_MB_2U(SCH_1):M_E_CPU1_SA_DQS_DP<8>
  J25    190  DQS8_A_P  SCONN288_ADR50001P013C01  I179
  J26    190  DQS8_A_P  SCONN288_ADR50001P003C01  I178
  U1     EP61  DDR4_SA_DQS_DP8  SOCKET4677_AZIFS054P001C01   I7

M_E_CPU1_SA_DQS_DP<9>   @S9S_MB_2U_LIB.S9S_MB_2U(SCH_1):M_E_CPU1_SA_DQS_DP<9>
  J25    201  DQS9_A_P  SCONN288_ADR50001P013C01  I179
  J26    201  DQS9_A_P  SCONN288_ADR50001P003C01  I178
  U1     EP55  DDR4_SA_DQS_DP9  SOCKET4677_AZIFS054P001C01   I7

M_E_CPU1_SA_PAR   @S9S_MB_2U_LIB.S9S_MB_2U(SCH_1):M_E_CPU1_SA_PAR
  J25     74  PAR_A  SCONN288_ADR50001P013C01  I180
  J26     74  PAR_A  SCONN288_ADR50001P003C01  I180
  U1     EE43  DDR4_SA_PAR  SOCKET4677_AZIFS054P001C01   I7

M_E_CPU1_SA_RSP<0>   @S9S_MB_2U_LIB.S9S_MB_2U(SCH_1):M_E_CPU1_SA_RSP<0>
  J25     86  LBD||RSP_N_A  SCONN288_ADR50001P013C01  I180
  U1     DD44  DDR4_A_RSP0  SOCKET4677_AZIFS054P001C01   I7

M_E_CPU1_SA_RSP<1>   @S9S_MB_2U_LIB.S9S_MB_2U(SCH_1):M_E_CPU1_SA_RSP<1>
  J26     86  LBD||RSP_N_A  SCONN288_ADR50001P003C01  I180
  U1     DC43  DDR4_A_RSP1  SOCKET4677_AZIFS054P001C01   I7

M_E_CPU1_SB_CA<0>   @S9S_MB_2U_LIB.S9S_MB_2U(SCH_1):M_E_CPU1_SB_CA<0>
  J25     76  CA0_B  SCONN288_ADR50001P013C01  I180
  J26     76  CA0_B  SCONN288_ADR50001P003C01  I180
  U1     EG43  DDR4_SB_CA0  SOCKET4677_AZIFS054P001C01   I7

M_E_CPU1_SB_CA<1>   @S9S_MB_2U_LIB.S9S_MB_2U(SCH_1):M_E_CPU1_SB_CA<1>
  J25    221  CA1_B  SCONN288_ADR50001P013C01  I180
  J26    221  CA1_B  SCONN288_ADR50001P003C01  I180
  U1     EH44  DDR4_SB_CA1  SOCKET4677_AZIFS054P001C01   I7

M_E_CPU1_SB_CA<2>   @S9S_MB_2U_LIB.S9S_MB_2U(SCH_1):M_E_CPU1_SB_CA<2>
  J25     78  CA2_B  SCONN288_ADR50001P013C01  I180
  J26     78  CA2_B  SCONN288_ADR50001P003C01  I180
  U1     EM44  DDR4_SB_CA2  SOCKET4677_AZIFS054P001C01   I7

M_E_CPU1_SB_CA<3>   @S9S_MB_2U_LIB.S9S_MB_2U(SCH_1):M_E_CPU1_SB_CA<3>
  J25    223  CA3_B  SCONN288_ADR50001P013C01  I180
  J26    223  CA3_B  SCONN288_ADR50001P003C01  I180
  U1     EP44  DDR4_SB_CA3  SOCKET4677_AZIFS054P001C01   I7

M_E_CPU1_SB_CA<4>   @S9S_MB_2U_LIB.S9S_MB_2U(SCH_1):M_E_CPU1_SB_CA<4>
  J25     80  CA4_B  SCONN288_ADR50001P013C01  I180
  J26     80  CA4_B  SCONN288_ADR50001P003C01  I180
  U1     EL43  DDR4_SB_CA4  SOCKET4677_AZIFS054P001C01   I7

M_E_CPU1_SB_CA<5>   @S9S_MB_2U_LIB.S9S_MB_2U(SCH_1):M_E_CPU1_SB_CA<5>
  J25    225  CA5_B  SCONN288_ADR50001P013C01  I180
  J26    225  CA5_B  SCONN288_ADR50001P003C01  I180
  U1     ET42  DDR4_SB_CA5  SOCKET4677_AZIFS054P001C01   I7

M_E_CPU1_SB_CA<6>   @S9S_MB_2U_LIB.S9S_MB_2U(SCH_1):M_E_CPU1_SB_CA<6>
  J25     82  CA6_B  SCONN288_ADR50001P013C01  I180
  J26     82  CA6_B  SCONN288_ADR50001P003C01  I180
  U1     EK42  DDR4_SB_CA6  SOCKET4677_AZIFS054P001C01   I7

M_E_CPU1_SB_CB<0>   @S9S_MB_2U_LIB.S9S_MB_2U(SCH_1):M_E_CPU1_SB_CB<0>
  J25     96  CB_B0  SCONN288_ADR50001P013C01  I180
  J26     96  CB_B0  SCONN288_ADR50001P003C01  I180
  U1     EL35  DDR4_SB_ECC0  SOCKET4677_AZIFS054P001C01   I7

M_E_CPU1_SB_CB<1>   @S9S_MB_2U_LIB.S9S_MB_2U(SCH_1):M_E_CPU1_SB_CB<1>
  J25     98  CB_B1  SCONN288_ADR50001P013C01  I180
  J26     98  CB_B1  SCONN288_ADR50001P003C01  I180
  U1     EM34  DDR4_SB_ECC1  SOCKET4677_AZIFS054P001C01   I7

M_E_CPU1_SB_CB<2>   @S9S_MB_2U_LIB.S9S_MB_2U(SCH_1):M_E_CPU1_SB_CB<2>
  J25    241  CB_B2  SCONN288_ADR50001P013C01  I180
  J26    241  CB_B2  SCONN288_ADR50001P003C01  I180
  U1     ER35  DDR4_SB_ECC2  SOCKET4677_AZIFS054P001C01   I7

M_E_CPU1_SB_CB<3>   @S9S_MB_2U_LIB.S9S_MB_2U(SCH_1):M_E_CPU1_SB_CB<3>
  J25    243  CB_B3  SCONN288_ADR50001P013C01  I180
  J26    243  CB_B3  SCONN288_ADR50001P003C01  I180
  U1     EP34  DDR4_SB_ECC3  SOCKET4677_AZIFS054P001C01   I7

M_E_CPU1_SB_CB<4>   @S9S_MB_2U_LIB.S9S_MB_2U(SCH_1):M_E_CPU1_SB_CB<4>
  J25     89  CB_B4  SCONN288_ADR50001P013C01  I180
  J26     89  CB_B4  SCONN288_ADR50001P003C01  I180
  U1     EM38  DDR4_SB_ECC4  SOCKET4677_AZIFS054P001C01   I7

M_E_CPU1_SB_CB<5>   @S9S_MB_2U_LIB.S9S_MB_2U(SCH_1):M_E_CPU1_SB_CB<5>
  J25     91  CB_B5  SCONN288_ADR50001P013C01  I180
  J26     91  CB_B5  SCONN288_ADR50001P003C01  I180
  U1     EL37  DDR4_SB_ECC5  SOCKET4677_AZIFS054P001C01   I7

M_E_CPU1_SB_CB<6>   @S9S_MB_2U_LIB.S9S_MB_2U(SCH_1):M_E_CPU1_SB_CB<6>
  J25    234  CB_B6  SCONN288_ADR50001P013C01  I180
  J26    234  CB_B6  SCONN288_ADR50001P003C01  I180
  U1     EP38  DDR4_SB_ECC6  SOCKET4677_AZIFS054P001C01   I7

M_E_CPU1_SB_CB<7>   @S9S_MB_2U_LIB.S9S_MB_2U(SCH_1):M_E_CPU1_SB_CB<7>
  J25    236  CB_B7  SCONN288_ADR50001P013C01  I180
  J26    236  CB_B7  SCONN288_ADR50001P003C01  I180
  U1     ER37  DDR4_SB_ECC7  SOCKET4677_AZIFS054P001C01   I7

M_E_CPU1_SB_CS_N<0>   @S9S_MB_2U_LIB.S9S_MB_2U(SCH_1):M_E_CPU1_SB_CS_N<0>
  J25     84  CS0_N_B  SCONN288_ADR50001P013C01  I180
  U1     EP40  DDR4_SB_CS0_N  SOCKET4677_AZIFS054P001C01   I7

M_E_CPU1_SB_CS_N<1>   @S9S_MB_2U_LIB.S9S_MB_2U(SCH_1):M_E_CPU1_SB_CS_N<1>
  J25    229  CS1_N_B  SCONN288_ADR50001P013C01  I180
  U1     ET40  DDR4_SB_CS1_N  SOCKET4677_AZIFS054P001C01   I7

M_E_CPU1_SB_CS_N<2>   @S9S_MB_2U_LIB.S9S_MB_2U(SCH_1):M_E_CPU1_SB_CS_N<2>
  J26     84  CS0_N_B  SCONN288_ADR50001P003C01  I180
  U1     EM40  DDR4_SB_CS2_N  SOCKET4677_AZIFS054P001C01   I7

M_E_CPU1_SB_CS_N<3>   @S9S_MB_2U_LIB.S9S_MB_2U(SCH_1):M_E_CPU1_SB_CS_N<3>
  J26    229  CS1_N_B  SCONN288_ADR50001P003C01  I180
  U1     EL41  DDR4_SB_CS3_N  SOCKET4677_AZIFS054P001C01   I7

M_E_CPU1_SB_DQ<0>   @S9S_MB_2U_LIB.S9S_MB_2U(SCH_1):M_E_CPU1_SB_DQ<0>
  J25    100  DQ_B0  SCONN288_ADR50001P013C01  I180
  J26    100  DQ_B0  SCONN288_ADR50001P003C01  I180
  U1     EE29  DDR4_SB_DQ0  SOCKET4677_AZIFS054P001C01   I7

M_E_CPU1_SB_DQ<1>   @S9S_MB_2U_LIB.S9S_MB_2U(SCH_1):M_E_CPU1_SB_DQ<1>
  J25    102  DQ_B1  SCONN288_ADR50001P013C01  I180
  J26    102  DQ_B1  SCONN288_ADR50001P003C01  I180
  U1     ED28  DDR4_SB_DQ1  SOCKET4677_AZIFS054P001C01   I7

M_E_CPU1_SB_DQ<2>   @S9S_MB_2U_LIB.S9S_MB_2U(SCH_1):M_E_CPU1_SB_DQ<2>
  J25    245  DQ_B2  SCONN288_ADR50001P013C01  I180
  J26    245  DQ_B2  SCONN288_ADR50001P003C01  I180
  U1     EG29  DDR4_SB_DQ2  SOCKET4677_AZIFS054P001C01   I7

M_E_CPU1_SB_DQ<3>   @S9S_MB_2U_LIB.S9S_MB_2U(SCH_1):M_E_CPU1_SB_DQ<3>
  J25    247  DQ_B3  SCONN288_ADR50001P013C01  I180
  J26    247  DQ_B3  SCONN288_ADR50001P003C01  I180
  U1     EH28  DDR4_SB_DQ3  SOCKET4677_AZIFS054P001C01   I7

M_E_CPU1_SB_DQ<4>   @S9S_MB_2U_LIB.S9S_MB_2U(SCH_1):M_E_CPU1_SB_DQ<4>
  J25    107  DQ_B4  SCONN288_ADR50001P013C01  I180
  J26    107  DQ_B4  SCONN288_ADR50001P003C01  I180
  U1     ED26  DDR4_SB_DQ4  SOCKET4677_AZIFS054P001C01   I7

M_E_CPU1_SB_DQ<5>   @S9S_MB_2U_LIB.S9S_MB_2U(SCH_1):M_E_CPU1_SB_DQ<5>
  J25    109  DQ_B5  SCONN288_ADR50001P013C01  I180
  J26    109  DQ_B5  SCONN288_ADR50001P003C01  I180
  U1     EE25  DDR4_SB_DQ5  SOCKET4677_AZIFS054P001C01   I7

M_E_CPU1_SB_DQ<6>   @S9S_MB_2U_LIB.S9S_MB_2U(SCH_1):M_E_CPU1_SB_DQ<6>
  J25    252  DQ_B6  SCONN288_ADR50001P013C01  I180
  J26    252  DQ_B6  SCONN288_ADR50001P003C01  I180
  U1     EH26  DDR4_SB_DQ6  SOCKET4677_AZIFS054P001C01   I7

M_E_CPU1_SB_DQ<7>   @S9S_MB_2U_LIB.S9S_MB_2U(SCH_1):M_E_CPU1_SB_DQ<7>
  J25    254  DQ_B7  SCONN288_ADR50001P013C01  I180
  J26    254  DQ_B7  SCONN288_ADR50001P003C01  I180
  U1     EG25  DDR4_SB_DQ7  SOCKET4677_AZIFS054P001C01   I7

M_E_CPU1_SB_DQ<8>   @S9S_MB_2U_LIB.S9S_MB_2U(SCH_1):M_E_CPU1_SB_DQ<8>
  J25    111  DQ_B8  SCONN288_ADR50001P013C01  I180
  J26    111  DQ_B8  SCONN288_ADR50001P003C01  I180
  U1     EM32  DDR4_SB_DQ8  SOCKET4677_AZIFS054P001C01   I7

M_E_CPU1_SB_DQ<9>   @S9S_MB_2U_LIB.S9S_MB_2U(SCH_1):M_E_CPU1_SB_DQ<9>
  J25    113  DQ_B9  SCONN288_ADR50001P013C01  I180
  J26    113  DQ_B9  SCONN288_ADR50001P003C01  I180
  U1     EL31  DDR4_SB_DQ9  SOCKET4677_AZIFS054P001C01   I7

M_E_CPU1_SB_DQ<10>   @S9S_MB_2U_LIB.S9S_MB_2U(SCH_1):M_E_CPU1_SB_DQ<10>
  J25    256  DQ_B10  SCONN288_ADR50001P013C01  I180
  J26    256  DQ_B10  SCONN288_ADR50001P003C01  I180
  U1     EP32  DDR4_SB_DQ10  SOCKET4677_AZIFS054P001C01   I7

M_E_CPU1_SB_DQ<11>   @S9S_MB_2U_LIB.S9S_MB_2U(SCH_1):M_E_CPU1_SB_DQ<11>
  J25    258  DQ_B11  SCONN288_ADR50001P013C01  I180
  J26    258  DQ_B11  SCONN288_ADR50001P003C01  I180
  U1     ER31  DDR4_SB_DQ11  SOCKET4677_AZIFS054P001C01   I7

M_E_CPU1_SB_DQ<12>   @S9S_MB_2U_LIB.S9S_MB_2U(SCH_1):M_E_CPU1_SB_DQ<12>
  J25    118  DQ_B12  SCONN288_ADR50001P013C01  I180
  J26    118  DQ_B12  SCONN288_ADR50001P003C01  I180
  U1     EL29  DDR4_SB_DQ12  SOCKET4677_AZIFS054P001C01   I7

M_E_CPU1_SB_DQ<13>   @S9S_MB_2U_LIB.S9S_MB_2U(SCH_1):M_E_CPU1_SB_DQ<13>
  J25    120  DQ_B13  SCONN288_ADR50001P013C01  I180
  J26    120  DQ_B13  SCONN288_ADR50001P003C01  I180
  U1     EM28  DDR4_SB_DQ13  SOCKET4677_AZIFS054P001C01   I7

M_E_CPU1_SB_DQ<14>   @S9S_MB_2U_LIB.S9S_MB_2U(SCH_1):M_E_CPU1_SB_DQ<14>
  J25    263  DQ_B14  SCONN288_ADR50001P013C01  I180
  J26    263  DQ_B14  SCONN288_ADR50001P003C01  I180
  U1     ER29  DDR4_SB_DQ14  SOCKET4677_AZIFS054P001C01   I7

M_E_CPU1_SB_DQ<15>   @S9S_MB_2U_LIB.S9S_MB_2U(SCH_1):M_E_CPU1_SB_DQ<15>
  J25    265  DQ_B15  SCONN288_ADR50001P013C01  I180
  J26    265  DQ_B15  SCONN288_ADR50001P003C01  I180
  U1     EP28  DDR4_SB_DQ15  SOCKET4677_AZIFS054P001C01   I7

M_E_CPU1_SB_DQ<16>   @S9S_MB_2U_LIB.S9S_MB_2U(SCH_1):M_E_CPU1_SB_DQ<16>
  J25    122  DQ_B16  SCONN288_ADR50001P013C01  I180
  J26    122  DQ_B16  SCONN288_ADR50001P003C01  I180
  U1     EM26  DDR4_SB_DQ16  SOCKET4677_AZIFS054P001C01   I7

M_E_CPU1_SB_DQ<17>   @S9S_MB_2U_LIB.S9S_MB_2U(SCH_1):M_E_CPU1_SB_DQ<17>
  J25    124  DQ_B17  SCONN288_ADR50001P013C01  I180
  J26    124  DQ_B17  SCONN288_ADR50001P003C01  I180
  U1     EL25  DDR4_SB_DQ17  SOCKET4677_AZIFS054P001C01   I7

M_E_CPU1_SB_DQ<18>   @S9S_MB_2U_LIB.S9S_MB_2U(SCH_1):M_E_CPU1_SB_DQ<18>
  J25    267  DQ_B18  SCONN288_ADR50001P013C01  I180
  J26    267  DQ_B18  SCONN288_ADR50001P003C01  I180
  U1     EP26  DDR4_SB_DQ18  SOCKET4677_AZIFS054P001C01   I7

M_E_CPU1_SB_DQ<19>   @S9S_MB_2U_LIB.S9S_MB_2U(SCH_1):M_E_CPU1_SB_DQ<19>
  J25    269  DQ_B19  SCONN288_ADR50001P013C01  I180
  J26    269  DQ_B19  SCONN288_ADR50001P003C01  I180
  U1     ER25  DDR4_SB_DQ19  SOCKET4677_AZIFS054P001C01   I7

M_E_CPU1_SB_DQ<20>   @S9S_MB_2U_LIB.S9S_MB_2U(SCH_1):M_E_CPU1_SB_DQ<20>
  J25    129  DQ_B20  SCONN288_ADR50001P013C01  I180
  J26    129  DQ_B20  SCONN288_ADR50001P003C01  I180
  U1     EL23  DDR4_SB_DQ20  SOCKET4677_AZIFS054P001C01   I7

M_E_CPU1_SB_DQ<21>   @S9S_MB_2U_LIB.S9S_MB_2U(SCH_1):M_E_CPU1_SB_DQ<21>
  J25    131  DQ_B21  SCONN288_ADR50001P013C01  I180
  J26    131  DQ_B21  SCONN288_ADR50001P003C01  I180
  U1     EM22  DDR4_SB_DQ21  SOCKET4677_AZIFS054P001C01   I7

M_E_CPU1_SB_DQ<22>   @S9S_MB_2U_LIB.S9S_MB_2U(SCH_1):M_E_CPU1_SB_DQ<22>
  J25    274  DQ_B22  SCONN288_ADR50001P013C01  I180
  J26    274  DQ_B22  SCONN288_ADR50001P003C01  I180
  U1     ER23  DDR4_SB_DQ22  SOCKET4677_AZIFS054P001C01   I7

M_E_CPU1_SB_DQ<23>   @S9S_MB_2U_LIB.S9S_MB_2U(SCH_1):M_E_CPU1_SB_DQ<23>
  J25    276  DQ_B23  SCONN288_ADR50001P013C01  I180
  J26    276  DQ_B23  SCONN288_ADR50001P003C01  I180
  U1     EP22  DDR4_SB_DQ23  SOCKET4677_AZIFS054P001C01   I7

M_E_CPU1_SB_DQ<24>   @S9S_MB_2U_LIB.S9S_MB_2U(SCH_1):M_E_CPU1_SB_DQ<24>
  J25    133  DQ_B24  SCONN288_ADR50001P013C01  I180
  J26    133  DQ_B24  SCONN288_ADR50001P003C01  I180
  U1     EM20  DDR4_SB_DQ24  SOCKET4677_AZIFS054P001C01   I7

M_E_CPU1_SB_DQ<25>   @S9S_MB_2U_LIB.S9S_MB_2U(SCH_1):M_E_CPU1_SB_DQ<25>
  J25    135  DQ_B25  SCONN288_ADR50001P013C01  I180
  J26    135  DQ_B25  SCONN288_ADR50001P003C01  I180
  U1     EL19  DDR4_SB_DQ25  SOCKET4677_AZIFS054P001C01   I7

M_E_CPU1_SB_DQ<26>   @S9S_MB_2U_LIB.S9S_MB_2U(SCH_1):M_E_CPU1_SB_DQ<26>
  J25    278  DQ_B26  SCONN288_ADR50001P013C01  I180
  J26    278  DQ_B26  SCONN288_ADR50001P003C01  I180
  U1     EP20  DDR4_SB_DQ26  SOCKET4677_AZIFS054P001C01   I7

M_E_CPU1_SB_DQ<27>   @S9S_MB_2U_LIB.S9S_MB_2U(SCH_1):M_E_CPU1_SB_DQ<27>
  J25    280  DQ_B27  SCONN288_ADR50001P013C01  I180
  J26    280  DQ_B27  SCONN288_ADR50001P003C01  I180
  U1     ER19  DDR4_SB_DQ27  SOCKET4677_AZIFS054P001C01   I7

M_E_CPU1_SB_DQ<28>   @S9S_MB_2U_LIB.S9S_MB_2U(SCH_1):M_E_CPU1_SB_DQ<28>
  J25    140  DQ_B28  SCONN288_ADR50001P013C01  I180
  J26    140  DQ_B28  SCONN288_ADR50001P003C01  I180
  U1     EL17  DDR4_SB_DQ28  SOCKET4677_AZIFS054P001C01   I7

M_E_CPU1_SB_DQ<29>   @S9S_MB_2U_LIB.S9S_MB_2U(SCH_1):M_E_CPU1_SB_DQ<29>
  J25    142  DQ_B29  SCONN288_ADR50001P013C01  I180
  J26    142  DQ_B29  SCONN288_ADR50001P003C01  I180
  U1     EM16  DDR4_SB_DQ29  SOCKET4677_AZIFS054P001C01   I7

M_E_CPU1_SB_DQ<30>   @S9S_MB_2U_LIB.S9S_MB_2U(SCH_1):M_E_CPU1_SB_DQ<30>
  J25    285  DQ_B30  SCONN288_ADR50001P013C01  I180
  J26    285  DQ_B30  SCONN288_ADR50001P003C01  I180
  U1     ER17  DDR4_SB_DQ30  SOCKET4677_AZIFS054P001C01   I7

M_E_CPU1_SB_DQ<31>   @S9S_MB_2U_LIB.S9S_MB_2U(SCH_1):M_E_CPU1_SB_DQ<31>
  J25    287  DQ_B31  SCONN288_ADR50001P013C01  I180
  J26    287  DQ_B31  SCONN288_ADR50001P003C01  I180
  U1     EP16  DDR4_SB_DQ31  SOCKET4677_AZIFS054P001C01   I7

M_E_CPU1_SB_DQS_DN<0>   @S9S_MB_2U_LIB.S9S_MB_2U(SCH_1):M_E_CPU1_SB_DQS_DN<0>
  J25    105  DQS0_B_N  SCONN288_ADR50001P013C01  I179
  J26    105  DQS0_B_N  SCONN288_ADR50001P003C01  I178
  U1     EE27  DDR4_SB_DQS_DN0  SOCKET4677_AZIFS054P001C01   I7

M_E_CPU1_SB_DQS_DN<1>   @S9S_MB_2U_LIB.S9S_MB_2U(SCH_1):M_E_CPU1_SB_DQS_DN<1>
  J25    116  DQS1_B_N  SCONN288_ADR50001P013C01  I179
  J26    116  DQS1_B_N  SCONN288_ADR50001P003C01  I178
  U1     EK30  DDR4_SB_DQS_DN1  SOCKET4677_AZIFS054P001C01   I7

M_E_CPU1_SB_DQS_DN<2>   @S9S_MB_2U_LIB.S9S_MB_2U(SCH_1):M_E_CPU1_SB_DQS_DN<2>
  J25    127  DQS2_B_N  SCONN288_ADR50001P013C01  I179
  J26    127  DQS2_B_N  SCONN288_ADR50001P003C01  I178
  U1     EK24  DDR4_SB_DQS_DN2  SOCKET4677_AZIFS054P001C01   I7

M_E_CPU1_SB_DQS_DN<3>   @S9S_MB_2U_LIB.S9S_MB_2U(SCH_1):M_E_CPU1_SB_DQS_DN<3>
  J25    138  DQS3_B_N  SCONN288_ADR50001P013C01  I179
  J26    138  DQS3_B_N  SCONN288_ADR50001P003C01  I178
  U1     EK18  DDR4_SB_DQS_DN3  SOCKET4677_AZIFS054P001C01   I7

M_E_CPU1_SB_DQS_DN<4>   @S9S_MB_2U_LIB.S9S_MB_2U(SCH_1):M_E_CPU1_SB_DQS_DN<4>
  J25    238  DQS4_B_N  SCONN288_ADR50001P013C01  I179
  J26    238  DQS4_B_N  SCONN288_ADR50001P003C01  I178
  U1     ET36  DDR4_SB_DQS_DN4  SOCKET4677_AZIFS054P001C01   I7

M_E_CPU1_SB_DQS_DN<5>   @S9S_MB_2U_LIB.S9S_MB_2U(SCH_1):M_E_CPU1_SB_DQS_DN<5>
  J25    249  DQS5_B_N  SCONN288_ADR50001P013C01  I179
  J26    249  DQS5_B_N  SCONN288_ADR50001P003C01  I178
  U1     EJ27  DDR4_SB_DQS_DN5  SOCKET4677_AZIFS054P001C01   I7

M_E_CPU1_SB_DQS_DN<6>   @S9S_MB_2U_LIB.S9S_MB_2U(SCH_1):M_E_CPU1_SB_DQS_DN<6>
  J25    260  DQS6_B_N  SCONN288_ADR50001P013C01  I179
  J26    260  DQS6_B_N  SCONN288_ADR50001P003C01  I178
  U1     ET30  DDR4_SB_DQS_DN6  SOCKET4677_AZIFS054P001C01   I7

M_E_CPU1_SB_DQS_DN<7>   @S9S_MB_2U_LIB.S9S_MB_2U(SCH_1):M_E_CPU1_SB_DQS_DN<7>
  J25    271  DQS7_B_N  SCONN288_ADR50001P013C01  I179
  J26    271  DQS7_B_N  SCONN288_ADR50001P003C01  I178
  U1     ET24  DDR4_SB_DQS_DN7  SOCKET4677_AZIFS054P001C01   I7

M_E_CPU1_SB_DQS_DN<8>   @S9S_MB_2U_LIB.S9S_MB_2U(SCH_1):M_E_CPU1_SB_DQS_DN<8>
  J25    282  DQS8_B_N  SCONN288_ADR50001P013C01  I179
  J26    282  DQS8_B_N  SCONN288_ADR50001P003C01  I178
  U1     ET18  DDR4_SB_DQS_DN8  SOCKET4677_AZIFS054P001C01   I7

M_E_CPU1_SB_DQS_DN<9>   @S9S_MB_2U_LIB.S9S_MB_2U(SCH_1):M_E_CPU1_SB_DQS_DN<9>
  J25     94  DQS9_B_N  SCONN288_ADR50001P013C01  I179
  J26     94  DQS9_B_N  SCONN288_ADR50001P003C01  I178
  U1     EK36  DDR4_SB_DQS_DN9  SOCKET4677_AZIFS054P001C01   I7

M_E_CPU1_SB_DQS_DP<0>   @S9S_MB_2U_LIB.S9S_MB_2U(SCH_1):M_E_CPU1_SB_DQS_DP<0>
  J25    104  DQS0_B_P  SCONN288_ADR50001P013C01  I179
  J26    104  DQS0_B_P  SCONN288_ADR50001P003C01  I178
  U1     EC27  DDR4_SB_DQS_DP0  SOCKET4677_AZIFS054P001C01   I7

M_E_CPU1_SB_DQS_DP<1>   @S9S_MB_2U_LIB.S9S_MB_2U(SCH_1):M_E_CPU1_SB_DQS_DP<1>
  J25    115  DQS1_B_P  SCONN288_ADR50001P013C01  I179
  J26    115  DQS1_B_P  SCONN288_ADR50001P003C01  I178
  U1     EM30  DDR4_SB_DQS_DP1  SOCKET4677_AZIFS054P001C01   I7

M_E_CPU1_SB_DQS_DP<2>   @S9S_MB_2U_LIB.S9S_MB_2U(SCH_1):M_E_CPU1_SB_DQS_DP<2>
  J25    126  DQS2_B_P  SCONN288_ADR50001P013C01  I179
  J26    126  DQS2_B_P  SCONN288_ADR50001P003C01  I178
  U1     EM24  DDR4_SB_DQS_DP2  SOCKET4677_AZIFS054P001C01   I7

M_E_CPU1_SB_DQS_DP<3>   @S9S_MB_2U_LIB.S9S_MB_2U(SCH_1):M_E_CPU1_SB_DQS_DP<3>
  J25    137  DQS3_B_P  SCONN288_ADR50001P013C01  I179
  J26    137  DQS3_B_P  SCONN288_ADR50001P003C01  I178
  U1     EM18  DDR4_SB_DQS_DP3  SOCKET4677_AZIFS054P001C01   I7

M_E_CPU1_SB_DQS_DP<4>   @S9S_MB_2U_LIB.S9S_MB_2U(SCH_1):M_E_CPU1_SB_DQS_DP<4>
  J25    239  DQS4_B_P  SCONN288_ADR50001P013C01  I179
  J26    239  DQS4_B_P  SCONN288_ADR50001P003C01  I178
  U1     EP36  DDR4_SB_DQS_DP4  SOCKET4677_AZIFS054P001C01   I7

M_E_CPU1_SB_DQS_DP<5>   @S9S_MB_2U_LIB.S9S_MB_2U(SCH_1):M_E_CPU1_SB_DQS_DP<5>
  J25    250  DQS5_B_P  SCONN288_ADR50001P013C01  I179
  J26    250  DQS5_B_P  SCONN288_ADR50001P003C01  I178
  U1     EG27  DDR4_SB_DQS_DP5  SOCKET4677_AZIFS054P001C01   I7

M_E_CPU1_SB_DQS_DP<6>   @S9S_MB_2U_LIB.S9S_MB_2U(SCH_1):M_E_CPU1_SB_DQS_DP<6>
  J25    261  DQS6_B_P  SCONN288_ADR50001P013C01  I179
  J26    261  DQS6_B_P  SCONN288_ADR50001P003C01  I178
  U1     EP30  DDR4_SB_DQS_DP6  SOCKET4677_AZIFS054P001C01   I7

M_E_CPU1_SB_DQS_DP<7>   @S9S_MB_2U_LIB.S9S_MB_2U(SCH_1):M_E_CPU1_SB_DQS_DP<7>
  J25    272  DQS7_B_P  SCONN288_ADR50001P013C01  I179
  J26    272  DQS7_B_P  SCONN288_ADR50001P003C01  I178
  U1     EP24  DDR4_SB_DQS_DP7  SOCKET4677_AZIFS054P001C01   I7

M_E_CPU1_SB_DQS_DP<8>   @S9S_MB_2U_LIB.S9S_MB_2U(SCH_1):M_E_CPU1_SB_DQS_DP<8>
  J25    283  DQS8_B_P  SCONN288_ADR50001P013C01  I179
  J26    283  DQS8_B_P  SCONN288_ADR50001P003C01  I178
  U1     EP18  DDR4_SB_DQS_DP8  SOCKET4677_AZIFS054P001C01   I7

M_E_CPU1_SB_DQS_DP<9>   @S9S_MB_2U_LIB.S9S_MB_2U(SCH_1):M_E_CPU1_SB_DQS_DP<9>
  J25     93  DQS9_B_P  SCONN288_ADR50001P013C01  I179
  J26     93  DQS9_B_P  SCONN288_ADR50001P003C01  I178
  U1     EM36  DDR4_SB_DQS_DP9  SOCKET4677_AZIFS054P001C01   I7

M_E_CPU1_SB_PAR   @S9S_MB_2U_LIB.S9S_MB_2U(SCH_1):M_E_CPU1_SB_PAR
  J25    227  PAR_B  SCONN288_ADR50001P013C01  I180
  J26    227  PAR_B  SCONN288_ADR50001P003C01  I180
  U1     EP42  DDR4_SB_PAR  SOCKET4677_AZIFS054P001C01   I7

M_E_CPU1_SB_RSP<0>   @S9S_MB_2U_LIB.S9S_MB_2U(SCH_1):M_E_CPU1_SB_RSP<0>
  J25     87  LBS||RSP_N_B  SCONN288_ADR50001P013C01  I180
  U1     DF44  DDR4_B_RSP0  SOCKET4677_AZIFS054P001C01   I7

M_E_CPU1_SB_RSP<1>   @S9S_MB_2U_LIB.S9S_MB_2U(SCH_1):M_E_CPU1_SB_RSP<1>
  J26     87  LBS||RSP_N_B  SCONN288_ADR50001P003C01  I180
  U1     DG43  DDR4_B_RSP1  SOCKET4677_AZIFS054P001C01   I7

M_F_CPU0_ALERT_N   @S9S_MB_2U_LIB.S9S_MB_2U(SCH_1):M_F_CPU0_ALERT_N
  J11     62  ALERT_N  SCONN288_ADR50001P013C01  I25
  J12     62  ALERT_N  SCONN288_ADR50001P003C01  I24
  U2     CW48  DDR5_ALERT_N  SOCKET4677_AZIFS054P001C01  I169

M_F_CPU0_CLK_DN<0>   @S9S_MB_2U_LIB.S9S_MB_2U(SCH_1):M_F_CPU0_CLK_DN<0>
  J11    218   CK_N  SCONN288_ADR50001P013C01  I25
  U2     DY49  DDR5_CLK_DN0  SOCKET4677_AZIFS054P001C01  I169

M_F_CPU0_CLK_DN<1>   @S9S_MB_2U_LIB.S9S_MB_2U(SCH_1):M_F_CPU0_CLK_DN<1>
  J12    218   CK_N  SCONN288_ADR50001P003C01  I24
  U2     DV49  DDR5_CLK_DN1  SOCKET4677_AZIFS054P001C01  I169

M_F_CPU0_CLK_DP<0>   @S9S_MB_2U_LIB.S9S_MB_2U(SCH_1):M_F_CPU0_CLK_DP<0>
  J11    217   CK_P  SCONN288_ADR50001P013C01  I25
  U2     EB49  DDR5_CLK_DP0  SOCKET4677_AZIFS054P001C01  I169

M_F_CPU0_CLK_DP<1>   @S9S_MB_2U_LIB.S9S_MB_2U(SCH_1):M_F_CPU0_CLK_DP<1>
  J12    217   CK_P  SCONN288_ADR50001P003C01  I24
  U2     DT49  DDR5_CLK_DP1  SOCKET4677_AZIFS054P001C01  I169

M_F_CPU0_SA_CA<0>   @S9S_MB_2U_LIB.S9S_MB_2U(SCH_1):M_F_CPU0_SA_CA<0>
  J11     66  CA0_A  SCONN288_ADR50001P013C01  I25
  J12     66  CA0_A  SCONN288_ADR50001P003C01  I24
  U2     EC52  DDR5_SA_CA0  SOCKET4677_AZIFS054P001C01  I169

M_F_CPU0_SA_CA<1>   @S9S_MB_2U_LIB.S9S_MB_2U(SCH_1):M_F_CPU0_SA_CA<1>
  J11    211  CA1_A  SCONN288_ADR50001P013C01  I25
  J12    211  CA1_A  SCONN288_ADR50001P003C01  I24
  U2     EJ52  DDR5_SA_CA1  SOCKET4677_AZIFS054P001C01  I169

M_F_CPU0_SA_CA<2>   @S9S_MB_2U_LIB.S9S_MB_2U(SCH_1):M_F_CPU0_SA_CA<2>
  J11     68  CA2_A  SCONN288_ADR50001P013C01  I25
  J12     68  CA2_A  SCONN288_ADR50001P003C01  I24
  U2     ED51  DDR5_SA_CA2  SOCKET4677_AZIFS054P001C01  I169

M_F_CPU0_SA_CA<3>   @S9S_MB_2U_LIB.S9S_MB_2U(SCH_1):M_F_CPU0_SA_CA<3>
  J11    213  CA3_A  SCONN288_ADR50001P013C01  I25
  J12    213  CA3_A  SCONN288_ADR50001P003C01  I24
  U2     EH51  DDR5_SA_CA3  SOCKET4677_AZIFS054P001C01  I169

M_F_CPU0_SA_CA<4>   @S9S_MB_2U_LIB.S9S_MB_2U(SCH_1):M_F_CPU0_SA_CA<4>
  J11     70  CA4_A  SCONN288_ADR50001P013C01  I25
  J12     70  CA4_A  SCONN288_ADR50001P003C01  I24
  U2     EE50  DDR5_SA_CA4  SOCKET4677_AZIFS054P001C01  I169

M_F_CPU0_SA_CA<5>   @S9S_MB_2U_LIB.S9S_MB_2U(SCH_1):M_F_CPU0_SA_CA<5>
  J11    215  CA5_A  SCONN288_ADR50001P013C01  I25
  J12    215  CA5_A  SCONN288_ADR50001P003C01  I24
  U2     EG50  DDR5_SA_CA5  SOCKET4677_AZIFS054P001C01  I169

M_F_CPU0_SA_CA<6>   @S9S_MB_2U_LIB.S9S_MB_2U(SCH_1):M_F_CPU0_SA_CA<6>
  J11     72  CA6_A  SCONN288_ADR50001P013C01  I25
  J12     72  CA6_A  SCONN288_ADR50001P003C01  I24
  U2     DY51  DDR5_SA_CA6  SOCKET4677_AZIFS054P001C01  I169

M_F_CPU0_SA_CB<0>   @S9S_MB_2U_LIB.S9S_MB_2U(SCH_1):M_F_CPU0_SA_CB<0>
  J11     51  CB_A0  SCONN288_ADR50001P013C01  I25
  J12     51  CB_A0  SCONN288_ADR50001P003C01  I24
  U2     EE60  DDR5_SA_ECC0  SOCKET4677_AZIFS054P001C01  I169

M_F_CPU0_SA_CB<1>   @S9S_MB_2U_LIB.S9S_MB_2U(SCH_1):M_F_CPU0_SA_CB<1>
  J11     53  CB_A1  SCONN288_ADR50001P013C01  I25
  J12     53  CB_A1  SCONN288_ADR50001P003C01  I24
  U2     ED59  DDR5_SA_ECC1  SOCKET4677_AZIFS054P001C01  I169

M_F_CPU0_SA_CB<2>   @S9S_MB_2U_LIB.S9S_MB_2U(SCH_1):M_F_CPU0_SA_CB<2>
  J11    196  CB_A2  SCONN288_ADR50001P013C01  I25
  J12    196  CB_A2  SCONN288_ADR50001P003C01  I24
  U2     EG60  DDR5_SA_ECC2  SOCKET4677_AZIFS054P001C01  I169

M_F_CPU0_SA_CB<3>   @S9S_MB_2U_LIB.S9S_MB_2U(SCH_1):M_F_CPU0_SA_CB<3>
  J11    198  CB_A3  SCONN288_ADR50001P013C01  I25
  J12    198  CB_A3  SCONN288_ADR50001P003C01  I24
  U2     EH59  DDR5_SA_ECC3  SOCKET4677_AZIFS054P001C01  I169

M_F_CPU0_SA_CB<4>   @S9S_MB_2U_LIB.S9S_MB_2U(SCH_1):M_F_CPU0_SA_CB<4>
  J11     58  CB_A4  SCONN288_ADR50001P013C01  I25
  J12     58  CB_A4  SCONN288_ADR50001P003C01  I24
  U2     ED57  DDR5_SA_ECC4  SOCKET4677_AZIFS054P001C01  I169

M_F_CPU0_SA_CB<5>   @S9S_MB_2U_LIB.S9S_MB_2U(SCH_1):M_F_CPU0_SA_CB<5>
  J11     60  CB_A5  SCONN288_ADR50001P013C01  I25
  J12     60  CB_A5  SCONN288_ADR50001P003C01  I24
  U2     EE56  DDR5_SA_ECC5  SOCKET4677_AZIFS054P001C01  I169

M_F_CPU0_SA_CB<6>   @S9S_MB_2U_LIB.S9S_MB_2U(SCH_1):M_F_CPU0_SA_CB<6>
  J11    203  CB_A6  SCONN288_ADR50001P013C01  I25
  J12    203  CB_A6  SCONN288_ADR50001P003C01  I24
  U2     EH57  DDR5_SA_ECC6  SOCKET4677_AZIFS054P001C01  I169

M_F_CPU0_SA_CB<7>   @S9S_MB_2U_LIB.S9S_MB_2U(SCH_1):M_F_CPU0_SA_CB<7>
  J11    205  CB_A7  SCONN288_ADR50001P013C01  I25
  J12    205  CB_A7  SCONN288_ADR50001P003C01  I24
  U2     EG56  DDR5_SA_ECC7  SOCKET4677_AZIFS054P001C01  I169

M_F_CPU0_SA_CS_N<0>   @S9S_MB_2U_LIB.S9S_MB_2U(SCH_1):M_F_CPU0_SA_CS_N<0>
  J11     64  CS0_N_A  SCONN288_ADR50001P013C01  I25
  U2     EG54  DDR5_SA_CS0_N  SOCKET4677_AZIFS054P001C01  I169

M_F_CPU0_SA_CS_N<1>   @S9S_MB_2U_LIB.S9S_MB_2U(SCH_1):M_F_CPU0_SA_CS_N<1>
  J11    209  CS1_N_A  SCONN288_ADR50001P013C01  I25
  U2     EH53  DDR5_SA_CS1_N  SOCKET4677_AZIFS054P001C01  I169

M_F_CPU0_SA_CS_N<2>   @S9S_MB_2U_LIB.S9S_MB_2U(SCH_1):M_F_CPU0_SA_CS_N<2>
  J12     64  CS0_N_A  SCONN288_ADR50001P003C01  I24
  U2     EE54  DDR5_SA_CS2_N  SOCKET4677_AZIFS054P001C01  I169

M_F_CPU0_SA_CS_N<3>   @S9S_MB_2U_LIB.S9S_MB_2U(SCH_1):M_F_CPU0_SA_CS_N<3>
  J12    209  CS1_N_A  SCONN288_ADR50001P003C01  I24
  U2     ED53  DDR5_SA_CS3_N  SOCKET4677_AZIFS054P001C01  I169

M_F_CPU0_SA_DQ<0>   @S9S_MB_2U_LIB.S9S_MB_2U(SCH_1):M_F_CPU0_SA_DQ<0>
  J11      7  DQ_A0  SCONN288_ADR50001P013C01  I25
  J12      7  DQ_A0  SCONN288_ADR50001P003C01  I24
  U2     EB77  DDR5_SA_DQ0  SOCKET4677_AZIFS054P001C01  I169

M_F_CPU0_SA_DQ<1>   @S9S_MB_2U_LIB.S9S_MB_2U(SCH_1):M_F_CPU0_SA_DQ<1>
  J11      9  DQ_A1  SCONN288_ADR50001P013C01  I25
  J12      9  DQ_A1  SCONN288_ADR50001P003C01  I24
  U2     EH77  DDR5_SA_DQ1  SOCKET4677_AZIFS054P001C01  I169

M_F_CPU0_SA_DQ<2>   @S9S_MB_2U_LIB.S9S_MB_2U(SCH_1):M_F_CPU0_SA_DQ<2>
  J11    152  DQ_A2  SCONN288_ADR50001P013C01  I25
  J12    152  DQ_A2  SCONN288_ADR50001P003C01  I24
  U2     ED77  DDR5_SA_DQ2  SOCKET4677_AZIFS054P001C01  I169

M_F_CPU0_SA_DQ<3>   @S9S_MB_2U_LIB.S9S_MB_2U(SCH_1):M_F_CPU0_SA_DQ<3>
  J11    154  DQ_A3  SCONN288_ADR50001P013C01  I25
  J12    154  DQ_A3  SCONN288_ADR50001P003C01  I24
  U2     EG78  DDR5_SA_DQ3  SOCKET4677_AZIFS054P001C01  I169

M_F_CPU0_SA_DQ<4>   @S9S_MB_2U_LIB.S9S_MB_2U(SCH_1):M_F_CPU0_SA_DQ<4>
  J11     14  DQ_A4  SCONN288_ADR50001P013C01  I25
  J12     14  DQ_A4  SCONN288_ADR50001P003C01  I24
  U2     ED75  DDR5_SA_DQ4  SOCKET4677_AZIFS054P001C01  I169

M_F_CPU0_SA_DQ<5>   @S9S_MB_2U_LIB.S9S_MB_2U(SCH_1):M_F_CPU0_SA_DQ<5>
  J11     16  DQ_A5  SCONN288_ADR50001P013C01  I25
  J12     16  DQ_A5  SCONN288_ADR50001P003C01  I24
  U2     EE74  DDR5_SA_DQ5  SOCKET4677_AZIFS054P001C01  I169

M_F_CPU0_SA_DQ<6>   @S9S_MB_2U_LIB.S9S_MB_2U(SCH_1):M_F_CPU0_SA_DQ<6>
  J11    159  DQ_A6  SCONN288_ADR50001P013C01  I25
  J12    159  DQ_A6  SCONN288_ADR50001P003C01  I24
  U2     EH75  DDR5_SA_DQ6  SOCKET4677_AZIFS054P001C01  I169

M_F_CPU0_SA_DQ<7>   @S9S_MB_2U_LIB.S9S_MB_2U(SCH_1):M_F_CPU0_SA_DQ<7>
  J11    161  DQ_A7  SCONN288_ADR50001P013C01  I25
  J12    161  DQ_A7  SCONN288_ADR50001P003C01  I24
  U2     EG74  DDR5_SA_DQ7  SOCKET4677_AZIFS054P001C01  I169

M_F_CPU0_SA_DQ<8>   @S9S_MB_2U_LIB.S9S_MB_2U(SCH_1):M_F_CPU0_SA_DQ<8>
  J11     18  DQ_A8  SCONN288_ADR50001P013C01  I25
  J12     18  DQ_A8  SCONN288_ADR50001P003C01  I24
  U2     DV69  DDR5_SA_DQ8  SOCKET4677_AZIFS054P001C01  I169

M_F_CPU0_SA_DQ<9>   @S9S_MB_2U_LIB.S9S_MB_2U(SCH_1):M_F_CPU0_SA_DQ<9>
  J11     20  DQ_A9  SCONN288_ADR50001P013C01  I25
  J12     20  DQ_A9  SCONN288_ADR50001P003C01  I24
  U2     DU68  DDR5_SA_DQ9  SOCKET4677_AZIFS054P001C01  I169

M_F_CPU0_SA_DQ<10>   @S9S_MB_2U_LIB.S9S_MB_2U(SCH_1):M_F_CPU0_SA_DQ<10>
  J11    163  DQ_A10  SCONN288_ADR50001P013C01  I25
  J12    163  DQ_A10  SCONN288_ADR50001P003C01  I24
  U2     DY69  DDR5_SA_DQ10  SOCKET4677_AZIFS054P001C01  I169

M_F_CPU0_SA_DQ<11>   @S9S_MB_2U_LIB.S9S_MB_2U(SCH_1):M_F_CPU0_SA_DQ<11>
  J11    165  DQ_A11  SCONN288_ADR50001P013C01  I25
  J12    165  DQ_A11  SCONN288_ADR50001P003C01  I24
  U2     EA68  DDR5_SA_DQ11  SOCKET4677_AZIFS054P001C01  I169

M_F_CPU0_SA_DQ<12>   @S9S_MB_2U_LIB.S9S_MB_2U(SCH_1):M_F_CPU0_SA_DQ<12>
  J11     25  DQ_A12  SCONN288_ADR50001P013C01  I25
  J12     25  DQ_A12  SCONN288_ADR50001P003C01  I24
  U2     DU66  DDR5_SA_DQ12  SOCKET4677_AZIFS054P001C01  I169

M_F_CPU0_SA_DQ<13>   @S9S_MB_2U_LIB.S9S_MB_2U(SCH_1):M_F_CPU0_SA_DQ<13>
  J11     27  DQ_A13  SCONN288_ADR50001P013C01  I25
  J12     27  DQ_A13  SCONN288_ADR50001P003C01  I24
  U2     DV65  DDR5_SA_DQ13  SOCKET4677_AZIFS054P001C01  I169

M_F_CPU0_SA_DQ<14>   @S9S_MB_2U_LIB.S9S_MB_2U(SCH_1):M_F_CPU0_SA_DQ<14>
  J11    170  DQ_A14  SCONN288_ADR50001P013C01  I25
  J12    170  DQ_A14  SCONN288_ADR50001P003C01  I24
  U2     EA66  DDR5_SA_DQ14  SOCKET4677_AZIFS054P001C01  I169

M_F_CPU0_SA_DQ<15>   @S9S_MB_2U_LIB.S9S_MB_2U(SCH_1):M_F_CPU0_SA_DQ<15>
  J11    172  DQ_A15  SCONN288_ADR50001P013C01  I25
  J12    172  DQ_A15  SCONN288_ADR50001P003C01  I24
  U2     DY65  DDR5_SA_DQ15  SOCKET4677_AZIFS054P001C01  I169

M_F_CPU0_SA_DQ<16>   @S9S_MB_2U_LIB.S9S_MB_2U(SCH_1):M_F_CPU0_SA_DQ<16>
  J11     29  DQ_A16  SCONN288_ADR50001P013C01  I25
  J12     29  DQ_A16  SCONN288_ADR50001P003C01  I24
  U2     EE66  DDR5_SA_DQ16  SOCKET4677_AZIFS054P001C01  I169

M_F_CPU0_SA_DQ<17>   @S9S_MB_2U_LIB.S9S_MB_2U(SCH_1):M_F_CPU0_SA_DQ<17>
  J11     31  DQ_A17  SCONN288_ADR50001P013C01  I25
  J12     31  DQ_A17  SCONN288_ADR50001P003C01  I24
  U2     ED65  DDR5_SA_DQ17  SOCKET4677_AZIFS054P001C01  I169

M_F_CPU0_SA_DQ<18>   @S9S_MB_2U_LIB.S9S_MB_2U(SCH_1):M_F_CPU0_SA_DQ<18>
  J11    174  DQ_A18  SCONN288_ADR50001P013C01  I25
  J12    174  DQ_A18  SCONN288_ADR50001P003C01  I24
  U2     EG66  DDR5_SA_DQ18  SOCKET4677_AZIFS054P001C01  I169

M_F_CPU0_SA_DQ<19>   @S9S_MB_2U_LIB.S9S_MB_2U(SCH_1):M_F_CPU0_SA_DQ<19>
  J11    176  DQ_A19  SCONN288_ADR50001P013C01  I25
  J12    176  DQ_A19  SCONN288_ADR50001P003C01  I24
  U2     EH65  DDR5_SA_DQ19  SOCKET4677_AZIFS054P001C01  I169

M_F_CPU0_SA_DQ<20>   @S9S_MB_2U_LIB.S9S_MB_2U(SCH_1):M_F_CPU0_SA_DQ<20>
  J11     36  DQ_A20  SCONN288_ADR50001P013C01  I25
  J12     36  DQ_A20  SCONN288_ADR50001P003C01  I24
  U2     ED63  DDR5_SA_DQ20  SOCKET4677_AZIFS054P001C01  I169

M_F_CPU0_SA_DQ<21>   @S9S_MB_2U_LIB.S9S_MB_2U(SCH_1):M_F_CPU0_SA_DQ<21>
  J11     38  DQ_A21  SCONN288_ADR50001P013C01  I25
  J12     38  DQ_A21  SCONN288_ADR50001P003C01  I24
  U2     EE62  DDR5_SA_DQ21  SOCKET4677_AZIFS054P001C01  I169

M_F_CPU0_SA_DQ<22>   @S9S_MB_2U_LIB.S9S_MB_2U(SCH_1):M_F_CPU0_SA_DQ<22>
  J11    181  DQ_A22  SCONN288_ADR50001P013C01  I25
  J12    181  DQ_A22  SCONN288_ADR50001P003C01  I24
  U2     EH63  DDR5_SA_DQ22  SOCKET4677_AZIFS054P001C01  I169

M_F_CPU0_SA_DQ<23>   @S9S_MB_2U_LIB.S9S_MB_2U(SCH_1):M_F_CPU0_SA_DQ<23>
  J11    183  DQ_A23  SCONN288_ADR50001P013C01  I25
  J12    183  DQ_A23  SCONN288_ADR50001P003C01  I24
  U2     EG62  DDR5_SA_DQ23  SOCKET4677_AZIFS054P001C01  I169

M_F_CPU0_SA_DQ<24>   @S9S_MB_2U_LIB.S9S_MB_2U(SCH_1):M_F_CPU0_SA_DQ<24>
  J11     40  DQ_A24  SCONN288_ADR50001P013C01  I25
  J12     40  DQ_A24  SCONN288_ADR50001P003C01  I24
  U2     DV57  DDR5_SA_DQ24  SOCKET4677_AZIFS054P001C01  I169

M_F_CPU0_SA_DQ<25>   @S9S_MB_2U_LIB.S9S_MB_2U(SCH_1):M_F_CPU0_SA_DQ<25>
  J11     42  DQ_A25  SCONN288_ADR50001P013C01  I25
  J12     42  DQ_A25  SCONN288_ADR50001P003C01  I24
  U2     DU56  DDR5_SA_DQ25  SOCKET4677_AZIFS054P001C01  I169

M_F_CPU0_SA_DQ<26>   @S9S_MB_2U_LIB.S9S_MB_2U(SCH_1):M_F_CPU0_SA_DQ<26>
  J11    185  DQ_A26  SCONN288_ADR50001P013C01  I25
  J12    185  DQ_A26  SCONN288_ADR50001P003C01  I24
  U2     DY57  DDR5_SA_DQ26  SOCKET4677_AZIFS054P001C01  I169

M_F_CPU0_SA_DQ<27>   @S9S_MB_2U_LIB.S9S_MB_2U(SCH_1):M_F_CPU0_SA_DQ<27>
  J11    187  DQ_A27  SCONN288_ADR50001P013C01  I25
  J12    187  DQ_A27  SCONN288_ADR50001P003C01  I24
  U2     EA56  DDR5_SA_DQ27  SOCKET4677_AZIFS054P001C01  I169

M_F_CPU0_SA_DQ<28>   @S9S_MB_2U_LIB.S9S_MB_2U(SCH_1):M_F_CPU0_SA_DQ<28>
  J11     47  DQ_A28  SCONN288_ADR50001P013C01  I25
  J12     47  DQ_A28  SCONN288_ADR50001P003C01  I24
  U2     DU54  DDR5_SA_DQ28  SOCKET4677_AZIFS054P001C01  I169

M_F_CPU0_SA_DQ<29>   @S9S_MB_2U_LIB.S9S_MB_2U(SCH_1):M_F_CPU0_SA_DQ<29>
  J11     49  DQ_A29  SCONN288_ADR50001P013C01  I25
  J12     49  DQ_A29  SCONN288_ADR50001P003C01  I24
  U2     DV53  DDR5_SA_DQ29  SOCKET4677_AZIFS054P001C01  I169

M_F_CPU0_SA_DQ<30>   @S9S_MB_2U_LIB.S9S_MB_2U(SCH_1):M_F_CPU0_SA_DQ<30>
  J11    192  DQ_A30  SCONN288_ADR50001P013C01  I25
  J12    192  DQ_A30  SCONN288_ADR50001P003C01  I24
  U2     EA54  DDR5_SA_DQ30  SOCKET4677_AZIFS054P001C01  I169

M_F_CPU0_SA_DQ<31>   @S9S_MB_2U_LIB.S9S_MB_2U(SCH_1):M_F_CPU0_SA_DQ<31>
  J11    194  DQ_A31  SCONN288_ADR50001P013C01  I25
  J12    194  DQ_A31  SCONN288_ADR50001P003C01  I24
  U2     DY53  DDR5_SA_DQ31  SOCKET4677_AZIFS054P001C01  I169

M_F_CPU0_SA_DQS_DN<0>   @S9S_MB_2U_LIB.S9S_MB_2U(SCH_1):M_F_CPU0_SA_DQS_DN<0>
  J11     12  DQS0_A_N  SCONN288_ADR50001P013C01  I126
  J12     12  DQS0_A_N  SCONN288_ADR50001P003C01  I125
  U2     EE76  DDR5_SA_DQS_DN0  SOCKET4677_AZIFS054P001C01  I169

M_F_CPU0_SA_DQS_DN<1>   @S9S_MB_2U_LIB.S9S_MB_2U(SCH_1):M_F_CPU0_SA_DQS_DN<1>
  J11     23  DQS1_A_N  SCONN288_ADR50001P013C01  I126
  J12     23  DQS1_A_N  SCONN288_ADR50001P003C01  I125
  U2     DT67  DDR5_SA_DQS_DN1  SOCKET4677_AZIFS054P001C01  I169

M_F_CPU0_SA_DQS_DN<2>   @S9S_MB_2U_LIB.S9S_MB_2U(SCH_1):M_F_CPU0_SA_DQS_DN<2>
  J11     34  DQS2_A_N  SCONN288_ADR50001P013C01  I126
  J12     34  DQS2_A_N  SCONN288_ADR50001P003C01  I125
  U2     EC64  DDR5_SA_DQS_DN2  SOCKET4677_AZIFS054P001C01  I169

M_F_CPU0_SA_DQS_DN<3>   @S9S_MB_2U_LIB.S9S_MB_2U(SCH_1):M_F_CPU0_SA_DQS_DN<3>
  J11     45  DQS3_A_N  SCONN288_ADR50001P013C01  I126
  J12     45  DQS3_A_N  SCONN288_ADR50001P003C01  I125
  U2     DV55  DDR5_SA_DQS_DN3  SOCKET4677_AZIFS054P001C01  I169

M_F_CPU0_SA_DQS_DN<4>   @S9S_MB_2U_LIB.S9S_MB_2U(SCH_1):M_F_CPU0_SA_DQS_DN<4>
  J11     56  DQS4_A_N  SCONN288_ADR50001P013C01  I126
  J12     56  DQS4_A_N  SCONN288_ADR50001P003C01  I125
  U2     EE58  DDR5_SA_DQS_DN4  SOCKET4677_AZIFS054P001C01  I169

M_F_CPU0_SA_DQS_DN<5>   @S9S_MB_2U_LIB.S9S_MB_2U(SCH_1):M_F_CPU0_SA_DQS_DN<5>
  J11    156  DQS5_A_N  SCONN288_ADR50001P013C01  I126
  J12    156  DQS5_A_N  SCONN288_ADR50001P003C01  I125
  U2     EJ76  DDR5_SA_DQS_DN5  SOCKET4677_AZIFS054P001C01  I169

M_F_CPU0_SA_DQS_DN<6>   @S9S_MB_2U_LIB.S9S_MB_2U(SCH_1):M_F_CPU0_SA_DQS_DN<6>
  J11    167  DQS6_A_N  SCONN288_ADR50001P013C01  I126
  J12    167  DQS6_A_N  SCONN288_ADR50001P003C01  I125
  U2     EB67  DDR5_SA_DQS_DN6  SOCKET4677_AZIFS054P001C01  I169

M_F_CPU0_SA_DQS_DN<7>   @S9S_MB_2U_LIB.S9S_MB_2U(SCH_1):M_F_CPU0_SA_DQS_DN<7>
  J11    178  DQS7_A_N  SCONN288_ADR50001P013C01  I126
  J12    178  DQS7_A_N  SCONN288_ADR50001P003C01  I125
  U2     EJ64  DDR5_SA_DQS_DN7  SOCKET4677_AZIFS054P001C01  I169

M_F_CPU0_SA_DQS_DN<8>   @S9S_MB_2U_LIB.S9S_MB_2U(SCH_1):M_F_CPU0_SA_DQS_DN<8>
  J11    189  DQS8_A_N  SCONN288_ADR50001P013C01  I126
  J12    189  DQS8_A_N  SCONN288_ADR50001P003C01  I125
  U2     EB55  DDR5_SA_DQS_DN8  SOCKET4677_AZIFS054P001C01  I169

M_F_CPU0_SA_DQS_DN<9>   @S9S_MB_2U_LIB.S9S_MB_2U(SCH_1):M_F_CPU0_SA_DQS_DN<9>
  J11    200  DQS9_A_N  SCONN288_ADR50001P013C01  I126
  J12    200  DQS9_A_N  SCONN288_ADR50001P003C01  I125
  U2     EJ58  DDR5_SA_DQS_DN9  SOCKET4677_AZIFS054P001C01  I169

M_F_CPU0_SA_DQS_DP<0>   @S9S_MB_2U_LIB.S9S_MB_2U(SCH_1):M_F_CPU0_SA_DQS_DP<0>
  J11     11  DQS0_A_P  SCONN288_ADR50001P013C01  I126
  J12     11  DQS0_A_P  SCONN288_ADR50001P003C01  I125
  U2     EC76  DDR5_SA_DQS_DP0  SOCKET4677_AZIFS054P001C01  I169

M_F_CPU0_SA_DQS_DP<1>   @S9S_MB_2U_LIB.S9S_MB_2U(SCH_1):M_F_CPU0_SA_DQS_DP<1>
  J11     22  DQS1_A_P  SCONN288_ADR50001P013C01  I126
  J12     22  DQS1_A_P  SCONN288_ADR50001P003C01  I125
  U2     DV67  DDR5_SA_DQS_DP1  SOCKET4677_AZIFS054P001C01  I169

M_F_CPU0_SA_DQS_DP<2>   @S9S_MB_2U_LIB.S9S_MB_2U(SCH_1):M_F_CPU0_SA_DQS_DP<2>
  J11     33  DQS2_A_P  SCONN288_ADR50001P013C01  I126
  J12     33  DQS2_A_P  SCONN288_ADR50001P003C01  I125
  U2     EE64  DDR5_SA_DQS_DP2  SOCKET4677_AZIFS054P001C01  I169

M_F_CPU0_SA_DQS_DP<3>   @S9S_MB_2U_LIB.S9S_MB_2U(SCH_1):M_F_CPU0_SA_DQS_DP<3>
  J11     44  DQS3_A_P  SCONN288_ADR50001P013C01  I126
  J12     44  DQS3_A_P  SCONN288_ADR50001P003C01  I125
  U2     DT55  DDR5_SA_DQS_DP3  SOCKET4677_AZIFS054P001C01  I169

M_F_CPU0_SA_DQS_DP<4>   @S9S_MB_2U_LIB.S9S_MB_2U(SCH_1):M_F_CPU0_SA_DQS_DP<4>
  J11     55  DQS4_A_P  SCONN288_ADR50001P013C01  I126
  J12     55  DQS4_A_P  SCONN288_ADR50001P003C01  I125
  U2     EC58  DDR5_SA_DQS_DP4  SOCKET4677_AZIFS054P001C01  I169

M_F_CPU0_SA_DQS_DP<5>   @S9S_MB_2U_LIB.S9S_MB_2U(SCH_1):M_F_CPU0_SA_DQS_DP<5>
  J11    157  DQS5_A_P  SCONN288_ADR50001P013C01  I126
  J12    157  DQS5_A_P  SCONN288_ADR50001P003C01  I125
  U2     EG76  DDR5_SA_DQS_DP5  SOCKET4677_AZIFS054P001C01  I169

M_F_CPU0_SA_DQS_DP<6>   @S9S_MB_2U_LIB.S9S_MB_2U(SCH_1):M_F_CPU0_SA_DQS_DP<6>
  J11    168  DQS6_A_P  SCONN288_ADR50001P013C01  I126
  J12    168  DQS6_A_P  SCONN288_ADR50001P003C01  I125
  U2     DY67  DDR5_SA_DQS_DP6  SOCKET4677_AZIFS054P001C01  I169

M_F_CPU0_SA_DQS_DP<7>   @S9S_MB_2U_LIB.S9S_MB_2U(SCH_1):M_F_CPU0_SA_DQS_DP<7>
  J11    179  DQS7_A_P  SCONN288_ADR50001P013C01  I126
  J12    179  DQS7_A_P  SCONN288_ADR50001P003C01  I125
  U2     EG64  DDR5_SA_DQS_DP7  SOCKET4677_AZIFS054P001C01  I169

M_F_CPU0_SA_DQS_DP<8>   @S9S_MB_2U_LIB.S9S_MB_2U(SCH_1):M_F_CPU0_SA_DQS_DP<8>
  J11    190  DQS8_A_P  SCONN288_ADR50001P013C01  I126
  J12    190  DQS8_A_P  SCONN288_ADR50001P003C01  I125
  U2     DY55  DDR5_SA_DQS_DP8  SOCKET4677_AZIFS054P001C01  I169

M_F_CPU0_SA_DQS_DP<9>   @S9S_MB_2U_LIB.S9S_MB_2U(SCH_1):M_F_CPU0_SA_DQS_DP<9>
  J11    201  DQS9_A_P  SCONN288_ADR50001P013C01  I126
  J12    201  DQS9_A_P  SCONN288_ADR50001P003C01  I125
  U2     EG58  DDR5_SA_DQS_DP9  SOCKET4677_AZIFS054P001C01  I169

M_F_CPU0_SA_PAR   @S9S_MB_2U_LIB.S9S_MB_2U(SCH_1):M_F_CPU0_SA_PAR
  J11     74  PAR_A  SCONN288_ADR50001P013C01  I25
  J12     74  PAR_A  SCONN288_ADR50001P003C01  I24
  U2     EA50  DDR5_SA_PAR  SOCKET4677_AZIFS054P001C01  I169

M_F_CPU0_SA_RSP<0>   @S9S_MB_2U_LIB.S9S_MB_2U(SCH_1):M_F_CPU0_SA_RSP<0>
  J11     86  LBD||RSP_N_A  SCONN288_ADR50001P013C01  I25
  U2     DN48  DDR5_A_RSP0  SOCKET4677_AZIFS054P001C01  I169

M_F_CPU0_SA_RSP<1>   @S9S_MB_2U_LIB.S9S_MB_2U(SCH_1):M_F_CPU0_SA_RSP<1>
  J12     86  LBD||RSP_N_A  SCONN288_ADR50001P003C01  I24
  U2     DP47  DDR5_A_RSP1  SOCKET4677_AZIFS054P001C01  I169

M_F_CPU0_SB_CA<0>   @S9S_MB_2U_LIB.S9S_MB_2U(SCH_1):M_F_CPU0_SB_CA<0>
  J11     76  CA0_B  SCONN288_ADR50001P013C01  I25
  J12     76  CA0_B  SCONN288_ADR50001P003C01  I24
  U2     DV51  DDR5_SB_CA0  SOCKET4677_AZIFS054P001C01  I169

M_F_CPU0_SB_CA<1>   @S9S_MB_2U_LIB.S9S_MB_2U(SCH_1):M_F_CPU0_SB_CA<1>
  J11    221  CA1_B  SCONN288_ADR50001P013C01  I25
  J12    221  CA1_B  SCONN288_ADR50001P003C01  I24
  U2     DU50  DDR5_SB_CA1  SOCKET4677_AZIFS054P001C01  I169

M_F_CPU0_SB_CA<2>   @S9S_MB_2U_LIB.S9S_MB_2U(SCH_1):M_F_CPU0_SB_CA<2>
  J11     78  CA2_B  SCONN288_ADR50001P013C01  I25
  J12     78  CA2_B  SCONN288_ADR50001P003C01  I24
  U2     EE41  DDR5_SB_CA2  SOCKET4677_AZIFS054P001C01  I169

M_F_CPU0_SB_CA<3>   @S9S_MB_2U_LIB.S9S_MB_2U(SCH_1):M_F_CPU0_SB_CA<3>
  J11    223  CA3_B  SCONN288_ADR50001P013C01  I25
  J12    223  CA3_B  SCONN288_ADR50001P003C01  I24
  U2     EG41  DDR5_SB_CA3  SOCKET4677_AZIFS054P001C01  I169

M_F_CPU0_SB_CA<4>   @S9S_MB_2U_LIB.S9S_MB_2U(SCH_1):M_F_CPU0_SB_CA<4>
  J11     80  CA4_B  SCONN288_ADR50001P013C01  I25
  J12     80  CA4_B  SCONN288_ADR50001P003C01  I24
  U2     ED40  DDR5_SB_CA4  SOCKET4677_AZIFS054P001C01  I169

M_F_CPU0_SB_CA<5>   @S9S_MB_2U_LIB.S9S_MB_2U(SCH_1):M_F_CPU0_SB_CA<5>
  J11    225  CA5_B  SCONN288_ADR50001P013C01  I25
  J12    225  CA5_B  SCONN288_ADR50001P003C01  I24
  U2     EH40  DDR5_SB_CA5  SOCKET4677_AZIFS054P001C01  I169

M_F_CPU0_SB_CA<6>   @S9S_MB_2U_LIB.S9S_MB_2U(SCH_1):M_F_CPU0_SB_CA<6>
  J11     82  CA6_B  SCONN288_ADR50001P013C01  I25
  J12     82  CA6_B  SCONN288_ADR50001P003C01  I24
  U2     EC39  DDR5_SB_CA6  SOCKET4677_AZIFS054P001C01  I169

M_F_CPU0_SB_CB<0>   @S9S_MB_2U_LIB.S9S_MB_2U(SCH_1):M_F_CPU0_SB_CB<0>
  J11     96  CB_B0  SCONN288_ADR50001P013C01  I25
  J12     96  CB_B0  SCONN288_ADR50001P003C01  I24
  U2     ED32  DDR5_SB_ECC0  SOCKET4677_AZIFS054P001C01  I169

M_F_CPU0_SB_CB<1>   @S9S_MB_2U_LIB.S9S_MB_2U(SCH_1):M_F_CPU0_SB_CB<1>
  J11     98  CB_B1  SCONN288_ADR50001P013C01  I25
  J12     98  CB_B1  SCONN288_ADR50001P003C01  I24
  U2     EE31  DDR5_SB_ECC1  SOCKET4677_AZIFS054P001C01  I169

M_F_CPU0_SB_CB<2>   @S9S_MB_2U_LIB.S9S_MB_2U(SCH_1):M_F_CPU0_SB_CB<2>
  J11    241  CB_B2  SCONN288_ADR50001P013C01  I25
  J12    241  CB_B2  SCONN288_ADR50001P003C01  I24
  U2     EH32  DDR5_SB_ECC2  SOCKET4677_AZIFS054P001C01  I169

M_F_CPU0_SB_CB<3>   @S9S_MB_2U_LIB.S9S_MB_2U(SCH_1):M_F_CPU0_SB_CB<3>
  J11    243  CB_B3  SCONN288_ADR50001P013C01  I25
  J12    243  CB_B3  SCONN288_ADR50001P003C01  I24
  U2     EG31  DDR5_SB_ECC3  SOCKET4677_AZIFS054P001C01  I169

M_F_CPU0_SB_CB<4>   @S9S_MB_2U_LIB.S9S_MB_2U(SCH_1):M_F_CPU0_SB_CB<4>
  J11     89  CB_B4  SCONN288_ADR50001P013C01  I25
  J12     89  CB_B4  SCONN288_ADR50001P003C01  I24
  U2     EE35  DDR5_SB_ECC4  SOCKET4677_AZIFS054P001C01  I169

M_F_CPU0_SB_CB<5>   @S9S_MB_2U_LIB.S9S_MB_2U(SCH_1):M_F_CPU0_SB_CB<5>
  J11     91  CB_B5  SCONN288_ADR50001P013C01  I25
  J12     91  CB_B5  SCONN288_ADR50001P003C01  I24
  U2     ED34  DDR5_SB_ECC5  SOCKET4677_AZIFS054P001C01  I169

M_F_CPU0_SB_CB<6>   @S9S_MB_2U_LIB.S9S_MB_2U(SCH_1):M_F_CPU0_SB_CB<6>
  J11    234  CB_B6  SCONN288_ADR50001P013C01  I25
  J12    234  CB_B6  SCONN288_ADR50001P003C01  I24
  U2     EG35  DDR5_SB_ECC6  SOCKET4677_AZIFS054P001C01  I169

M_F_CPU0_SB_CB<7>   @S9S_MB_2U_LIB.S9S_MB_2U(SCH_1):M_F_CPU0_SB_CB<7>
  J11    236  CB_B7  SCONN288_ADR50001P013C01  I25
  J12    236  CB_B7  SCONN288_ADR50001P003C01  I24
  U2     EH34  DDR5_SB_ECC7  SOCKET4677_AZIFS054P001C01  I169

M_F_CPU0_SB_CS_N<0>   @S9S_MB_2U_LIB.S9S_MB_2U(SCH_1):M_F_CPU0_SB_CS_N<0>
  J11     84  CS0_N_B  SCONN288_ADR50001P013C01  I25
  U2     EH38  DDR5_SB_CS0_N  SOCKET4677_AZIFS054P001C01  I169

M_F_CPU0_SB_CS_N<1>   @S9S_MB_2U_LIB.S9S_MB_2U(SCH_1):M_F_CPU0_SB_CS_N<1>
  J11    229  CS1_N_B  SCONN288_ADR50001P013C01  I25
  U2     EG37  DDR5_SB_CS1_N  SOCKET4677_AZIFS054P001C01  I169

M_F_CPU0_SB_CS_N<2>   @S9S_MB_2U_LIB.S9S_MB_2U(SCH_1):M_F_CPU0_SB_CS_N<2>
  J12     84  CS0_N_B  SCONN288_ADR50001P003C01  I24
  U2     ED38  DDR5_SB_CS2_N  SOCKET4677_AZIFS054P001C01  I169

M_F_CPU0_SB_CS_N<3>   @S9S_MB_2U_LIB.S9S_MB_2U(SCH_1):M_F_CPU0_SB_CS_N<3>
  J12    229  CS1_N_B  SCONN288_ADR50001P003C01  I24
  U2     EE37  DDR5_SB_CS3_N  SOCKET4677_AZIFS054P001C01  I169

M_F_CPU0_SB_DQ<0>   @S9S_MB_2U_LIB.S9S_MB_2U(SCH_1):M_F_CPU0_SB_DQ<0>
  J11    100  DQ_B0  SCONN288_ADR50001P013C01  I25
  J12    100  DQ_B0  SCONN288_ADR50001P003C01  I24
  U2     DV32  DDR5_SB_DQ0  SOCKET4677_AZIFS054P001C01  I169

M_F_CPU0_SB_DQ<1>   @S9S_MB_2U_LIB.S9S_MB_2U(SCH_1):M_F_CPU0_SB_DQ<1>
  J11    102  DQ_B1  SCONN288_ADR50001P013C01  I25
  J12    102  DQ_B1  SCONN288_ADR50001P003C01  I24
  U2     DU31  DDR5_SB_DQ1  SOCKET4677_AZIFS054P001C01  I169

M_F_CPU0_SB_DQ<2>   @S9S_MB_2U_LIB.S9S_MB_2U(SCH_1):M_F_CPU0_SB_DQ<2>
  J11    245  DQ_B2  SCONN288_ADR50001P013C01  I25
  J12    245  DQ_B2  SCONN288_ADR50001P003C01  I24
  U2     DY32  DDR5_SB_DQ2  SOCKET4677_AZIFS054P001C01  I169

M_F_CPU0_SB_DQ<3>   @S9S_MB_2U_LIB.S9S_MB_2U(SCH_1):M_F_CPU0_SB_DQ<3>
  J11    247  DQ_B3  SCONN288_ADR50001P013C01  I25
  J12    247  DQ_B3  SCONN288_ADR50001P003C01  I24
  U2     EA31  DDR5_SB_DQ3  SOCKET4677_AZIFS054P001C01  I169

M_F_CPU0_SB_DQ<4>   @S9S_MB_2U_LIB.S9S_MB_2U(SCH_1):M_F_CPU0_SB_DQ<4>
  J11    107  DQ_B4  SCONN288_ADR50001P013C01  I25
  J12    107  DQ_B4  SCONN288_ADR50001P003C01  I24
  U2     DU29  DDR5_SB_DQ4  SOCKET4677_AZIFS054P001C01  I169

M_F_CPU0_SB_DQ<5>   @S9S_MB_2U_LIB.S9S_MB_2U(SCH_1):M_F_CPU0_SB_DQ<5>
  J11    109  DQ_B5  SCONN288_ADR50001P013C01  I25
  J12    109  DQ_B5  SCONN288_ADR50001P003C01  I24
  U2     DV28  DDR5_SB_DQ5  SOCKET4677_AZIFS054P001C01  I169

M_F_CPU0_SB_DQ<6>   @S9S_MB_2U_LIB.S9S_MB_2U(SCH_1):M_F_CPU0_SB_DQ<6>
  J11    252  DQ_B6  SCONN288_ADR50001P013C01  I25
  J12    252  DQ_B6  SCONN288_ADR50001P003C01  I24
  U2     EA29  DDR5_SB_DQ6  SOCKET4677_AZIFS054P001C01  I169

M_F_CPU0_SB_DQ<7>   @S9S_MB_2U_LIB.S9S_MB_2U(SCH_1):M_F_CPU0_SB_DQ<7>
  J11    254  DQ_B7  SCONN288_ADR50001P013C01  I25
  J12    254  DQ_B7  SCONN288_ADR50001P003C01  I24
  U2     DY28  DDR5_SB_DQ7  SOCKET4677_AZIFS054P001C01  I169

M_F_CPU0_SB_DQ<8>   @S9S_MB_2U_LIB.S9S_MB_2U(SCH_1):M_F_CPU0_SB_DQ<8>
  J11    111  DQ_B8  SCONN288_ADR50001P013C01  I25
  J12    111  DQ_B8  SCONN288_ADR50001P003C01  I24
  U2     EE23  DDR5_SB_DQ8  SOCKET4677_AZIFS054P001C01  I169

M_F_CPU0_SB_DQ<9>   @S9S_MB_2U_LIB.S9S_MB_2U(SCH_1):M_F_CPU0_SB_DQ<9>
  J11    113  DQ_B9  SCONN288_ADR50001P013C01  I25
  J12    113  DQ_B9  SCONN288_ADR50001P003C01  I24
  U2     ED22  DDR5_SB_DQ9  SOCKET4677_AZIFS054P001C01  I169

M_F_CPU0_SB_DQ<10>   @S9S_MB_2U_LIB.S9S_MB_2U(SCH_1):M_F_CPU0_SB_DQ<10>
  J11    256  DQ_B10  SCONN288_ADR50001P013C01  I25
  J12    256  DQ_B10  SCONN288_ADR50001P003C01  I24
  U2     EG23  DDR5_SB_DQ10  SOCKET4677_AZIFS054P001C01  I169

M_F_CPU0_SB_DQ<11>   @S9S_MB_2U_LIB.S9S_MB_2U(SCH_1):M_F_CPU0_SB_DQ<11>
  J11    258  DQ_B11  SCONN288_ADR50001P013C01  I25
  J12    258  DQ_B11  SCONN288_ADR50001P003C01  I24
  U2     EH22  DDR5_SB_DQ11  SOCKET4677_AZIFS054P001C01  I169

M_F_CPU0_SB_DQ<12>   @S9S_MB_2U_LIB.S9S_MB_2U(SCH_1):M_F_CPU0_SB_DQ<12>
  J11    118  DQ_B12  SCONN288_ADR50001P013C01  I25
  J12    118  DQ_B12  SCONN288_ADR50001P003C01  I24
  U2     ED20  DDR5_SB_DQ12  SOCKET4677_AZIFS054P001C01  I169

M_F_CPU0_SB_DQ<13>   @S9S_MB_2U_LIB.S9S_MB_2U(SCH_1):M_F_CPU0_SB_DQ<13>
  J11    120  DQ_B13  SCONN288_ADR50001P013C01  I25
  J12    120  DQ_B13  SCONN288_ADR50001P003C01  I24
  U2     EE19  DDR5_SB_DQ13  SOCKET4677_AZIFS054P001C01  I169

M_F_CPU0_SB_DQ<14>   @S9S_MB_2U_LIB.S9S_MB_2U(SCH_1):M_F_CPU0_SB_DQ<14>
  J11    263  DQ_B14  SCONN288_ADR50001P013C01  I25
  J12    263  DQ_B14  SCONN288_ADR50001P003C01  I24
  U2     EH20  DDR5_SB_DQ14  SOCKET4677_AZIFS054P001C01  I169

M_F_CPU0_SB_DQ<15>   @S9S_MB_2U_LIB.S9S_MB_2U(SCH_1):M_F_CPU0_SB_DQ<15>
  J11    265  DQ_B15  SCONN288_ADR50001P013C01  I25
  J12    265  DQ_B15  SCONN288_ADR50001P003C01  I24
  U2     EG19  DDR5_SB_DQ15  SOCKET4677_AZIFS054P001C01  I169

M_F_CPU0_SB_DQ<16>   @S9S_MB_2U_LIB.S9S_MB_2U(SCH_1):M_F_CPU0_SB_DQ<16>
  J11    122  DQ_B16  SCONN288_ADR50001P013C01  I25
  J12    122  DQ_B16  SCONN288_ADR50001P003C01  I24
  U2     EM14  DDR5_SB_DQ16  SOCKET4677_AZIFS054P001C01  I169

M_F_CPU0_SB_DQ<17>   @S9S_MB_2U_LIB.S9S_MB_2U(SCH_1):M_F_CPU0_SB_DQ<17>
  J11    124  DQ_B17  SCONN288_ADR50001P013C01  I25
  J12    124  DQ_B17  SCONN288_ADR50001P003C01  I24
  U2     EL13  DDR5_SB_DQ17  SOCKET4677_AZIFS054P001C01  I169

M_F_CPU0_SB_DQ<18>   @S9S_MB_2U_LIB.S9S_MB_2U(SCH_1):M_F_CPU0_SB_DQ<18>
  J11    267  DQ_B18  SCONN288_ADR50001P013C01  I25
  J12    267  DQ_B18  SCONN288_ADR50001P003C01  I24
  U2     EP14  DDR5_SB_DQ18  SOCKET4677_AZIFS054P001C01  I169

M_F_CPU0_SB_DQ<19>   @S9S_MB_2U_LIB.S9S_MB_2U(SCH_1):M_F_CPU0_SB_DQ<19>
  J11    269  DQ_B19  SCONN288_ADR50001P013C01  I25
  J12    269  DQ_B19  SCONN288_ADR50001P003C01  I24
  U2     ER13  DDR5_SB_DQ19  SOCKET4677_AZIFS054P001C01  I169

M_F_CPU0_SB_DQ<20>   @S9S_MB_2U_LIB.S9S_MB_2U(SCH_1):M_F_CPU0_SB_DQ<20>
  J11    129  DQ_B20  SCONN288_ADR50001P013C01  I25
  J12    129  DQ_B20  SCONN288_ADR50001P003C01  I24
  U2     EL11  DDR5_SB_DQ20  SOCKET4677_AZIFS054P001C01  I169

M_F_CPU0_SB_DQ<21>   @S9S_MB_2U_LIB.S9S_MB_2U(SCH_1):M_F_CPU0_SB_DQ<21>
  J11    131  DQ_B21  SCONN288_ADR50001P013C01  I25
  J12    131  DQ_B21  SCONN288_ADR50001P003C01  I24
  U2     EM10  DDR5_SB_DQ21  SOCKET4677_AZIFS054P001C01  I169

M_F_CPU0_SB_DQ<22>   @S9S_MB_2U_LIB.S9S_MB_2U(SCH_1):M_F_CPU0_SB_DQ<22>
  J11    274  DQ_B22  SCONN288_ADR50001P013C01  I25
  J12    274  DQ_B22  SCONN288_ADR50001P003C01  I24
  U2     ER11  DDR5_SB_DQ22  SOCKET4677_AZIFS054P001C01  I169

M_F_CPU0_SB_DQ<23>   @S9S_MB_2U_LIB.S9S_MB_2U(SCH_1):M_F_CPU0_SB_DQ<23>
  J11    276  DQ_B23  SCONN288_ADR50001P013C01  I25
  J12    276  DQ_B23  SCONN288_ADR50001P003C01  I24
  U2     EP10  DDR5_SB_DQ23  SOCKET4677_AZIFS054P001C01  I169

M_F_CPU0_SB_DQ<24>   @S9S_MB_2U_LIB.S9S_MB_2U(SCH_1):M_F_CPU0_SB_DQ<24>
  J11    133  DQ_B24  SCONN288_ADR50001P013C01  I25
  J12    133  DQ_B24  SCONN288_ADR50001P003C01  I24
  U2     DV20  DDR5_SB_DQ24  SOCKET4677_AZIFS054P001C01  I169

M_F_CPU0_SB_DQ<25>   @S9S_MB_2U_LIB.S9S_MB_2U(SCH_1):M_F_CPU0_SB_DQ<25>
  J11    135  DQ_B25  SCONN288_ADR50001P013C01  I25
  J12    135  DQ_B25  SCONN288_ADR50001P003C01  I24
  U2     DU19  DDR5_SB_DQ25  SOCKET4677_AZIFS054P001C01  I169

M_F_CPU0_SB_DQ<26>   @S9S_MB_2U_LIB.S9S_MB_2U(SCH_1):M_F_CPU0_SB_DQ<26>
  J11    278  DQ_B26  SCONN288_ADR50001P013C01  I25
  J12    278  DQ_B26  SCONN288_ADR50001P003C01  I24
  U2     DY20  DDR5_SB_DQ26  SOCKET4677_AZIFS054P001C01  I169

M_F_CPU0_SB_DQ<27>   @S9S_MB_2U_LIB.S9S_MB_2U(SCH_1):M_F_CPU0_SB_DQ<27>
  J11    280  DQ_B27  SCONN288_ADR50001P013C01  I25
  J12    280  DQ_B27  SCONN288_ADR50001P003C01  I24
  U2     EA19  DDR5_SB_DQ27  SOCKET4677_AZIFS054P001C01  I169

M_F_CPU0_SB_DQ<28>   @S9S_MB_2U_LIB.S9S_MB_2U(SCH_1):M_F_CPU0_SB_DQ<28>
  J11    140  DQ_B28  SCONN288_ADR50001P013C01  I25
  J12    140  DQ_B28  SCONN288_ADR50001P003C01  I24
  U2     EA17  DDR5_SB_DQ28  SOCKET4677_AZIFS054P001C01  I169

M_F_CPU0_SB_DQ<29>   @S9S_MB_2U_LIB.S9S_MB_2U(SCH_1):M_F_CPU0_SB_DQ<29>
  J11    142  DQ_B29  SCONN288_ADR50001P013C01  I25
  J12    142  DQ_B29  SCONN288_ADR50001P003C01  I24
  U2     DU17  DDR5_SB_DQ29  SOCKET4677_AZIFS054P001C01  I169

M_F_CPU0_SB_DQ<30>   @S9S_MB_2U_LIB.S9S_MB_2U(SCH_1):M_F_CPU0_SB_DQ<30>
  J11    285  DQ_B30  SCONN288_ADR50001P013C01  I25
  J12    285  DQ_B30  SCONN288_ADR50001P003C01  I24
  U2     EC17  DDR5_SB_DQ30  SOCKET4677_AZIFS054P001C01  I169

M_F_CPU0_SB_DQ<31>   @S9S_MB_2U_LIB.S9S_MB_2U(SCH_1):M_F_CPU0_SB_DQ<31>
  J11    287  DQ_B31  SCONN288_ADR50001P013C01  I25
  J12    287  DQ_B31  SCONN288_ADR50001P003C01  I24
  U2     DR17  DDR5_SB_DQ31  SOCKET4677_AZIFS054P001C01  I169

M_F_CPU0_SB_DQS_DN<0>   @S9S_MB_2U_LIB.S9S_MB_2U(SCH_1):M_F_CPU0_SB_DQS_DN<0>
  J11    105  DQS0_B_N  SCONN288_ADR50001P013C01  I126
  J12    105  DQS0_B_N  SCONN288_ADR50001P003C01  I125
  U2     DV30  DDR5_SB_DQS_DN0  SOCKET4677_AZIFS054P001C01  I169

M_F_CPU0_SB_DQS_DN<1>   @S9S_MB_2U_LIB.S9S_MB_2U(SCH_1):M_F_CPU0_SB_DQS_DN<1>
  J11    116  DQS1_B_N  SCONN288_ADR50001P013C01  I126
  J12    116  DQS1_B_N  SCONN288_ADR50001P003C01  I125
  U2     EE21  DDR5_SB_DQS_DN1  SOCKET4677_AZIFS054P001C01  I169

M_F_CPU0_SB_DQS_DN<2>   @S9S_MB_2U_LIB.S9S_MB_2U(SCH_1):M_F_CPU0_SB_DQS_DN<2>
  J11    127  DQS2_B_N  SCONN288_ADR50001P013C01  I126
  J12    127  DQS2_B_N  SCONN288_ADR50001P003C01  I125
  U2     EM12  DDR5_SB_DQS_DN2  SOCKET4677_AZIFS054P001C01  I169

M_F_CPU0_SB_DQS_DN<3>   @S9S_MB_2U_LIB.S9S_MB_2U(SCH_1):M_F_CPU0_SB_DQS_DN<3>
  J11    138  DQS3_B_N  SCONN288_ADR50001P013C01  I126
  J12    138  DQS3_B_N  SCONN288_ADR50001P003C01  I125
  U2     DT18  DDR5_SB_DQS_DN3  SOCKET4677_AZIFS054P001C01  I169

M_F_CPU0_SB_DQS_DN<4>   @S9S_MB_2U_LIB.S9S_MB_2U(SCH_1):M_F_CPU0_SB_DQS_DN<4>
  J11    238  DQS4_B_N  SCONN288_ADR50001P013C01  I126
  J12    238  DQS4_B_N  SCONN288_ADR50001P003C01  I125
  U2     EJ33  DDR5_SB_DQS_DN4  SOCKET4677_AZIFS054P001C01  I169

M_F_CPU0_SB_DQS_DN<5>   @S9S_MB_2U_LIB.S9S_MB_2U(SCH_1):M_F_CPU0_SB_DQS_DN<5>
  J11    249  DQS5_B_N  SCONN288_ADR50001P013C01  I126
  J12    249  DQS5_B_N  SCONN288_ADR50001P003C01  I125
  U2     EB30  DDR5_SB_DQS_DN5  SOCKET4677_AZIFS054P001C01  I169

M_F_CPU0_SB_DQS_DN<6>   @S9S_MB_2U_LIB.S9S_MB_2U(SCH_1):M_F_CPU0_SB_DQS_DN<6>
  J11    260  DQS6_B_N  SCONN288_ADR50001P013C01  I126
  J12    260  DQS6_B_N  SCONN288_ADR50001P003C01  I125
  U2     EJ21  DDR5_SB_DQS_DN6  SOCKET4677_AZIFS054P001C01  I169

M_F_CPU0_SB_DQS_DN<7>   @S9S_MB_2U_LIB.S9S_MB_2U(SCH_1):M_F_CPU0_SB_DQS_DN<7>
  J11    271  DQS7_B_N  SCONN288_ADR50001P013C01  I126
  J12    271  DQS7_B_N  SCONN288_ADR50001P003C01  I125
  U2     ET12  DDR5_SB_DQS_DN7  SOCKET4677_AZIFS054P001C01  I169

M_F_CPU0_SB_DQS_DN<8>   @S9S_MB_2U_LIB.S9S_MB_2U(SCH_1):M_F_CPU0_SB_DQS_DN<8>
  J11    282  DQS8_B_N  SCONN288_ADR50001P013C01  I126
  J12    282  DQS8_B_N  SCONN288_ADR50001P003C01  I125
  U2     DY18  DDR5_SB_DQS_DN8  SOCKET4677_AZIFS054P001C01  I169

M_F_CPU0_SB_DQS_DN<9>   @S9S_MB_2U_LIB.S9S_MB_2U(SCH_1):M_F_CPU0_SB_DQS_DN<9>
  J11     94  DQS9_B_N  SCONN288_ADR50001P013C01  I126
  J12     94  DQS9_B_N  SCONN288_ADR50001P003C01  I125
  U2     EE33  DDR5_SB_DQS_DN9  SOCKET4677_AZIFS054P001C01  I169

M_F_CPU0_SB_DQS_DP<0>   @S9S_MB_2U_LIB.S9S_MB_2U(SCH_1):M_F_CPU0_SB_DQS_DP<0>
  J11    104  DQS0_B_P  SCONN288_ADR50001P013C01  I126
  J12    104  DQS0_B_P  SCONN288_ADR50001P003C01  I125
  U2     DT30  DDR5_SB_DQS_DP0  SOCKET4677_AZIFS054P001C01  I169

M_F_CPU0_SB_DQS_DP<1>   @S9S_MB_2U_LIB.S9S_MB_2U(SCH_1):M_F_CPU0_SB_DQS_DP<1>
  J11    115  DQS1_B_P  SCONN288_ADR50001P013C01  I126
  J12    115  DQS1_B_P  SCONN288_ADR50001P003C01  I125
  U2     EC21  DDR5_SB_DQS_DP1  SOCKET4677_AZIFS054P001C01  I169

M_F_CPU0_SB_DQS_DP<2>   @S9S_MB_2U_LIB.S9S_MB_2U(SCH_1):M_F_CPU0_SB_DQS_DP<2>
  J11    126  DQS2_B_P  SCONN288_ADR50001P013C01  I126
  J12    126  DQS2_B_P  SCONN288_ADR50001P003C01  I125
  U2     EK12  DDR5_SB_DQS_DP2  SOCKET4677_AZIFS054P001C01  I169

M_F_CPU0_SB_DQS_DP<3>   @S9S_MB_2U_LIB.S9S_MB_2U(SCH_1):M_F_CPU0_SB_DQS_DP<3>
  J11    137  DQS3_B_P  SCONN288_ADR50001P013C01  I126
  J12    137  DQS3_B_P  SCONN288_ADR50001P003C01  I125
  U2     DV18  DDR5_SB_DQS_DP3  SOCKET4677_AZIFS054P001C01  I169

M_F_CPU0_SB_DQS_DP<4>   @S9S_MB_2U_LIB.S9S_MB_2U(SCH_1):M_F_CPU0_SB_DQS_DP<4>
  J11    239  DQS4_B_P  SCONN288_ADR50001P013C01  I126
  J12    239  DQS4_B_P  SCONN288_ADR50001P003C01  I125
  U2     EG33  DDR5_SB_DQS_DP4  SOCKET4677_AZIFS054P001C01  I169

M_F_CPU0_SB_DQS_DP<5>   @S9S_MB_2U_LIB.S9S_MB_2U(SCH_1):M_F_CPU0_SB_DQS_DP<5>
  J11    250  DQS5_B_P  SCONN288_ADR50001P013C01  I126
  J12    250  DQS5_B_P  SCONN288_ADR50001P003C01  I125
  U2     DY30  DDR5_SB_DQS_DP5  SOCKET4677_AZIFS054P001C01  I169

M_F_CPU0_SB_DQS_DP<6>   @S9S_MB_2U_LIB.S9S_MB_2U(SCH_1):M_F_CPU0_SB_DQS_DP<6>
  J11    261  DQS6_B_P  SCONN288_ADR50001P013C01  I126
  J12    261  DQS6_B_P  SCONN288_ADR50001P003C01  I125
  U2     EG21  DDR5_SB_DQS_DP6  SOCKET4677_AZIFS054P001C01  I169

M_F_CPU0_SB_DQS_DP<7>   @S9S_MB_2U_LIB.S9S_MB_2U(SCH_1):M_F_CPU0_SB_DQS_DP<7>
  J11    272  DQS7_B_P  SCONN288_ADR50001P013C01  I126
  J12    272  DQS7_B_P  SCONN288_ADR50001P003C01  I125
  U2     EP12  DDR5_SB_DQS_DP7  SOCKET4677_AZIFS054P001C01  I169

M_F_CPU0_SB_DQS_DP<8>   @S9S_MB_2U_LIB.S9S_MB_2U(SCH_1):M_F_CPU0_SB_DQS_DP<8>
  J11    283  DQS8_B_P  SCONN288_ADR50001P013C01  I126
  J12    283  DQS8_B_P  SCONN288_ADR50001P003C01  I125
  U2     EB18  DDR5_SB_DQS_DP8  SOCKET4677_AZIFS054P001C01  I169

M_F_CPU0_SB_DQS_DP<9>   @S9S_MB_2U_LIB.S9S_MB_2U(SCH_1):M_F_CPU0_SB_DQS_DP<9>
  J11     93  DQS9_B_P  SCONN288_ADR50001P013C01  I126
  J12     93  DQS9_B_P  SCONN288_ADR50001P003C01  I125
  U2     EC33  DDR5_SB_DQS_DP9  SOCKET4677_AZIFS054P001C01  I169

M_F_CPU0_SB_PAR   @S9S_MB_2U_LIB.S9S_MB_2U(SCH_1):M_F_CPU0_SB_PAR
  J11    227  PAR_B  SCONN288_ADR50001P013C01  I25
  J12    227  PAR_B  SCONN288_ADR50001P003C01  I24
  U2     EJ39  DDR5_SB_PAR  SOCKET4677_AZIFS054P001C01  I169

M_F_CPU0_SB_RSP<0>   @S9S_MB_2U_LIB.S9S_MB_2U(SCH_1):M_F_CPU0_SB_RSP<0>
  J11     87  LBS||RSP_N_B  SCONN288_ADR50001P013C01  I25
  U2     DL48  DDR5_B_RSP0  SOCKET4677_AZIFS054P001C01  I169

M_F_CPU0_SB_RSP<1>   @S9S_MB_2U_LIB.S9S_MB_2U(SCH_1):M_F_CPU0_SB_RSP<1>
  J12     87  LBS||RSP_N_B  SCONN288_ADR50001P003C01  I24
  U2     DK47  DDR5_B_RSP1  SOCKET4677_AZIFS054P001C01  I169

M_F_CPU1_ALERT_N   @S9S_MB_2U_LIB.S9S_MB_2U(SCH_1):M_F_CPU1_ALERT_N
  J27     62  ALERT_N  SCONN288_ADR50001P013C01  I179
  J28     62  ALERT_N  SCONN288_ADR50001P003C01  I47
  U1     CW48  DDR5_ALERT_N  SOCKET4677_AZIFS054P001C01  I168

M_F_CPU1_CLK_DN<0>   @S9S_MB_2U_LIB.S9S_MB_2U(SCH_1):M_F_CPU1_CLK_DN<0>
  J27    218   CK_N  SCONN288_ADR50001P013C01  I179
  U1     DY49  DDR5_CLK_DN0  SOCKET4677_AZIFS054P001C01  I168

M_F_CPU1_CLK_DN<1>   @S9S_MB_2U_LIB.S9S_MB_2U(SCH_1):M_F_CPU1_CLK_DN<1>
  J28    218   CK_N  SCONN288_ADR50001P003C01  I47
  U1     DV49  DDR5_CLK_DN1  SOCKET4677_AZIFS054P001C01  I168

M_F_CPU1_CLK_DP<0>   @S9S_MB_2U_LIB.S9S_MB_2U(SCH_1):M_F_CPU1_CLK_DP<0>
  J27    217   CK_P  SCONN288_ADR50001P013C01  I179
  U1     EB49  DDR5_CLK_DP0  SOCKET4677_AZIFS054P001C01  I168

M_F_CPU1_CLK_DP<1>   @S9S_MB_2U_LIB.S9S_MB_2U(SCH_1):M_F_CPU1_CLK_DP<1>
  J28    217   CK_P  SCONN288_ADR50001P003C01  I47
  U1     DT49  DDR5_CLK_DP1  SOCKET4677_AZIFS054P001C01  I168

M_F_CPU1_SA_CA<0>   @S9S_MB_2U_LIB.S9S_MB_2U(SCH_1):M_F_CPU1_SA_CA<0>
  J27     66  CA0_A  SCONN288_ADR50001P013C01  I179
  J28     66  CA0_A  SCONN288_ADR50001P003C01  I47
  U1     EC52  DDR5_SA_CA0  SOCKET4677_AZIFS054P001C01  I168

M_F_CPU1_SA_CA<1>   @S9S_MB_2U_LIB.S9S_MB_2U(SCH_1):M_F_CPU1_SA_CA<1>
  J27    211  CA1_A  SCONN288_ADR50001P013C01  I179
  J28    211  CA1_A  SCONN288_ADR50001P003C01  I47
  U1     EJ52  DDR5_SA_CA1  SOCKET4677_AZIFS054P001C01  I168

M_F_CPU1_SA_CA<2>   @S9S_MB_2U_LIB.S9S_MB_2U(SCH_1):M_F_CPU1_SA_CA<2>
  J27     68  CA2_A  SCONN288_ADR50001P013C01  I179
  J28     68  CA2_A  SCONN288_ADR50001P003C01  I47
  U1     ED51  DDR5_SA_CA2  SOCKET4677_AZIFS054P001C01  I168

M_F_CPU1_SA_CA<3>   @S9S_MB_2U_LIB.S9S_MB_2U(SCH_1):M_F_CPU1_SA_CA<3>
  J27    213  CA3_A  SCONN288_ADR50001P013C01  I179
  J28    213  CA3_A  SCONN288_ADR50001P003C01  I47
  U1     EH51  DDR5_SA_CA3  SOCKET4677_AZIFS054P001C01  I168

M_F_CPU1_SA_CA<4>   @S9S_MB_2U_LIB.S9S_MB_2U(SCH_1):M_F_CPU1_SA_CA<4>
  J27     70  CA4_A  SCONN288_ADR50001P013C01  I179
  J28     70  CA4_A  SCONN288_ADR50001P003C01  I47
  U1     EE50  DDR5_SA_CA4  SOCKET4677_AZIFS054P001C01  I168

M_F_CPU1_SA_CA<5>   @S9S_MB_2U_LIB.S9S_MB_2U(SCH_1):M_F_CPU1_SA_CA<5>
  J27    215  CA5_A  SCONN288_ADR50001P013C01  I179
  J28    215  CA5_A  SCONN288_ADR50001P003C01  I47
  U1     EG50  DDR5_SA_CA5  SOCKET4677_AZIFS054P001C01  I168

M_F_CPU1_SA_CA<6>   @S9S_MB_2U_LIB.S9S_MB_2U(SCH_1):M_F_CPU1_SA_CA<6>
  J27     72  CA6_A  SCONN288_ADR50001P013C01  I179
  J28     72  CA6_A  SCONN288_ADR50001P003C01  I47
  U1     DY51  DDR5_SA_CA6  SOCKET4677_AZIFS054P001C01  I168

M_F_CPU1_SA_CB<0>   @S9S_MB_2U_LIB.S9S_MB_2U(SCH_1):M_F_CPU1_SA_CB<0>
  J27     51  CB_A0  SCONN288_ADR50001P013C01  I179
  J28     51  CB_A0  SCONN288_ADR50001P003C01  I47
  U1     EE60  DDR5_SA_ECC0  SOCKET4677_AZIFS054P001C01  I168

M_F_CPU1_SA_CB<1>   @S9S_MB_2U_LIB.S9S_MB_2U(SCH_1):M_F_CPU1_SA_CB<1>
  J27     53  CB_A1  SCONN288_ADR50001P013C01  I179
  J28     53  CB_A1  SCONN288_ADR50001P003C01  I47
  U1     ED59  DDR5_SA_ECC1  SOCKET4677_AZIFS054P001C01  I168

M_F_CPU1_SA_CB<2>   @S9S_MB_2U_LIB.S9S_MB_2U(SCH_1):M_F_CPU1_SA_CB<2>
  J27    196  CB_A2  SCONN288_ADR50001P013C01  I179
  J28    196  CB_A2  SCONN288_ADR50001P003C01  I47
  U1     EG60  DDR5_SA_ECC2  SOCKET4677_AZIFS054P001C01  I168

M_F_CPU1_SA_CB<3>   @S9S_MB_2U_LIB.S9S_MB_2U(SCH_1):M_F_CPU1_SA_CB<3>
  J27    198  CB_A3  SCONN288_ADR50001P013C01  I179
  J28    198  CB_A3  SCONN288_ADR50001P003C01  I47
  U1     EH59  DDR5_SA_ECC3  SOCKET4677_AZIFS054P001C01  I168

M_F_CPU1_SA_CB<4>   @S9S_MB_2U_LIB.S9S_MB_2U(SCH_1):M_F_CPU1_SA_CB<4>
  J27     58  CB_A4  SCONN288_ADR50001P013C01  I179
  J28     58  CB_A4  SCONN288_ADR50001P003C01  I47
  U1     ED57  DDR5_SA_ECC4  SOCKET4677_AZIFS054P001C01  I168

M_F_CPU1_SA_CB<5>   @S9S_MB_2U_LIB.S9S_MB_2U(SCH_1):M_F_CPU1_SA_CB<5>
  J27     60  CB_A5  SCONN288_ADR50001P013C01  I179
  J28     60  CB_A5  SCONN288_ADR50001P003C01  I47
  U1     EE56  DDR5_SA_ECC5  SOCKET4677_AZIFS054P001C01  I168

M_F_CPU1_SA_CB<6>   @S9S_MB_2U_LIB.S9S_MB_2U(SCH_1):M_F_CPU1_SA_CB<6>
  J27    203  CB_A6  SCONN288_ADR50001P013C01  I179
  J28    203  CB_A6  SCONN288_ADR50001P003C01  I47
  U1     EH57  DDR5_SA_ECC6  SOCKET4677_AZIFS054P001C01  I168

M_F_CPU1_SA_CB<7>   @S9S_MB_2U_LIB.S9S_MB_2U(SCH_1):M_F_CPU1_SA_CB<7>
  J27    205  CB_A7  SCONN288_ADR50001P013C01  I179
  J28    205  CB_A7  SCONN288_ADR50001P003C01  I47
  U1     EG56  DDR5_SA_ECC7  SOCKET4677_AZIFS054P001C01  I168

M_F_CPU1_SA_CS_N<0>   @S9S_MB_2U_LIB.S9S_MB_2U(SCH_1):M_F_CPU1_SA_CS_N<0>
  J27     64  CS0_N_A  SCONN288_ADR50001P013C01  I179
  U1     EG54  DDR5_SA_CS0_N  SOCKET4677_AZIFS054P001C01  I168

M_F_CPU1_SA_CS_N<1>   @S9S_MB_2U_LIB.S9S_MB_2U(SCH_1):M_F_CPU1_SA_CS_N<1>
  J27    209  CS1_N_A  SCONN288_ADR50001P013C01  I179
  U1     EH53  DDR5_SA_CS1_N  SOCKET4677_AZIFS054P001C01  I168

M_F_CPU1_SA_CS_N<2>   @S9S_MB_2U_LIB.S9S_MB_2U(SCH_1):M_F_CPU1_SA_CS_N<2>
  J28     64  CS0_N_A  SCONN288_ADR50001P003C01  I47
  U1     EE54  DDR5_SA_CS2_N  SOCKET4677_AZIFS054P001C01  I168

M_F_CPU1_SA_CS_N<3>   @S9S_MB_2U_LIB.S9S_MB_2U(SCH_1):M_F_CPU1_SA_CS_N<3>
  J28    209  CS1_N_A  SCONN288_ADR50001P003C01  I47
  U1     ED53  DDR5_SA_CS3_N  SOCKET4677_AZIFS054P001C01  I168

M_F_CPU1_SA_DQ<0>   @S9S_MB_2U_LIB.S9S_MB_2U(SCH_1):M_F_CPU1_SA_DQ<0>
  J27      7  DQ_A0  SCONN288_ADR50001P013C01  I179
  J28      7  DQ_A0  SCONN288_ADR50001P003C01  I47
  U1     EB77  DDR5_SA_DQ0  SOCKET4677_AZIFS054P001C01  I168

M_F_CPU1_SA_DQ<1>   @S9S_MB_2U_LIB.S9S_MB_2U(SCH_1):M_F_CPU1_SA_DQ<1>
  J27      9  DQ_A1  SCONN288_ADR50001P013C01  I179
  J28      9  DQ_A1  SCONN288_ADR50001P003C01  I47
  U1     EH77  DDR5_SA_DQ1  SOCKET4677_AZIFS054P001C01  I168

M_F_CPU1_SA_DQ<2>   @S9S_MB_2U_LIB.S9S_MB_2U(SCH_1):M_F_CPU1_SA_DQ<2>
  J27    152  DQ_A2  SCONN288_ADR50001P013C01  I179
  J28    152  DQ_A2  SCONN288_ADR50001P003C01  I47
  U1     ED77  DDR5_SA_DQ2  SOCKET4677_AZIFS054P001C01  I168

M_F_CPU1_SA_DQ<3>   @S9S_MB_2U_LIB.S9S_MB_2U(SCH_1):M_F_CPU1_SA_DQ<3>
  J27    154  DQ_A3  SCONN288_ADR50001P013C01  I179
  J28    154  DQ_A3  SCONN288_ADR50001P003C01  I47
  U1     EG78  DDR5_SA_DQ3  SOCKET4677_AZIFS054P001C01  I168

M_F_CPU1_SA_DQ<4>   @S9S_MB_2U_LIB.S9S_MB_2U(SCH_1):M_F_CPU1_SA_DQ<4>
  J27     14  DQ_A4  SCONN288_ADR50001P013C01  I179
  J28     14  DQ_A4  SCONN288_ADR50001P003C01  I47
  U1     ED75  DDR5_SA_DQ4  SOCKET4677_AZIFS054P001C01  I168

M_F_CPU1_SA_DQ<5>   @S9S_MB_2U_LIB.S9S_MB_2U(SCH_1):M_F_CPU1_SA_DQ<5>
  J27     16  DQ_A5  SCONN288_ADR50001P013C01  I179
  J28     16  DQ_A5  SCONN288_ADR50001P003C01  I47
  U1     EE74  DDR5_SA_DQ5  SOCKET4677_AZIFS054P001C01  I168

M_F_CPU1_SA_DQ<6>   @S9S_MB_2U_LIB.S9S_MB_2U(SCH_1):M_F_CPU1_SA_DQ<6>
  J27    159  DQ_A6  SCONN288_ADR50001P013C01  I179
  J28    159  DQ_A6  SCONN288_ADR50001P003C01  I47
  U1     EH75  DDR5_SA_DQ6  SOCKET4677_AZIFS054P001C01  I168

M_F_CPU1_SA_DQ<7>   @S9S_MB_2U_LIB.S9S_MB_2U(SCH_1):M_F_CPU1_SA_DQ<7>
  J27    161  DQ_A7  SCONN288_ADR50001P013C01  I179
  J28    161  DQ_A7  SCONN288_ADR50001P003C01  I47
  U1     EG74  DDR5_SA_DQ7  SOCKET4677_AZIFS054P001C01  I168

M_F_CPU1_SA_DQ<8>   @S9S_MB_2U_LIB.S9S_MB_2U(SCH_1):M_F_CPU1_SA_DQ<8>
  J27     18  DQ_A8  SCONN288_ADR50001P013C01  I179
  J28     18  DQ_A8  SCONN288_ADR50001P003C01  I47
  U1     DV69  DDR5_SA_DQ8  SOCKET4677_AZIFS054P001C01  I168

M_F_CPU1_SA_DQ<9>   @S9S_MB_2U_LIB.S9S_MB_2U(SCH_1):M_F_CPU1_SA_DQ<9>
  J27     20  DQ_A9  SCONN288_ADR50001P013C01  I179
  J28     20  DQ_A9  SCONN288_ADR50001P003C01  I47
  U1     DU68  DDR5_SA_DQ9  SOCKET4677_AZIFS054P001C01  I168

M_F_CPU1_SA_DQ<10>   @S9S_MB_2U_LIB.S9S_MB_2U(SCH_1):M_F_CPU1_SA_DQ<10>
  J27    163  DQ_A10  SCONN288_ADR50001P013C01  I179
  J28    163  DQ_A10  SCONN288_ADR50001P003C01  I47
  U1     DY69  DDR5_SA_DQ10  SOCKET4677_AZIFS054P001C01  I168

M_F_CPU1_SA_DQ<11>   @S9S_MB_2U_LIB.S9S_MB_2U(SCH_1):M_F_CPU1_SA_DQ<11>
  J27    165  DQ_A11  SCONN288_ADR50001P013C01  I179
  J28    165  DQ_A11  SCONN288_ADR50001P003C01  I47
  U1     EA68  DDR5_SA_DQ11  SOCKET4677_AZIFS054P001C01  I168

M_F_CPU1_SA_DQ<12>   @S9S_MB_2U_LIB.S9S_MB_2U(SCH_1):M_F_CPU1_SA_DQ<12>
  J27     25  DQ_A12  SCONN288_ADR50001P013C01  I179
  J28     25  DQ_A12  SCONN288_ADR50001P003C01  I47
  U1     DU66  DDR5_SA_DQ12  SOCKET4677_AZIFS054P001C01  I168

M_F_CPU1_SA_DQ<13>   @S9S_MB_2U_LIB.S9S_MB_2U(SCH_1):M_F_CPU1_SA_DQ<13>
  J27     27  DQ_A13  SCONN288_ADR50001P013C01  I179
  J28     27  DQ_A13  SCONN288_ADR50001P003C01  I47
  U1     DV65  DDR5_SA_DQ13  SOCKET4677_AZIFS054P001C01  I168

M_F_CPU1_SA_DQ<14>   @S9S_MB_2U_LIB.S9S_MB_2U(SCH_1):M_F_CPU1_SA_DQ<14>
  J27    170  DQ_A14  SCONN288_ADR50001P013C01  I179
  J28    170  DQ_A14  SCONN288_ADR50001P003C01  I47
  U1     EA66  DDR5_SA_DQ14  SOCKET4677_AZIFS054P001C01  I168

M_F_CPU1_SA_DQ<15>   @S9S_MB_2U_LIB.S9S_MB_2U(SCH_1):M_F_CPU1_SA_DQ<15>
  J27    172  DQ_A15  SCONN288_ADR50001P013C01  I179
  J28    172  DQ_A15  SCONN288_ADR50001P003C01  I47
  U1     DY65  DDR5_SA_DQ15  SOCKET4677_AZIFS054P001C01  I168

M_F_CPU1_SA_DQ<16>   @S9S_MB_2U_LIB.S9S_MB_2U(SCH_1):M_F_CPU1_SA_DQ<16>
  J27     29  DQ_A16  SCONN288_ADR50001P013C01  I179
  J28     29  DQ_A16  SCONN288_ADR50001P003C01  I47
  U1     EE66  DDR5_SA_DQ16  SOCKET4677_AZIFS054P001C01  I168

M_F_CPU1_SA_DQ<17>   @S9S_MB_2U_LIB.S9S_MB_2U(SCH_1):M_F_CPU1_SA_DQ<17>
  J27     31  DQ_A17  SCONN288_ADR50001P013C01  I179
  J28     31  DQ_A17  SCONN288_ADR50001P003C01  I47
  U1     ED65  DDR5_SA_DQ17  SOCKET4677_AZIFS054P001C01  I168

M_F_CPU1_SA_DQ<18>   @S9S_MB_2U_LIB.S9S_MB_2U(SCH_1):M_F_CPU1_SA_DQ<18>
  J27    174  DQ_A18  SCONN288_ADR50001P013C01  I179
  J28    174  DQ_A18  SCONN288_ADR50001P003C01  I47
  U1     EG66  DDR5_SA_DQ18  SOCKET4677_AZIFS054P001C01  I168

M_F_CPU1_SA_DQ<19>   @S9S_MB_2U_LIB.S9S_MB_2U(SCH_1):M_F_CPU1_SA_DQ<19>
  J27    176  DQ_A19  SCONN288_ADR50001P013C01  I179
  J28    176  DQ_A19  SCONN288_ADR50001P003C01  I47
  U1     EH65  DDR5_SA_DQ19  SOCKET4677_AZIFS054P001C01  I168

M_F_CPU1_SA_DQ<20>   @S9S_MB_2U_LIB.S9S_MB_2U(SCH_1):M_F_CPU1_SA_DQ<20>
  J27     36  DQ_A20  SCONN288_ADR50001P013C01  I179
  J28     36  DQ_A20  SCONN288_ADR50001P003C01  I47
  U1     ED63  DDR5_SA_DQ20  SOCKET4677_AZIFS054P001C01  I168

M_F_CPU1_SA_DQ<21>   @S9S_MB_2U_LIB.S9S_MB_2U(SCH_1):M_F_CPU1_SA_DQ<21>
  J27     38  DQ_A21  SCONN288_ADR50001P013C01  I179
  J28     38  DQ_A21  SCONN288_ADR50001P003C01  I47
  U1     EE62  DDR5_SA_DQ21  SOCKET4677_AZIFS054P001C01  I168

M_F_CPU1_SA_DQ<22>   @S9S_MB_2U_LIB.S9S_MB_2U(SCH_1):M_F_CPU1_SA_DQ<22>
  J27    181  DQ_A22  SCONN288_ADR50001P013C01  I179
  J28    181  DQ_A22  SCONN288_ADR50001P003C01  I47
  U1     EH63  DDR5_SA_DQ22  SOCKET4677_AZIFS054P001C01  I168

M_F_CPU1_SA_DQ<23>   @S9S_MB_2U_LIB.S9S_MB_2U(SCH_1):M_F_CPU1_SA_DQ<23>
  J27    183  DQ_A23  SCONN288_ADR50001P013C01  I179
  J28    183  DQ_A23  SCONN288_ADR50001P003C01  I47
  U1     EG62  DDR5_SA_DQ23  SOCKET4677_AZIFS054P001C01  I168

M_F_CPU1_SA_DQ<24>   @S9S_MB_2U_LIB.S9S_MB_2U(SCH_1):M_F_CPU1_SA_DQ<24>
  J27     40  DQ_A24  SCONN288_ADR50001P013C01  I179
  J28     40  DQ_A24  SCONN288_ADR50001P003C01  I47
  U1     DV57  DDR5_SA_DQ24  SOCKET4677_AZIFS054P001C01  I168

M_F_CPU1_SA_DQ<25>   @S9S_MB_2U_LIB.S9S_MB_2U(SCH_1):M_F_CPU1_SA_DQ<25>
  J27     42  DQ_A25  SCONN288_ADR50001P013C01  I179
  J28     42  DQ_A25  SCONN288_ADR50001P003C01  I47
  U1     DU56  DDR5_SA_DQ25  SOCKET4677_AZIFS054P001C01  I168

M_F_CPU1_SA_DQ<26>   @S9S_MB_2U_LIB.S9S_MB_2U(SCH_1):M_F_CPU1_SA_DQ<26>
  J27    185  DQ_A26  SCONN288_ADR50001P013C01  I179
  J28    185  DQ_A26  SCONN288_ADR50001P003C01  I47
  U1     DY57  DDR5_SA_DQ26  SOCKET4677_AZIFS054P001C01  I168

M_F_CPU1_SA_DQ<27>   @S9S_MB_2U_LIB.S9S_MB_2U(SCH_1):M_F_CPU1_SA_DQ<27>
  J27    187  DQ_A27  SCONN288_ADR50001P013C01  I179
  J28    187  DQ_A27  SCONN288_ADR50001P003C01  I47
  U1     EA56  DDR5_SA_DQ27  SOCKET4677_AZIFS054P001C01  I168

M_F_CPU1_SA_DQ<28>   @S9S_MB_2U_LIB.S9S_MB_2U(SCH_1):M_F_CPU1_SA_DQ<28>
  J27     47  DQ_A28  SCONN288_ADR50001P013C01  I179
  J28     47  DQ_A28  SCONN288_ADR50001P003C01  I47
  U1     DU54  DDR5_SA_DQ28  SOCKET4677_AZIFS054P001C01  I168

M_F_CPU1_SA_DQ<29>   @S9S_MB_2U_LIB.S9S_MB_2U(SCH_1):M_F_CPU1_SA_DQ<29>
  J27     49  DQ_A29  SCONN288_ADR50001P013C01  I179
  J28     49  DQ_A29  SCONN288_ADR50001P003C01  I47
  U1     DV53  DDR5_SA_DQ29  SOCKET4677_AZIFS054P001C01  I168

M_F_CPU1_SA_DQ<30>   @S9S_MB_2U_LIB.S9S_MB_2U(SCH_1):M_F_CPU1_SA_DQ<30>
  J27    192  DQ_A30  SCONN288_ADR50001P013C01  I179
  J28    192  DQ_A30  SCONN288_ADR50001P003C01  I47
  U1     EA54  DDR5_SA_DQ30  SOCKET4677_AZIFS054P001C01  I168

M_F_CPU1_SA_DQ<31>   @S9S_MB_2U_LIB.S9S_MB_2U(SCH_1):M_F_CPU1_SA_DQ<31>
  J27    194  DQ_A31  SCONN288_ADR50001P013C01  I179
  J28    194  DQ_A31  SCONN288_ADR50001P003C01  I47
  U1     DY53  DDR5_SA_DQ31  SOCKET4677_AZIFS054P001C01  I168

M_F_CPU1_SA_DQS_DN<0>   @S9S_MB_2U_LIB.S9S_MB_2U(SCH_1):M_F_CPU1_SA_DQS_DN<0>
  J27     12  DQS0_A_N  SCONN288_ADR50001P013C01  I177
  J28     12  DQS0_A_N  SCONN288_ADR50001P003C01  I124
  U1     EE76  DDR5_SA_DQS_DN0  SOCKET4677_AZIFS054P001C01  I168

M_F_CPU1_SA_DQS_DN<1>   @S9S_MB_2U_LIB.S9S_MB_2U(SCH_1):M_F_CPU1_SA_DQS_DN<1>
  J27     23  DQS1_A_N  SCONN288_ADR50001P013C01  I177
  J28     23  DQS1_A_N  SCONN288_ADR50001P003C01  I124
  U1     DT67  DDR5_SA_DQS_DN1  SOCKET4677_AZIFS054P001C01  I168

M_F_CPU1_SA_DQS_DN<2>   @S9S_MB_2U_LIB.S9S_MB_2U(SCH_1):M_F_CPU1_SA_DQS_DN<2>
  J27     34  DQS2_A_N  SCONN288_ADR50001P013C01  I177
  J28     34  DQS2_A_N  SCONN288_ADR50001P003C01  I124
  U1     EC64  DDR5_SA_DQS_DN2  SOCKET4677_AZIFS054P001C01  I168

M_F_CPU1_SA_DQS_DN<3>   @S9S_MB_2U_LIB.S9S_MB_2U(SCH_1):M_F_CPU1_SA_DQS_DN<3>
  J27     45  DQS3_A_N  SCONN288_ADR50001P013C01  I177
  J28     45  DQS3_A_N  SCONN288_ADR50001P003C01  I124
  U1     DV55  DDR5_SA_DQS_DN3  SOCKET4677_AZIFS054P001C01  I168

M_F_CPU1_SA_DQS_DN<4>   @S9S_MB_2U_LIB.S9S_MB_2U(SCH_1):M_F_CPU1_SA_DQS_DN<4>
  J27     56  DQS4_A_N  SCONN288_ADR50001P013C01  I177
  J28     56  DQS4_A_N  SCONN288_ADR50001P003C01  I124
  U1     EE58  DDR5_SA_DQS_DN4  SOCKET4677_AZIFS054P001C01  I168

M_F_CPU1_SA_DQS_DN<5>   @S9S_MB_2U_LIB.S9S_MB_2U(SCH_1):M_F_CPU1_SA_DQS_DN<5>
  J27    156  DQS5_A_N  SCONN288_ADR50001P013C01  I177
  J28    156  DQS5_A_N  SCONN288_ADR50001P003C01  I124
  U1     EJ76  DDR5_SA_DQS_DN5  SOCKET4677_AZIFS054P001C01  I168

M_F_CPU1_SA_DQS_DN<6>   @S9S_MB_2U_LIB.S9S_MB_2U(SCH_1):M_F_CPU1_SA_DQS_DN<6>
  J27    167  DQS6_A_N  SCONN288_ADR50001P013C01  I177
  J28    167  DQS6_A_N  SCONN288_ADR50001P003C01  I124
  U1     EB67  DDR5_SA_DQS_DN6  SOCKET4677_AZIFS054P001C01  I168

M_F_CPU1_SA_DQS_DN<7>   @S9S_MB_2U_LIB.S9S_MB_2U(SCH_1):M_F_CPU1_SA_DQS_DN<7>
  J27    178  DQS7_A_N  SCONN288_ADR50001P013C01  I177
  J28    178  DQS7_A_N  SCONN288_ADR50001P003C01  I124
  U1     EJ64  DDR5_SA_DQS_DN7  SOCKET4677_AZIFS054P001C01  I168

M_F_CPU1_SA_DQS_DN<8>   @S9S_MB_2U_LIB.S9S_MB_2U(SCH_1):M_F_CPU1_SA_DQS_DN<8>
  J27    189  DQS8_A_N  SCONN288_ADR50001P013C01  I177
  J28    189  DQS8_A_N  SCONN288_ADR50001P003C01  I124
  U1     EB55  DDR5_SA_DQS_DN8  SOCKET4677_AZIFS054P001C01  I168

M_F_CPU1_SA_DQS_DN<9>   @S9S_MB_2U_LIB.S9S_MB_2U(SCH_1):M_F_CPU1_SA_DQS_DN<9>
  J27    200  DQS9_A_N  SCONN288_ADR50001P013C01  I177
  J28    200  DQS9_A_N  SCONN288_ADR50001P003C01  I124
  U1     EJ58  DDR5_SA_DQS_DN9  SOCKET4677_AZIFS054P001C01  I168

M_F_CPU1_SA_DQS_DP<0>   @S9S_MB_2U_LIB.S9S_MB_2U(SCH_1):M_F_CPU1_SA_DQS_DP<0>
  J27     11  DQS0_A_P  SCONN288_ADR50001P013C01  I177
  J28     11  DQS0_A_P  SCONN288_ADR50001P003C01  I124
  U1     EC76  DDR5_SA_DQS_DP0  SOCKET4677_AZIFS054P001C01  I168

M_F_CPU1_SA_DQS_DP<1>   @S9S_MB_2U_LIB.S9S_MB_2U(SCH_1):M_F_CPU1_SA_DQS_DP<1>
  J27     22  DQS1_A_P  SCONN288_ADR50001P013C01  I177
  J28     22  DQS1_A_P  SCONN288_ADR50001P003C01  I124
  U1     DV67  DDR5_SA_DQS_DP1  SOCKET4677_AZIFS054P001C01  I168

M_F_CPU1_SA_DQS_DP<2>   @S9S_MB_2U_LIB.S9S_MB_2U(SCH_1):M_F_CPU1_SA_DQS_DP<2>
  J27     33  DQS2_A_P  SCONN288_ADR50001P013C01  I177
  J28     33  DQS2_A_P  SCONN288_ADR50001P003C01  I124
  U1     EE64  DDR5_SA_DQS_DP2  SOCKET4677_AZIFS054P001C01  I168

M_F_CPU1_SA_DQS_DP<3>   @S9S_MB_2U_LIB.S9S_MB_2U(SCH_1):M_F_CPU1_SA_DQS_DP<3>
  J27     44  DQS3_A_P  SCONN288_ADR50001P013C01  I177
  J28     44  DQS3_A_P  SCONN288_ADR50001P003C01  I124
  U1     DT55  DDR5_SA_DQS_DP3  SOCKET4677_AZIFS054P001C01  I168

M_F_CPU1_SA_DQS_DP<4>   @S9S_MB_2U_LIB.S9S_MB_2U(SCH_1):M_F_CPU1_SA_DQS_DP<4>
  J27     55  DQS4_A_P  SCONN288_ADR50001P013C01  I177
  J28     55  DQS4_A_P  SCONN288_ADR50001P003C01  I124
  U1     EC58  DDR5_SA_DQS_DP4  SOCKET4677_AZIFS054P001C01  I168

M_F_CPU1_SA_DQS_DP<5>   @S9S_MB_2U_LIB.S9S_MB_2U(SCH_1):M_F_CPU1_SA_DQS_DP<5>
  J27    157  DQS5_A_P  SCONN288_ADR50001P013C01  I177
  J28    157  DQS5_A_P  SCONN288_ADR50001P003C01  I124
  U1     EG76  DDR5_SA_DQS_DP5  SOCKET4677_AZIFS054P001C01  I168

M_F_CPU1_SA_DQS_DP<6>   @S9S_MB_2U_LIB.S9S_MB_2U(SCH_1):M_F_CPU1_SA_DQS_DP<6>
  J27    168  DQS6_A_P  SCONN288_ADR50001P013C01  I177
  J28    168  DQS6_A_P  SCONN288_ADR50001P003C01  I124
  U1     DY67  DDR5_SA_DQS_DP6  SOCKET4677_AZIFS054P001C01  I168

M_F_CPU1_SA_DQS_DP<7>   @S9S_MB_2U_LIB.S9S_MB_2U(SCH_1):M_F_CPU1_SA_DQS_DP<7>
  J27    179  DQS7_A_P  SCONN288_ADR50001P013C01  I177
  J28    179  DQS7_A_P  SCONN288_ADR50001P003C01  I124
  U1     EG64  DDR5_SA_DQS_DP7  SOCKET4677_AZIFS054P001C01  I168

M_F_CPU1_SA_DQS_DP<8>   @S9S_MB_2U_LIB.S9S_MB_2U(SCH_1):M_F_CPU1_SA_DQS_DP<8>
  J27    190  DQS8_A_P  SCONN288_ADR50001P013C01  I177
  J28    190  DQS8_A_P  SCONN288_ADR50001P003C01  I124
  U1     DY55  DDR5_SA_DQS_DP8  SOCKET4677_AZIFS054P001C01  I168

M_F_CPU1_SA_DQS_DP<9>   @S9S_MB_2U_LIB.S9S_MB_2U(SCH_1):M_F_CPU1_SA_DQS_DP<9>
  J27    201  DQS9_A_P  SCONN288_ADR50001P013C01  I177
  J28    201  DQS9_A_P  SCONN288_ADR50001P003C01  I124
  U1     EG58  DDR5_SA_DQS_DP9  SOCKET4677_AZIFS054P001C01  I168

M_F_CPU1_SA_PAR   @S9S_MB_2U_LIB.S9S_MB_2U(SCH_1):M_F_CPU1_SA_PAR
  J27     74  PAR_A  SCONN288_ADR50001P013C01  I179
  J28     74  PAR_A  SCONN288_ADR50001P003C01  I47
  U1     EA50  DDR5_SA_PAR  SOCKET4677_AZIFS054P001C01  I168

M_F_CPU1_SA_RSP<0>   @S9S_MB_2U_LIB.S9S_MB_2U(SCH_1):M_F_CPU1_SA_RSP<0>
  J27     86  LBD||RSP_N_A  SCONN288_ADR50001P013C01  I179
  U1     DN48  DDR5_A_RSP0  SOCKET4677_AZIFS054P001C01  I168

M_F_CPU1_SA_RSP<1>   @S9S_MB_2U_LIB.S9S_MB_2U(SCH_1):M_F_CPU1_SA_RSP<1>
  J28     86  LBD||RSP_N_A  SCONN288_ADR50001P003C01  I47
  U1     DP47  DDR5_A_RSP1  SOCKET4677_AZIFS054P001C01  I168

M_F_CPU1_SB_CA<0>   @S9S_MB_2U_LIB.S9S_MB_2U(SCH_1):M_F_CPU1_SB_CA<0>
  J27     76  CA0_B  SCONN288_ADR50001P013C01  I179
  J28     76  CA0_B  SCONN288_ADR50001P003C01  I47
  U1     DV51  DDR5_SB_CA0  SOCKET4677_AZIFS054P001C01  I168

M_F_CPU1_SB_CA<1>   @S9S_MB_2U_LIB.S9S_MB_2U(SCH_1):M_F_CPU1_SB_CA<1>
  J27    221  CA1_B  SCONN288_ADR50001P013C01  I179
  J28    221  CA1_B  SCONN288_ADR50001P003C01  I47
  U1     DU50  DDR5_SB_CA1  SOCKET4677_AZIFS054P001C01  I168

M_F_CPU1_SB_CA<2>   @S9S_MB_2U_LIB.S9S_MB_2U(SCH_1):M_F_CPU1_SB_CA<2>
  J27     78  CA2_B  SCONN288_ADR50001P013C01  I179
  J28     78  CA2_B  SCONN288_ADR50001P003C01  I47
  U1     EE41  DDR5_SB_CA2  SOCKET4677_AZIFS054P001C01  I168

M_F_CPU1_SB_CA<3>   @S9S_MB_2U_LIB.S9S_MB_2U(SCH_1):M_F_CPU1_SB_CA<3>
  J27    223  CA3_B  SCONN288_ADR50001P013C01  I179
  J28    223  CA3_B  SCONN288_ADR50001P003C01  I47
  U1     EG41  DDR5_SB_CA3  SOCKET4677_AZIFS054P001C01  I168

M_F_CPU1_SB_CA<4>   @S9S_MB_2U_LIB.S9S_MB_2U(SCH_1):M_F_CPU1_SB_CA<4>
  J27     80  CA4_B  SCONN288_ADR50001P013C01  I179
  J28     80  CA4_B  SCONN288_ADR50001P003C01  I47
  U1     ED40  DDR5_SB_CA4  SOCKET4677_AZIFS054P001C01  I168

M_F_CPU1_SB_CA<5>   @S9S_MB_2U_LIB.S9S_MB_2U(SCH_1):M_F_CPU1_SB_CA<5>
  J27    225  CA5_B  SCONN288_ADR50001P013C01  I179
  J28    225  CA5_B  SCONN288_ADR50001P003C01  I47
  U1     EH40  DDR5_SB_CA5  SOCKET4677_AZIFS054P001C01  I168

M_F_CPU1_SB_CA<6>   @S9S_MB_2U_LIB.S9S_MB_2U(SCH_1):M_F_CPU1_SB_CA<6>
  J27     82  CA6_B  SCONN288_ADR50001P013C01  I179
  J28     82  CA6_B  SCONN288_ADR50001P003C01  I47
  U1     EC39  DDR5_SB_CA6  SOCKET4677_AZIFS054P001C01  I168

M_F_CPU1_SB_CB<0>   @S9S_MB_2U_LIB.S9S_MB_2U(SCH_1):M_F_CPU1_SB_CB<0>
  J27     96  CB_B0  SCONN288_ADR50001P013C01  I179
  J28     96  CB_B0  SCONN288_ADR50001P003C01  I47
  U1     ED32  DDR5_SB_ECC0  SOCKET4677_AZIFS054P001C01  I168

M_F_CPU1_SB_CB<1>   @S9S_MB_2U_LIB.S9S_MB_2U(SCH_1):M_F_CPU1_SB_CB<1>
  J27     98  CB_B1  SCONN288_ADR50001P013C01  I179
  J28     98  CB_B1  SCONN288_ADR50001P003C01  I47
  U1     EE31  DDR5_SB_ECC1  SOCKET4677_AZIFS054P001C01  I168

M_F_CPU1_SB_CB<2>   @S9S_MB_2U_LIB.S9S_MB_2U(SCH_1):M_F_CPU1_SB_CB<2>
  J27    241  CB_B2  SCONN288_ADR50001P013C01  I179
  J28    241  CB_B2  SCONN288_ADR50001P003C01  I47
  U1     EH32  DDR5_SB_ECC2  SOCKET4677_AZIFS054P001C01  I168

M_F_CPU1_SB_CB<3>   @S9S_MB_2U_LIB.S9S_MB_2U(SCH_1):M_F_CPU1_SB_CB<3>
  J27    243  CB_B3  SCONN288_ADR50001P013C01  I179
  J28    243  CB_B3  SCONN288_ADR50001P003C01  I47
  U1     EG31  DDR5_SB_ECC3  SOCKET4677_AZIFS054P001C01  I168

M_F_CPU1_SB_CB<4>   @S9S_MB_2U_LIB.S9S_MB_2U(SCH_1):M_F_CPU1_SB_CB<4>
  J27     89  CB_B4  SCONN288_ADR50001P013C01  I179
  J28     89  CB_B4  SCONN288_ADR50001P003C01  I47
  U1     EE35  DDR5_SB_ECC4  SOCKET4677_AZIFS054P001C01  I168

M_F_CPU1_SB_CB<5>   @S9S_MB_2U_LIB.S9S_MB_2U(SCH_1):M_F_CPU1_SB_CB<5>
  J27     91  CB_B5  SCONN288_ADR50001P013C01  I179
  J28     91  CB_B5  SCONN288_ADR50001P003C01  I47
  U1     ED34  DDR5_SB_ECC5  SOCKET4677_AZIFS054P001C01  I168

M_F_CPU1_SB_CB<6>   @S9S_MB_2U_LIB.S9S_MB_2U(SCH_1):M_F_CPU1_SB_CB<6>
  J27    234  CB_B6  SCONN288_ADR50001P013C01  I179
  J28    234  CB_B6  SCONN288_ADR50001P003C01  I47
  U1     EG35  DDR5_SB_ECC6  SOCKET4677_AZIFS054P001C01  I168

M_F_CPU1_SB_CB<7>   @S9S_MB_2U_LIB.S9S_MB_2U(SCH_1):M_F_CPU1_SB_CB<7>
  J27    236  CB_B7  SCONN288_ADR50001P013C01  I179
  J28    236  CB_B7  SCONN288_ADR50001P003C01  I47
  U1     EH34  DDR5_SB_ECC7  SOCKET4677_AZIFS054P001C01  I168

M_F_CPU1_SB_CS_N<0>   @S9S_MB_2U_LIB.S9S_MB_2U(SCH_1):M_F_CPU1_SB_CS_N<0>
  J27     84  CS0_N_B  SCONN288_ADR50001P013C01  I179
  U1     EH38  DDR5_SB_CS0_N  SOCKET4677_AZIFS054P001C01  I168

M_F_CPU1_SB_CS_N<1>   @S9S_MB_2U_LIB.S9S_MB_2U(SCH_1):M_F_CPU1_SB_CS_N<1>
  J27    229  CS1_N_B  SCONN288_ADR50001P013C01  I179
  U1     EG37  DDR5_SB_CS1_N  SOCKET4677_AZIFS054P001C01  I168

M_F_CPU1_SB_CS_N<2>   @S9S_MB_2U_LIB.S9S_MB_2U(SCH_1):M_F_CPU1_SB_CS_N<2>
  J28     84  CS0_N_B  SCONN288_ADR50001P003C01  I47
  U1     ED38  DDR5_SB_CS2_N  SOCKET4677_AZIFS054P001C01  I168

M_F_CPU1_SB_CS_N<3>   @S9S_MB_2U_LIB.S9S_MB_2U(SCH_1):M_F_CPU1_SB_CS_N<3>
  J28    229  CS1_N_B  SCONN288_ADR50001P003C01  I47
  U1     EE37  DDR5_SB_CS3_N  SOCKET4677_AZIFS054P001C01  I168

M_F_CPU1_SB_DQ<0>   @S9S_MB_2U_LIB.S9S_MB_2U(SCH_1):M_F_CPU1_SB_DQ<0>
  J27    100  DQ_B0  SCONN288_ADR50001P013C01  I179
  J28    100  DQ_B0  SCONN288_ADR50001P003C01  I47
  U1     DV32  DDR5_SB_DQ0  SOCKET4677_AZIFS054P001C01  I168

M_F_CPU1_SB_DQ<1>   @S9S_MB_2U_LIB.S9S_MB_2U(SCH_1):M_F_CPU1_SB_DQ<1>
  J27    102  DQ_B1  SCONN288_ADR50001P013C01  I179
  J28    102  DQ_B1  SCONN288_ADR50001P003C01  I47
  U1     DU31  DDR5_SB_DQ1  SOCKET4677_AZIFS054P001C01  I168

M_F_CPU1_SB_DQ<2>   @S9S_MB_2U_LIB.S9S_MB_2U(SCH_1):M_F_CPU1_SB_DQ<2>
  J27    245  DQ_B2  SCONN288_ADR50001P013C01  I179
  J28    245  DQ_B2  SCONN288_ADR50001P003C01  I47
  U1     DY32  DDR5_SB_DQ2  SOCKET4677_AZIFS054P001C01  I168

M_F_CPU1_SB_DQ<3>   @S9S_MB_2U_LIB.S9S_MB_2U(SCH_1):M_F_CPU1_SB_DQ<3>
  J27    247  DQ_B3  SCONN288_ADR50001P013C01  I179
  J28    247  DQ_B3  SCONN288_ADR50001P003C01  I47
  U1     EA31  DDR5_SB_DQ3  SOCKET4677_AZIFS054P001C01  I168

M_F_CPU1_SB_DQ<4>   @S9S_MB_2U_LIB.S9S_MB_2U(SCH_1):M_F_CPU1_SB_DQ<4>
  J27    107  DQ_B4  SCONN288_ADR50001P013C01  I179
  J28    107  DQ_B4  SCONN288_ADR50001P003C01  I47
  U1     DU29  DDR5_SB_DQ4  SOCKET4677_AZIFS054P001C01  I168

M_F_CPU1_SB_DQ<5>   @S9S_MB_2U_LIB.S9S_MB_2U(SCH_1):M_F_CPU1_SB_DQ<5>
  J27    109  DQ_B5  SCONN288_ADR50001P013C01  I179
  J28    109  DQ_B5  SCONN288_ADR50001P003C01  I47
  U1     DV28  DDR5_SB_DQ5  SOCKET4677_AZIFS054P001C01  I168

M_F_CPU1_SB_DQ<6>   @S9S_MB_2U_LIB.S9S_MB_2U(SCH_1):M_F_CPU1_SB_DQ<6>
  J27    252  DQ_B6  SCONN288_ADR50001P013C01  I179
  J28    252  DQ_B6  SCONN288_ADR50001P003C01  I47
  U1     EA29  DDR5_SB_DQ6  SOCKET4677_AZIFS054P001C01  I168

M_F_CPU1_SB_DQ<7>   @S9S_MB_2U_LIB.S9S_MB_2U(SCH_1):M_F_CPU1_SB_DQ<7>
  J27    254  DQ_B7  SCONN288_ADR50001P013C01  I179
  J28    254  DQ_B7  SCONN288_ADR50001P003C01  I47
  U1     DY28  DDR5_SB_DQ7  SOCKET4677_AZIFS054P001C01  I168

M_F_CPU1_SB_DQ<8>   @S9S_MB_2U_LIB.S9S_MB_2U(SCH_1):M_F_CPU1_SB_DQ<8>
  J27    111  DQ_B8  SCONN288_ADR50001P013C01  I179
  J28    111  DQ_B8  SCONN288_ADR50001P003C01  I47
  U1     EE23  DDR5_SB_DQ8  SOCKET4677_AZIFS054P001C01  I168

M_F_CPU1_SB_DQ<9>   @S9S_MB_2U_LIB.S9S_MB_2U(SCH_1):M_F_CPU1_SB_DQ<9>
  J27    113  DQ_B9  SCONN288_ADR50001P013C01  I179
  J28    113  DQ_B9  SCONN288_ADR50001P003C01  I47
  U1     ED22  DDR5_SB_DQ9  SOCKET4677_AZIFS054P001C01  I168

M_F_CPU1_SB_DQ<10>   @S9S_MB_2U_LIB.S9S_MB_2U(SCH_1):M_F_CPU1_SB_DQ<10>
  J27    256  DQ_B10  SCONN288_ADR50001P013C01  I179
  J28    256  DQ_B10  SCONN288_ADR50001P003C01  I47
  U1     EG23  DDR5_SB_DQ10  SOCKET4677_AZIFS054P001C01  I168

M_F_CPU1_SB_DQ<11>   @S9S_MB_2U_LIB.S9S_MB_2U(SCH_1):M_F_CPU1_SB_DQ<11>
  J27    258  DQ_B11  SCONN288_ADR50001P013C01  I179
  J28    258  DQ_B11  SCONN288_ADR50001P003C01  I47
  U1     EH22  DDR5_SB_DQ11  SOCKET4677_AZIFS054P001C01  I168

M_F_CPU1_SB_DQ<12>   @S9S_MB_2U_LIB.S9S_MB_2U(SCH_1):M_F_CPU1_SB_DQ<12>
  J27    118  DQ_B12  SCONN288_ADR50001P013C01  I179
  J28    118  DQ_B12  SCONN288_ADR50001P003C01  I47
  U1     ED20  DDR5_SB_DQ12  SOCKET4677_AZIFS054P001C01  I168

M_F_CPU1_SB_DQ<13>   @S9S_MB_2U_LIB.S9S_MB_2U(SCH_1):M_F_CPU1_SB_DQ<13>
  J27    120  DQ_B13  SCONN288_ADR50001P013C01  I179
  J28    120  DQ_B13  SCONN288_ADR50001P003C01  I47
  U1     EE19  DDR5_SB_DQ13  SOCKET4677_AZIFS054P001C01  I168

M_F_CPU1_SB_DQ<14>   @S9S_MB_2U_LIB.S9S_MB_2U(SCH_1):M_F_CPU1_SB_DQ<14>
  J27    263  DQ_B14  SCONN288_ADR50001P013C01  I179
  J28    263  DQ_B14  SCONN288_ADR50001P003C01  I47
  U1     EH20  DDR5_SB_DQ14  SOCKET4677_AZIFS054P001C01  I168

M_F_CPU1_SB_DQ<15>   @S9S_MB_2U_LIB.S9S_MB_2U(SCH_1):M_F_CPU1_SB_DQ<15>
  J27    265  DQ_B15  SCONN288_ADR50001P013C01  I179
  J28    265  DQ_B15  SCONN288_ADR50001P003C01  I47
  U1     EG19  DDR5_SB_DQ15  SOCKET4677_AZIFS054P001C01  I168

M_F_CPU1_SB_DQ<16>   @S9S_MB_2U_LIB.S9S_MB_2U(SCH_1):M_F_CPU1_SB_DQ<16>
  J27    122  DQ_B16  SCONN288_ADR50001P013C01  I179
  J28    122  DQ_B16  SCONN288_ADR50001P003C01  I47
  U1     EM14  DDR5_SB_DQ16  SOCKET4677_AZIFS054P001C01  I168

M_F_CPU1_SB_DQ<17>   @S9S_MB_2U_LIB.S9S_MB_2U(SCH_1):M_F_CPU1_SB_DQ<17>
  J27    124  DQ_B17  SCONN288_ADR50001P013C01  I179
  J28    124  DQ_B17  SCONN288_ADR50001P003C01  I47
  U1     EL13  DDR5_SB_DQ17  SOCKET4677_AZIFS054P001C01  I168

M_F_CPU1_SB_DQ<18>   @S9S_MB_2U_LIB.S9S_MB_2U(SCH_1):M_F_CPU1_SB_DQ<18>
  J27    267  DQ_B18  SCONN288_ADR50001P013C01  I179
  J28    267  DQ_B18  SCONN288_ADR50001P003C01  I47
  U1     EP14  DDR5_SB_DQ18  SOCKET4677_AZIFS054P001C01  I168

M_F_CPU1_SB_DQ<19>   @S9S_MB_2U_LIB.S9S_MB_2U(SCH_1):M_F_CPU1_SB_DQ<19>
  J27    269  DQ_B19  SCONN288_ADR50001P013C01  I179
  J28    269  DQ_B19  SCONN288_ADR50001P003C01  I47
  U1     ER13  DDR5_SB_DQ19  SOCKET4677_AZIFS054P001C01  I168

M_F_CPU1_SB_DQ<20>   @S9S_MB_2U_LIB.S9S_MB_2U(SCH_1):M_F_CPU1_SB_DQ<20>
  J27    129  DQ_B20  SCONN288_ADR50001P013C01  I179
  J28    129  DQ_B20  SCONN288_ADR50001P003C01  I47
  U1     EL11  DDR5_SB_DQ20  SOCKET4677_AZIFS054P001C01  I168

M_F_CPU1_SB_DQ<21>   @S9S_MB_2U_LIB.S9S_MB_2U(SCH_1):M_F_CPU1_SB_DQ<21>
  J27    131  DQ_B21  SCONN288_ADR50001P013C01  I179
  J28    131  DQ_B21  SCONN288_ADR50001P003C01  I47
  U1     EM10  DDR5_SB_DQ21  SOCKET4677_AZIFS054P001C01  I168

M_F_CPU1_SB_DQ<22>   @S9S_MB_2U_LIB.S9S_MB_2U(SCH_1):M_F_CPU1_SB_DQ<22>
  J27    274  DQ_B22  SCONN288_ADR50001P013C01  I179
  J28    274  DQ_B22  SCONN288_ADR50001P003C01  I47
  U1     ER11  DDR5_SB_DQ22  SOCKET4677_AZIFS054P001C01  I168

M_F_CPU1_SB_DQ<23>   @S9S_MB_2U_LIB.S9S_MB_2U(SCH_1):M_F_CPU1_SB_DQ<23>
  J27    276  DQ_B23  SCONN288_ADR50001P013C01  I179
  J28    276  DQ_B23  SCONN288_ADR50001P003C01  I47
  U1     EP10  DDR5_SB_DQ23  SOCKET4677_AZIFS054P001C01  I168

M_F_CPU1_SB_DQ<24>   @S9S_MB_2U_LIB.S9S_MB_2U(SCH_1):M_F_CPU1_SB_DQ<24>
  J27    133  DQ_B24  SCONN288_ADR50001P013C01  I179
  J28    133  DQ_B24  SCONN288_ADR50001P003C01  I47
  U1     DV20  DDR5_SB_DQ24  SOCKET4677_AZIFS054P001C01  I168

M_F_CPU1_SB_DQ<25>   @S9S_MB_2U_LIB.S9S_MB_2U(SCH_1):M_F_CPU1_SB_DQ<25>
  J27    135  DQ_B25  SCONN288_ADR50001P013C01  I179
  J28    135  DQ_B25  SCONN288_ADR50001P003C01  I47
  U1     DU19  DDR5_SB_DQ25  SOCKET4677_AZIFS054P001C01  I168

M_F_CPU1_SB_DQ<26>   @S9S_MB_2U_LIB.S9S_MB_2U(SCH_1):M_F_CPU1_SB_DQ<26>
  J27    278  DQ_B26  SCONN288_ADR50001P013C01  I179
  J28    278  DQ_B26  SCONN288_ADR50001P003C01  I47
  U1     DY20  DDR5_SB_DQ26  SOCKET4677_AZIFS054P001C01  I168

M_F_CPU1_SB_DQ<27>   @S9S_MB_2U_LIB.S9S_MB_2U(SCH_1):M_F_CPU1_SB_DQ<27>
  J27    280  DQ_B27  SCONN288_ADR50001P013C01  I179
  J28    280  DQ_B27  SCONN288_ADR50001P003C01  I47
  U1     EA19  DDR5_SB_DQ27  SOCKET4677_AZIFS054P001C01  I168

M_F_CPU1_SB_DQ<28>   @S9S_MB_2U_LIB.S9S_MB_2U(SCH_1):M_F_CPU1_SB_DQ<28>
  J27    140  DQ_B28  SCONN288_ADR50001P013C01  I179
  J28    140  DQ_B28  SCONN288_ADR50001P003C01  I47
  U1     EA17  DDR5_SB_DQ28  SOCKET4677_AZIFS054P001C01  I168

M_F_CPU1_SB_DQ<29>   @S9S_MB_2U_LIB.S9S_MB_2U(SCH_1):M_F_CPU1_SB_DQ<29>
  J27    142  DQ_B29  SCONN288_ADR50001P013C01  I179
  J28    142  DQ_B29  SCONN288_ADR50001P003C01  I47
  U1     DU17  DDR5_SB_DQ29  SOCKET4677_AZIFS054P001C01  I168

M_F_CPU1_SB_DQ<30>   @S9S_MB_2U_LIB.S9S_MB_2U(SCH_1):M_F_CPU1_SB_DQ<30>
  J27    285  DQ_B30  SCONN288_ADR50001P013C01  I179
  J28    285  DQ_B30  SCONN288_ADR50001P003C01  I47
  U1     EC17  DDR5_SB_DQ30  SOCKET4677_AZIFS054P001C01  I168

M_F_CPU1_SB_DQ<31>   @S9S_MB_2U_LIB.S9S_MB_2U(SCH_1):M_F_CPU1_SB_DQ<31>
  J27    287  DQ_B31  SCONN288_ADR50001P013C01  I179
  J28    287  DQ_B31  SCONN288_ADR50001P003C01  I47
  U1     DR17  DDR5_SB_DQ31  SOCKET4677_AZIFS054P001C01  I168

M_F_CPU1_SB_DQS_DN<0>   @S9S_MB_2U_LIB.S9S_MB_2U(SCH_1):M_F_CPU1_SB_DQS_DN<0>
  J27    105  DQS0_B_N  SCONN288_ADR50001P013C01  I177
  J28    105  DQS0_B_N  SCONN288_ADR50001P003C01  I124
  U1     DV30  DDR5_SB_DQS_DN0  SOCKET4677_AZIFS054P001C01  I168

M_F_CPU1_SB_DQS_DN<1>   @S9S_MB_2U_LIB.S9S_MB_2U(SCH_1):M_F_CPU1_SB_DQS_DN<1>
  J27    116  DQS1_B_N  SCONN288_ADR50001P013C01  I177
  J28    116  DQS1_B_N  SCONN288_ADR50001P003C01  I124
  U1     EE21  DDR5_SB_DQS_DN1  SOCKET4677_AZIFS054P001C01  I168

M_F_CPU1_SB_DQS_DN<2>   @S9S_MB_2U_LIB.S9S_MB_2U(SCH_1):M_F_CPU1_SB_DQS_DN<2>
  J27    127  DQS2_B_N  SCONN288_ADR50001P013C01  I177
  J28    127  DQS2_B_N  SCONN288_ADR50001P003C01  I124
  U1     EM12  DDR5_SB_DQS_DN2  SOCKET4677_AZIFS054P001C01  I168

M_F_CPU1_SB_DQS_DN<3>   @S9S_MB_2U_LIB.S9S_MB_2U(SCH_1):M_F_CPU1_SB_DQS_DN<3>
  J27    138  DQS3_B_N  SCONN288_ADR50001P013C01  I177
  J28    138  DQS3_B_N  SCONN288_ADR50001P003C01  I124
  U1     DT18  DDR5_SB_DQS_DN3  SOCKET4677_AZIFS054P001C01  I168

M_F_CPU1_SB_DQS_DN<4>   @S9S_MB_2U_LIB.S9S_MB_2U(SCH_1):M_F_CPU1_SB_DQS_DN<4>
  J27    238  DQS4_B_N  SCONN288_ADR50001P013C01  I177
  J28    238  DQS4_B_N  SCONN288_ADR50001P003C01  I124
  U1     EJ33  DDR5_SB_DQS_DN4  SOCKET4677_AZIFS054P001C01  I168

M_F_CPU1_SB_DQS_DN<5>   @S9S_MB_2U_LIB.S9S_MB_2U(SCH_1):M_F_CPU1_SB_DQS_DN<5>
  J27    249  DQS5_B_N  SCONN288_ADR50001P013C01  I177
  J28    249  DQS5_B_N  SCONN288_ADR50001P003C01  I124
  U1     EB30  DDR5_SB_DQS_DN5  SOCKET4677_AZIFS054P001C01  I168

M_F_CPU1_SB_DQS_DN<6>   @S9S_MB_2U_LIB.S9S_MB_2U(SCH_1):M_F_CPU1_SB_DQS_DN<6>
  J27    260  DQS6_B_N  SCONN288_ADR50001P013C01  I177
  J28    260  DQS6_B_N  SCONN288_ADR50001P003C01  I124
  U1     EJ21  DDR5_SB_DQS_DN6  SOCKET4677_AZIFS054P001C01  I168

M_F_CPU1_SB_DQS_DN<7>   @S9S_MB_2U_LIB.S9S_MB_2U(SCH_1):M_F_CPU1_SB_DQS_DN<7>
  J27    271  DQS7_B_N  SCONN288_ADR50001P013C01  I177
  J28    271  DQS7_B_N  SCONN288_ADR50001P003C01  I124
  U1     ET12  DDR5_SB_DQS_DN7  SOCKET4677_AZIFS054P001C01  I168

M_F_CPU1_SB_DQS_DN<8>   @S9S_MB_2U_LIB.S9S_MB_2U(SCH_1):M_F_CPU1_SB_DQS_DN<8>
  J27    282  DQS8_B_N  SCONN288_ADR50001P013C01  I177
  J28    282  DQS8_B_N  SCONN288_ADR50001P003C01  I124
  U1     DY18  DDR5_SB_DQS_DN8  SOCKET4677_AZIFS054P001C01  I168

M_F_CPU1_SB_DQS_DN<9>   @S9S_MB_2U_LIB.S9S_MB_2U(SCH_1):M_F_CPU1_SB_DQS_DN<9>
  J27     94  DQS9_B_N  SCONN288_ADR50001P013C01  I177
  J28     94  DQS9_B_N  SCONN288_ADR50001P003C01  I124
  U1     EE33  DDR5_SB_DQS_DN9  SOCKET4677_AZIFS054P001C01  I168

M_F_CPU1_SB_DQS_DP<0>   @S9S_MB_2U_LIB.S9S_MB_2U(SCH_1):M_F_CPU1_SB_DQS_DP<0>
  J27    104  DQS0_B_P  SCONN288_ADR50001P013C01  I177
  J28    104  DQS0_B_P  SCONN288_ADR50001P003C01  I124
  U1     DT30  DDR5_SB_DQS_DP0  SOCKET4677_AZIFS054P001C01  I168

M_F_CPU1_SB_DQS_DP<1>   @S9S_MB_2U_LIB.S9S_MB_2U(SCH_1):M_F_CPU1_SB_DQS_DP<1>
  J27    115  DQS1_B_P  SCONN288_ADR50001P013C01  I177
  J28    115  DQS1_B_P  SCONN288_ADR50001P003C01  I124
  U1     EC21  DDR5_SB_DQS_DP1  SOCKET4677_AZIFS054P001C01  I168

M_F_CPU1_SB_DQS_DP<2>   @S9S_MB_2U_LIB.S9S_MB_2U(SCH_1):M_F_CPU1_SB_DQS_DP<2>
  J27    126  DQS2_B_P  SCONN288_ADR50001P013C01  I177
  J28    126  DQS2_B_P  SCONN288_ADR50001P003C01  I124
  U1     EK12  DDR5_SB_DQS_DP2  SOCKET4677_AZIFS054P001C01  I168

M_F_CPU1_SB_DQS_DP<3>   @S9S_MB_2U_LIB.S9S_MB_2U(SCH_1):M_F_CPU1_SB_DQS_DP<3>
  J27    137  DQS3_B_P  SCONN288_ADR50001P013C01  I177
  J28    137  DQS3_B_P  SCONN288_ADR50001P003C01  I124
  U1     DV18  DDR5_SB_DQS_DP3  SOCKET4677_AZIFS054P001C01  I168

M_F_CPU1_SB_DQS_DP<4>   @S9S_MB_2U_LIB.S9S_MB_2U(SCH_1):M_F_CPU1_SB_DQS_DP<4>
  J27    239  DQS4_B_P  SCONN288_ADR50001P013C01  I177
  J28    239  DQS4_B_P  SCONN288_ADR50001P003C01  I124
  U1     EG33  DDR5_SB_DQS_DP4  SOCKET4677_AZIFS054P001C01  I168

M_F_CPU1_SB_DQS_DP<5>   @S9S_MB_2U_LIB.S9S_MB_2U(SCH_1):M_F_CPU1_SB_DQS_DP<5>
  J27    250  DQS5_B_P  SCONN288_ADR50001P013C01  I177
  J28    250  DQS5_B_P  SCONN288_ADR50001P003C01  I124
  U1     DY30  DDR5_SB_DQS_DP5  SOCKET4677_AZIFS054P001C01  I168

M_F_CPU1_SB_DQS_DP<6>   @S9S_MB_2U_LIB.S9S_MB_2U(SCH_1):M_F_CPU1_SB_DQS_DP<6>
  J27    261  DQS6_B_P  SCONN288_ADR50001P013C01  I177
  J28    261  DQS6_B_P  SCONN288_ADR50001P003C01  I124
  U1     EG21  DDR5_SB_DQS_DP6  SOCKET4677_AZIFS054P001C01  I168

M_F_CPU1_SB_DQS_DP<7>   @S9S_MB_2U_LIB.S9S_MB_2U(SCH_1):M_F_CPU1_SB_DQS_DP<7>
  J27    272  DQS7_B_P  SCONN288_ADR50001P013C01  I177
  J28    272  DQS7_B_P  SCONN288_ADR50001P003C01  I124
  U1     EP12  DDR5_SB_DQS_DP7  SOCKET4677_AZIFS054P001C01  I168

M_F_CPU1_SB_DQS_DP<8>   @S9S_MB_2U_LIB.S9S_MB_2U(SCH_1):M_F_CPU1_SB_DQS_DP<8>
  J27    283  DQS8_B_P  SCONN288_ADR50001P013C01  I177
  J28    283  DQS8_B_P  SCONN288_ADR50001P003C01  I124
  U1     EB18  DDR5_SB_DQS_DP8  SOCKET4677_AZIFS054P001C01  I168

M_F_CPU1_SB_DQS_DP<9>   @S9S_MB_2U_LIB.S9S_MB_2U(SCH_1):M_F_CPU1_SB_DQS_DP<9>
  J27     93  DQS9_B_P  SCONN288_ADR50001P013C01  I177
  J28     93  DQS9_B_P  SCONN288_ADR50001P003C01  I124
  U1     EC33  DDR5_SB_DQS_DP9  SOCKET4677_AZIFS054P001C01  I168

M_F_CPU1_SB_PAR   @S9S_MB_2U_LIB.S9S_MB_2U(SCH_1):M_F_CPU1_SB_PAR
  J27    227  PAR_B  SCONN288_ADR50001P013C01  I179
  J28    227  PAR_B  SCONN288_ADR50001P003C01  I47
  U1     EJ39  DDR5_SB_PAR  SOCKET4677_AZIFS054P001C01  I168

M_F_CPU1_SB_RSP<0>   @S9S_MB_2U_LIB.S9S_MB_2U(SCH_1):M_F_CPU1_SB_RSP<0>
  J27     87  LBS||RSP_N_B  SCONN288_ADR50001P013C01  I179
  U1     DL48  DDR5_B_RSP0  SOCKET4677_AZIFS054P001C01  I168

M_F_CPU1_SB_RSP<1>   @S9S_MB_2U_LIB.S9S_MB_2U(SCH_1):M_F_CPU1_SB_RSP<1>
  J28     87  LBS||RSP_N_B  SCONN288_ADR50001P003C01  I47
  U1     DK47  DDR5_B_RSP1  SOCKET4677_AZIFS054P001C01  I168

M_G_CPU0_ALERT_N   @S9S_MB_2U_LIB.S9S_MB_2U(SCH_1):M_G_CPU0_ALERT_N
  J13     62  ALERT_N  SCONN288_ADR50001P013C01  I11
  J14     62  ALERT_N  SCONN288_ADR50001P003C01  I47
  U2     CW50  DDR6_ALERT_N  SOCKET4677_AZIFS054P001C01  I169

M_G_CPU0_CLK_DN<0>   @S9S_MB_2U_LIB.S9S_MB_2U(SCH_1):M_G_CPU0_CLK_DN<0>
  J13    218   CK_N  SCONN288_ADR50001P013C01  I11
  U2     DR45  DDR6_CLK_DN0  SOCKET4677_AZIFS054P001C01  I169

M_G_CPU0_CLK_DN<1>   @S9S_MB_2U_LIB.S9S_MB_2U(SCH_1):M_G_CPU0_CLK_DN<1>
  J14    218   CK_N  SCONN288_ADR50001P003C01  I47
  U2     DL45  DDR6_CLK_DN1  SOCKET4677_AZIFS054P001C01  I169

M_G_CPU0_CLK_DP<0>   @S9S_MB_2U_LIB.S9S_MB_2U(SCH_1):M_G_CPU0_CLK_DP<0>
  J13    217   CK_P  SCONN288_ADR50001P013C01  I11
  U2     DN45  DDR6_CLK_DP0  SOCKET4677_AZIFS054P001C01  I169

M_G_CPU0_CLK_DP<1>   @S9S_MB_2U_LIB.S9S_MB_2U(SCH_1):M_G_CPU0_CLK_DP<1>
  J14    217   CK_P  SCONN288_ADR50001P003C01  I47
  U2     DJ45  DDR6_CLK_DP1  SOCKET4677_AZIFS054P001C01  I169

M_G_CPU0_SA_CA<0>   @S9S_MB_2U_LIB.S9S_MB_2U(SCH_1):M_G_CPU0_SA_CA<0>
  J13     66  CA0_A  SCONN288_ADR50001P013C01  I11
  J14     66  CA0_A  SCONN288_ADR50001P003C01  I47
  U2     DJ52  DDR6_SA_CA0  SOCKET4677_AZIFS054P001C01  I169

M_G_CPU0_SA_CA<1>   @S9S_MB_2U_LIB.S9S_MB_2U(SCH_1):M_G_CPU0_SA_CA<1>
  J13    211  CA1_A  SCONN288_ADR50001P013C01  I11
  J14    211  CA1_A  SCONN288_ADR50001P003C01  I47
  U2     DR52  DDR6_SA_CA1  SOCKET4677_AZIFS054P001C01  I169

M_G_CPU0_SA_CA<2>   @S9S_MB_2U_LIB.S9S_MB_2U(SCH_1):M_G_CPU0_SA_CA<2>
  J13     68  CA2_A  SCONN288_ADR50001P013C01  I11
  J14     68  CA2_A  SCONN288_ADR50001P003C01  I47
  U2     DK51  DDR6_SA_CA2  SOCKET4677_AZIFS054P001C01  I169

M_G_CPU0_SA_CA<3>   @S9S_MB_2U_LIB.S9S_MB_2U(SCH_1):M_G_CPU0_SA_CA<3>
  J13    213  CA3_A  SCONN288_ADR50001P013C01  I11
  J14    213  CA3_A  SCONN288_ADR50001P003C01  I47
  U2     DP51  DDR6_SA_CA3  SOCKET4677_AZIFS054P001C01  I169

M_G_CPU0_SA_CA<4>   @S9S_MB_2U_LIB.S9S_MB_2U(SCH_1):M_G_CPU0_SA_CA<4>
  J13     70  CA4_A  SCONN288_ADR50001P013C01  I11
  J14     70  CA4_A  SCONN288_ADR50001P003C01  I47
  U2     DL50  DDR6_SA_CA4  SOCKET4677_AZIFS054P001C01  I169

M_G_CPU0_SA_CA<5>   @S9S_MB_2U_LIB.S9S_MB_2U(SCH_1):M_G_CPU0_SA_CA<5>
  J13    215  CA5_A  SCONN288_ADR50001P013C01  I11
  J14    215  CA5_A  SCONN288_ADR50001P003C01  I47
  U2     DN50  DDR6_SA_CA5  SOCKET4677_AZIFS054P001C01  I169

M_G_CPU0_SA_CA<6>   @S9S_MB_2U_LIB.S9S_MB_2U(SCH_1):M_G_CPU0_SA_CA<6>
  J13     72  CA6_A  SCONN288_ADR50001P013C01  I11
  J14     72  CA6_A  SCONN288_ADR50001P003C01  I47
  U2     DK44  DDR6_SA_CA6  SOCKET4677_AZIFS054P001C01  I169

M_G_CPU0_SA_CB<0>   @S9S_MB_2U_LIB.S9S_MB_2U(SCH_1):M_G_CPU0_SA_CB<0>
  J13     51  CB_A0  SCONN288_ADR50001P013C01  I11
  J14     51  CB_A0  SCONN288_ADR50001P003C01  I47
  U2     DL60  DDR6_SA_ECC0  SOCKET4677_AZIFS054P001C01  I169

M_G_CPU0_SA_CB<1>   @S9S_MB_2U_LIB.S9S_MB_2U(SCH_1):M_G_CPU0_SA_CB<1>
  J13     53  CB_A1  SCONN288_ADR50001P013C01  I11
  J14     53  CB_A1  SCONN288_ADR50001P003C01  I47
  U2     DK59  DDR6_SA_ECC1  SOCKET4677_AZIFS054P001C01  I169

M_G_CPU0_SA_CB<2>   @S9S_MB_2U_LIB.S9S_MB_2U(SCH_1):M_G_CPU0_SA_CB<2>
  J13    196  CB_A2  SCONN288_ADR50001P013C01  I11
  J14    196  CB_A2  SCONN288_ADR50001P003C01  I47
  U2     DN60  DDR6_SA_ECC2  SOCKET4677_AZIFS054P001C01  I169

M_G_CPU0_SA_CB<3>   @S9S_MB_2U_LIB.S9S_MB_2U(SCH_1):M_G_CPU0_SA_CB<3>
  J13    198  CB_A3  SCONN288_ADR50001P013C01  I11
  J14    198  CB_A3  SCONN288_ADR50001P003C01  I47
  U2     DP59  DDR6_SA_ECC3  SOCKET4677_AZIFS054P001C01  I169

M_G_CPU0_SA_CB<4>   @S9S_MB_2U_LIB.S9S_MB_2U(SCH_1):M_G_CPU0_SA_CB<4>
  J13     58  CB_A4  SCONN288_ADR50001P013C01  I11
  J14     58  CB_A4  SCONN288_ADR50001P003C01  I47
  U2     DK57  DDR6_SA_ECC4  SOCKET4677_AZIFS054P001C01  I169

M_G_CPU0_SA_CB<5>   @S9S_MB_2U_LIB.S9S_MB_2U(SCH_1):M_G_CPU0_SA_CB<5>
  J13     60  CB_A5  SCONN288_ADR50001P013C01  I11
  J14     60  CB_A5  SCONN288_ADR50001P003C01  I47
  U2     DL56  DDR6_SA_ECC5  SOCKET4677_AZIFS054P001C01  I169

M_G_CPU0_SA_CB<6>   @S9S_MB_2U_LIB.S9S_MB_2U(SCH_1):M_G_CPU0_SA_CB<6>
  J13    203  CB_A6  SCONN288_ADR50001P013C01  I11
  J14    203  CB_A6  SCONN288_ADR50001P003C01  I47
  U2     DP57  DDR6_SA_ECC6  SOCKET4677_AZIFS054P001C01  I169

M_G_CPU0_SA_CB<7>   @S9S_MB_2U_LIB.S9S_MB_2U(SCH_1):M_G_CPU0_SA_CB<7>
  J13    205  CB_A7  SCONN288_ADR50001P013C01  I11
  J14    205  CB_A7  SCONN288_ADR50001P003C01  I47
  U2     DN56  DDR6_SA_ECC7  SOCKET4677_AZIFS054P001C01  I169

M_G_CPU0_SA_CS_N<0>   @S9S_MB_2U_LIB.S9S_MB_2U(SCH_1):M_G_CPU0_SA_CS_N<0>
  J13     64  CS0_N_A  SCONN288_ADR50001P013C01  I11
  U2     DN54  DDR6_SA_CS0_N  SOCKET4677_AZIFS054P001C01  I169

M_G_CPU0_SA_CS_N<1>   @S9S_MB_2U_LIB.S9S_MB_2U(SCH_1):M_G_CPU0_SA_CS_N<1>
  J13    209  CS1_N_A  SCONN288_ADR50001P013C01  I11
  U2     DP53  DDR6_SA_CS1_N  SOCKET4677_AZIFS054P001C01  I169

M_G_CPU0_SA_CS_N<2>   @S9S_MB_2U_LIB.S9S_MB_2U(SCH_1):M_G_CPU0_SA_CS_N<2>
  J14     64  CS0_N_A  SCONN288_ADR50001P003C01  I47
  U2     DL54  DDR6_SA_CS2_N  SOCKET4677_AZIFS054P001C01  I169

M_G_CPU0_SA_CS_N<3>   @S9S_MB_2U_LIB.S9S_MB_2U(SCH_1):M_G_CPU0_SA_CS_N<3>
  J14    209  CS1_N_A  SCONN288_ADR50001P003C01  I47
  U2     DK53  DDR6_SA_CS3_N  SOCKET4677_AZIFS054P001C01  I169

M_G_CPU0_SA_DQ<0>   @S9S_MB_2U_LIB.S9S_MB_2U(SCH_1):M_G_CPU0_SA_DQ<0>
  J13      7  DQ_A0  SCONN288_ADR50001P013C01  I11
  J14      7  DQ_A0  SCONN288_ADR50001P003C01  I47
  U2     DV75  DDR6_SA_DQ0  SOCKET4677_AZIFS054P001C01  I169

M_G_CPU0_SA_DQ<1>   @S9S_MB_2U_LIB.S9S_MB_2U(SCH_1):M_G_CPU0_SA_DQ<1>
  J13      9  DQ_A1  SCONN288_ADR50001P013C01  I11
  J14      9  DQ_A1  SCONN288_ADR50001P003C01  I47
  U2     DU74  DDR6_SA_DQ1  SOCKET4677_AZIFS054P001C01  I169

M_G_CPU0_SA_DQ<2>   @S9S_MB_2U_LIB.S9S_MB_2U(SCH_1):M_G_CPU0_SA_DQ<2>
  J13    152  DQ_A2  SCONN288_ADR50001P013C01  I11
  J14    152  DQ_A2  SCONN288_ADR50001P003C01  I47
  U2     DY75  DDR6_SA_DQ2  SOCKET4677_AZIFS054P001C01  I169

M_G_CPU0_SA_DQ<3>   @S9S_MB_2U_LIB.S9S_MB_2U(SCH_1):M_G_CPU0_SA_DQ<3>
  J13    154  DQ_A3  SCONN288_ADR50001P013C01  I11
  J14    154  DQ_A3  SCONN288_ADR50001P003C01  I47
  U2     EA74  DDR6_SA_DQ3  SOCKET4677_AZIFS054P001C01  I169

M_G_CPU0_SA_DQ<4>   @S9S_MB_2U_LIB.S9S_MB_2U(SCH_1):M_G_CPU0_SA_DQ<4>
  J13     14  DQ_A4  SCONN288_ADR50001P013C01  I11
  J14     14  DQ_A4  SCONN288_ADR50001P003C01  I47
  U2     DU72  DDR6_SA_DQ4  SOCKET4677_AZIFS054P001C01  I169

M_G_CPU0_SA_DQ<5>   @S9S_MB_2U_LIB.S9S_MB_2U(SCH_1):M_G_CPU0_SA_DQ<5>
  J13     16  DQ_A5  SCONN288_ADR50001P013C01  I11
  J14     16  DQ_A5  SCONN288_ADR50001P003C01  I47
  U2     DV71  DDR6_SA_DQ5  SOCKET4677_AZIFS054P001C01  I169

M_G_CPU0_SA_DQ<6>   @S9S_MB_2U_LIB.S9S_MB_2U(SCH_1):M_G_CPU0_SA_DQ<6>
  J13    159  DQ_A6  SCONN288_ADR50001P013C01  I11
  J14    159  DQ_A6  SCONN288_ADR50001P003C01  I47
  U2     EA72  DDR6_SA_DQ6  SOCKET4677_AZIFS054P001C01  I169

M_G_CPU0_SA_DQ<7>   @S9S_MB_2U_LIB.S9S_MB_2U(SCH_1):M_G_CPU0_SA_DQ<7>
  J13    161  DQ_A7  SCONN288_ADR50001P013C01  I11
  J14    161  DQ_A7  SCONN288_ADR50001P003C01  I47
  U2     DY71  DDR6_SA_DQ7  SOCKET4677_AZIFS054P001C01  I169

M_G_CPU0_SA_DQ<8>   @S9S_MB_2U_LIB.S9S_MB_2U(SCH_1):M_G_CPU0_SA_DQ<8>
  J13     18  DQ_A8  SCONN288_ADR50001P013C01  I11
  J14     18  DQ_A8  SCONN288_ADR50001P003C01  I47
  U2     DL72  DDR6_SA_DQ8  SOCKET4677_AZIFS054P001C01  I169

M_G_CPU0_SA_DQ<9>   @S9S_MB_2U_LIB.S9S_MB_2U(SCH_1):M_G_CPU0_SA_DQ<9>
  J13     20  DQ_A9  SCONN288_ADR50001P013C01  I11
  J14     20  DQ_A9  SCONN288_ADR50001P003C01  I47
  U2     DK71  DDR6_SA_DQ9  SOCKET4677_AZIFS054P001C01  I169

M_G_CPU0_SA_DQ<10>   @S9S_MB_2U_LIB.S9S_MB_2U(SCH_1):M_G_CPU0_SA_DQ<10>
  J13    163  DQ_A10  SCONN288_ADR50001P013C01  I11
  J14    163  DQ_A10  SCONN288_ADR50001P003C01  I47
  U2     DN72  DDR6_SA_DQ10  SOCKET4677_AZIFS054P001C01  I169

M_G_CPU0_SA_DQ<11>   @S9S_MB_2U_LIB.S9S_MB_2U(SCH_1):M_G_CPU0_SA_DQ<11>
  J13    165  DQ_A11  SCONN288_ADR50001P013C01  I11
  J14    165  DQ_A11  SCONN288_ADR50001P003C01  I47
  U2     DP71  DDR6_SA_DQ11  SOCKET4677_AZIFS054P001C01  I169

M_G_CPU0_SA_DQ<12>   @S9S_MB_2U_LIB.S9S_MB_2U(SCH_1):M_G_CPU0_SA_DQ<12>
  J13     25  DQ_A12  SCONN288_ADR50001P013C01  I11
  J14     25  DQ_A12  SCONN288_ADR50001P003C01  I47
  U2     DK69  DDR6_SA_DQ12  SOCKET4677_AZIFS054P001C01  I169

M_G_CPU0_SA_DQ<13>   @S9S_MB_2U_LIB.S9S_MB_2U(SCH_1):M_G_CPU0_SA_DQ<13>
  J13     27  DQ_A13  SCONN288_ADR50001P013C01  I11
  J14     27  DQ_A13  SCONN288_ADR50001P003C01  I47
  U2     DL68  DDR6_SA_DQ13  SOCKET4677_AZIFS054P001C01  I169

M_G_CPU0_SA_DQ<14>   @S9S_MB_2U_LIB.S9S_MB_2U(SCH_1):M_G_CPU0_SA_DQ<14>
  J13    170  DQ_A14  SCONN288_ADR50001P013C01  I11
  J14    170  DQ_A14  SCONN288_ADR50001P003C01  I47
  U2     DP69  DDR6_SA_DQ14  SOCKET4677_AZIFS054P001C01  I169

M_G_CPU0_SA_DQ<15>   @S9S_MB_2U_LIB.S9S_MB_2U(SCH_1):M_G_CPU0_SA_DQ<15>
  J13    172  DQ_A15  SCONN288_ADR50001P013C01  I11
  J14    172  DQ_A15  SCONN288_ADR50001P003C01  I47
  U2     DN68  DDR6_SA_DQ15  SOCKET4677_AZIFS054P001C01  I169

M_G_CPU0_SA_DQ<16>   @S9S_MB_2U_LIB.S9S_MB_2U(SCH_1):M_G_CPU0_SA_DQ<16>
  J13     29  DQ_A16  SCONN288_ADR50001P013C01  I11
  J14     29  DQ_A16  SCONN288_ADR50001P003C01  I47
  U2     DV63  DDR6_SA_DQ16  SOCKET4677_AZIFS054P001C01  I169

M_G_CPU0_SA_DQ<17>   @S9S_MB_2U_LIB.S9S_MB_2U(SCH_1):M_G_CPU0_SA_DQ<17>
  J13     31  DQ_A17  SCONN288_ADR50001P013C01  I11
  J14     31  DQ_A17  SCONN288_ADR50001P003C01  I47
  U2     DU62  DDR6_SA_DQ17  SOCKET4677_AZIFS054P001C01  I169

M_G_CPU0_SA_DQ<18>   @S9S_MB_2U_LIB.S9S_MB_2U(SCH_1):M_G_CPU0_SA_DQ<18>
  J13    174  DQ_A18  SCONN288_ADR50001P013C01  I11
  J14    174  DQ_A18  SCONN288_ADR50001P003C01  I47
  U2     DY63  DDR6_SA_DQ18  SOCKET4677_AZIFS054P001C01  I169

M_G_CPU0_SA_DQ<19>   @S9S_MB_2U_LIB.S9S_MB_2U(SCH_1):M_G_CPU0_SA_DQ<19>
  J13    176  DQ_A19  SCONN288_ADR50001P013C01  I11
  J14    176  DQ_A19  SCONN288_ADR50001P003C01  I47
  U2     EA62  DDR6_SA_DQ19  SOCKET4677_AZIFS054P001C01  I169

M_G_CPU0_SA_DQ<20>   @S9S_MB_2U_LIB.S9S_MB_2U(SCH_1):M_G_CPU0_SA_DQ<20>
  J13     36  DQ_A20  SCONN288_ADR50001P013C01  I11
  J14     36  DQ_A20  SCONN288_ADR50001P003C01  I47
  U2     DU60  DDR6_SA_DQ20  SOCKET4677_AZIFS054P001C01  I169

M_G_CPU0_SA_DQ<21>   @S9S_MB_2U_LIB.S9S_MB_2U(SCH_1):M_G_CPU0_SA_DQ<21>
  J13     38  DQ_A21  SCONN288_ADR50001P013C01  I11
  J14     38  DQ_A21  SCONN288_ADR50001P003C01  I47
  U2     DV59  DDR6_SA_DQ21  SOCKET4677_AZIFS054P001C01  I169

M_G_CPU0_SA_DQ<22>   @S9S_MB_2U_LIB.S9S_MB_2U(SCH_1):M_G_CPU0_SA_DQ<22>
  J13    181  DQ_A22  SCONN288_ADR50001P013C01  I11
  J14    181  DQ_A22  SCONN288_ADR50001P003C01  I47
  U2     EA60  DDR6_SA_DQ22  SOCKET4677_AZIFS054P001C01  I169

M_G_CPU0_SA_DQ<23>   @S9S_MB_2U_LIB.S9S_MB_2U(SCH_1):M_G_CPU0_SA_DQ<23>
  J13    183  DQ_A23  SCONN288_ADR50001P013C01  I11
  J14    183  DQ_A23  SCONN288_ADR50001P003C01  I47
  U2     DY59  DDR6_SA_DQ23  SOCKET4677_AZIFS054P001C01  I169

M_G_CPU0_SA_DQ<24>   @S9S_MB_2U_LIB.S9S_MB_2U(SCH_1):M_G_CPU0_SA_DQ<24>
  J13     40  DQ_A24  SCONN288_ADR50001P013C01  I11
  J14     40  DQ_A24  SCONN288_ADR50001P003C01  I47
  U2     DL66  DDR6_SA_DQ24  SOCKET4677_AZIFS054P001C01  I169

M_G_CPU0_SA_DQ<25>   @S9S_MB_2U_LIB.S9S_MB_2U(SCH_1):M_G_CPU0_SA_DQ<25>
  J13     42  DQ_A25  SCONN288_ADR50001P013C01  I11
  J14     42  DQ_A25  SCONN288_ADR50001P003C01  I47
  U2     DK65  DDR6_SA_DQ25  SOCKET4677_AZIFS054P001C01  I169

M_G_CPU0_SA_DQ<26>   @S9S_MB_2U_LIB.S9S_MB_2U(SCH_1):M_G_CPU0_SA_DQ<26>
  J13    185  DQ_A26  SCONN288_ADR50001P013C01  I11
  J14    185  DQ_A26  SCONN288_ADR50001P003C01  I47
  U2     DN66  DDR6_SA_DQ26  SOCKET4677_AZIFS054P001C01  I169

M_G_CPU0_SA_DQ<27>   @S9S_MB_2U_LIB.S9S_MB_2U(SCH_1):M_G_CPU0_SA_DQ<27>
  J13    187  DQ_A27  SCONN288_ADR50001P013C01  I11
  J14    187  DQ_A27  SCONN288_ADR50001P003C01  I47
  U2     DP65  DDR6_SA_DQ27  SOCKET4677_AZIFS054P001C01  I169

M_G_CPU0_SA_DQ<28>   @S9S_MB_2U_LIB.S9S_MB_2U(SCH_1):M_G_CPU0_SA_DQ<28>
  J13     47  DQ_A28  SCONN288_ADR50001P013C01  I11
  J14     47  DQ_A28  SCONN288_ADR50001P003C01  I47
  U2     DK63  DDR6_SA_DQ28  SOCKET4677_AZIFS054P001C01  I169

M_G_CPU0_SA_DQ<29>   @S9S_MB_2U_LIB.S9S_MB_2U(SCH_1):M_G_CPU0_SA_DQ<29>
  J13     49  DQ_A29  SCONN288_ADR50001P013C01  I11
  J14     49  DQ_A29  SCONN288_ADR50001P003C01  I47
  U2     DL62  DDR6_SA_DQ29  SOCKET4677_AZIFS054P001C01  I169

M_G_CPU0_SA_DQ<30>   @S9S_MB_2U_LIB.S9S_MB_2U(SCH_1):M_G_CPU0_SA_DQ<30>
  J13    192  DQ_A30  SCONN288_ADR50001P013C01  I11
  J14    192  DQ_A30  SCONN288_ADR50001P003C01  I47
  U2     DP63  DDR6_SA_DQ30  SOCKET4677_AZIFS054P001C01  I169

M_G_CPU0_SA_DQ<31>   @S9S_MB_2U_LIB.S9S_MB_2U(SCH_1):M_G_CPU0_SA_DQ<31>
  J13    194  DQ_A31  SCONN288_ADR50001P013C01  I11
  J14    194  DQ_A31  SCONN288_ADR50001P003C01  I47
  U2     DN62  DDR6_SA_DQ31  SOCKET4677_AZIFS054P001C01  I169

M_G_CPU0_SA_DQS_DN<0>   @S9S_MB_2U_LIB.S9S_MB_2U(SCH_1):M_G_CPU0_SA_DQS_DN<0>
  J13     12  DQS0_A_N  SCONN288_ADR50001P013C01  I127
  J14     12  DQS0_A_N  SCONN288_ADR50001P003C01  I124
  U2     DV73  DDR6_SA_DQS_DN0  SOCKET4677_AZIFS054P001C01  I169

M_G_CPU0_SA_DQS_DN<1>   @S9S_MB_2U_LIB.S9S_MB_2U(SCH_1):M_G_CPU0_SA_DQS_DN<1>
  J13     23  DQS1_A_N  SCONN288_ADR50001P013C01  I127
  J14     23  DQS1_A_N  SCONN288_ADR50001P003C01  I124
  U2     DJ70  DDR6_SA_DQS_DN1  SOCKET4677_AZIFS054P001C01  I169

M_G_CPU0_SA_DQS_DN<2>   @S9S_MB_2U_LIB.S9S_MB_2U(SCH_1):M_G_CPU0_SA_DQS_DN<2>
  J13     34  DQS2_A_N  SCONN288_ADR50001P013C01  I127
  J14     34  DQS2_A_N  SCONN288_ADR50001P003C01  I124
  U2     DT61  DDR6_SA_DQS_DN2  SOCKET4677_AZIFS054P001C01  I169

M_G_CPU0_SA_DQS_DN<3>   @S9S_MB_2U_LIB.S9S_MB_2U(SCH_1):M_G_CPU0_SA_DQS_DN<3>
  J13     45  DQS3_A_N  SCONN288_ADR50001P013C01  I127
  J14     45  DQS3_A_N  SCONN288_ADR50001P003C01  I124
  U2     DL64  DDR6_SA_DQS_DN3  SOCKET4677_AZIFS054P001C01  I169

M_G_CPU0_SA_DQS_DN<4>   @S9S_MB_2U_LIB.S9S_MB_2U(SCH_1):M_G_CPU0_SA_DQS_DN<4>
  J13     56  DQS4_A_N  SCONN288_ADR50001P013C01  I127
  J14     56  DQS4_A_N  SCONN288_ADR50001P003C01  I124
  U2     DL58  DDR6_SA_DQS_DN4  SOCKET4677_AZIFS054P001C01  I169

M_G_CPU0_SA_DQS_DN<5>   @S9S_MB_2U_LIB.S9S_MB_2U(SCH_1):M_G_CPU0_SA_DQS_DN<5>
  J13    156  DQS5_A_N  SCONN288_ADR50001P013C01  I127
  J14    156  DQS5_A_N  SCONN288_ADR50001P003C01  I124
  U2     EB73  DDR6_SA_DQS_DN5  SOCKET4677_AZIFS054P001C01  I169

M_G_CPU0_SA_DQS_DN<6>   @S9S_MB_2U_LIB.S9S_MB_2U(SCH_1):M_G_CPU0_SA_DQS_DN<6>
  J13    167  DQS6_A_N  SCONN288_ADR50001P013C01  I127
  J14    167  DQS6_A_N  SCONN288_ADR50001P003C01  I124
  U2     DR70  DDR6_SA_DQS_DN6  SOCKET4677_AZIFS054P001C01  I169

M_G_CPU0_SA_DQS_DN<7>   @S9S_MB_2U_LIB.S9S_MB_2U(SCH_1):M_G_CPU0_SA_DQS_DN<7>
  J13    178  DQS7_A_N  SCONN288_ADR50001P013C01  I127
  J14    178  DQS7_A_N  SCONN288_ADR50001P003C01  I124
  U2     EB61  DDR6_SA_DQS_DN7  SOCKET4677_AZIFS054P001C01  I169

M_G_CPU0_SA_DQS_DN<8>   @S9S_MB_2U_LIB.S9S_MB_2U(SCH_1):M_G_CPU0_SA_DQS_DN<8>
  J13    189  DQS8_A_N  SCONN288_ADR50001P013C01  I127
  J14    189  DQS8_A_N  SCONN288_ADR50001P003C01  I124
  U2     DR64  DDR6_SA_DQS_DN8  SOCKET4677_AZIFS054P001C01  I169

M_G_CPU0_SA_DQS_DN<9>   @S9S_MB_2U_LIB.S9S_MB_2U(SCH_1):M_G_CPU0_SA_DQS_DN<9>
  J13    200  DQS9_A_N  SCONN288_ADR50001P013C01  I127
  J14    200  DQS9_A_N  SCONN288_ADR50001P003C01  I124
  U2     DR58  DDR6_SA_DQS_DN9  SOCKET4677_AZIFS054P001C01  I169

M_G_CPU0_SA_DQS_DP<0>   @S9S_MB_2U_LIB.S9S_MB_2U(SCH_1):M_G_CPU0_SA_DQS_DP<0>
  J13     11  DQS0_A_P  SCONN288_ADR50001P013C01  I127
  J14     11  DQS0_A_P  SCONN288_ADR50001P003C01  I124
  U2     DT73  DDR6_SA_DQS_DP0  SOCKET4677_AZIFS054P001C01  I169

M_G_CPU0_SA_DQS_DP<1>   @S9S_MB_2U_LIB.S9S_MB_2U(SCH_1):M_G_CPU0_SA_DQS_DP<1>
  J13     22  DQS1_A_P  SCONN288_ADR50001P013C01  I127
  J14     22  DQS1_A_P  SCONN288_ADR50001P003C01  I124
  U2     DL70  DDR6_SA_DQS_DP1  SOCKET4677_AZIFS054P001C01  I169

M_G_CPU0_SA_DQS_DP<2>   @S9S_MB_2U_LIB.S9S_MB_2U(SCH_1):M_G_CPU0_SA_DQS_DP<2>
  J13     33  DQS2_A_P  SCONN288_ADR50001P013C01  I127
  J14     33  DQS2_A_P  SCONN288_ADR50001P003C01  I124
  U2     DV61  DDR6_SA_DQS_DP2  SOCKET4677_AZIFS054P001C01  I169

M_G_CPU0_SA_DQS_DP<3>   @S9S_MB_2U_LIB.S9S_MB_2U(SCH_1):M_G_CPU0_SA_DQS_DP<3>
  J13     44  DQS3_A_P  SCONN288_ADR50001P013C01  I127
  J14     44  DQS3_A_P  SCONN288_ADR50001P003C01  I124
  U2     DJ64  DDR6_SA_DQS_DP3  SOCKET4677_AZIFS054P001C01  I169

M_G_CPU0_SA_DQS_DP<4>   @S9S_MB_2U_LIB.S9S_MB_2U(SCH_1):M_G_CPU0_SA_DQS_DP<4>
  J13     55  DQS4_A_P  SCONN288_ADR50001P013C01  I127
  J14     55  DQS4_A_P  SCONN288_ADR50001P003C01  I124
  U2     DJ58  DDR6_SA_DQS_DP4  SOCKET4677_AZIFS054P001C01  I169

M_G_CPU0_SA_DQS_DP<5>   @S9S_MB_2U_LIB.S9S_MB_2U(SCH_1):M_G_CPU0_SA_DQS_DP<5>
  J13    157  DQS5_A_P  SCONN288_ADR50001P013C01  I127
  J14    157  DQS5_A_P  SCONN288_ADR50001P003C01  I124
  U2     DY73  DDR6_SA_DQS_DP5  SOCKET4677_AZIFS054P001C01  I169

M_G_CPU0_SA_DQS_DP<6>   @S9S_MB_2U_LIB.S9S_MB_2U(SCH_1):M_G_CPU0_SA_DQS_DP<6>
  J13    168  DQS6_A_P  SCONN288_ADR50001P013C01  I127
  J14    168  DQS6_A_P  SCONN288_ADR50001P003C01  I124
  U2     DN70  DDR6_SA_DQS_DP6  SOCKET4677_AZIFS054P001C01  I169

M_G_CPU0_SA_DQS_DP<7>   @S9S_MB_2U_LIB.S9S_MB_2U(SCH_1):M_G_CPU0_SA_DQS_DP<7>
  J13    179  DQS7_A_P  SCONN288_ADR50001P013C01  I127
  J14    179  DQS7_A_P  SCONN288_ADR50001P003C01  I124
  U2     DY61  DDR6_SA_DQS_DP7  SOCKET4677_AZIFS054P001C01  I169

M_G_CPU0_SA_DQS_DP<8>   @S9S_MB_2U_LIB.S9S_MB_2U(SCH_1):M_G_CPU0_SA_DQS_DP<8>
  J13    190  DQS8_A_P  SCONN288_ADR50001P013C01  I127
  J14    190  DQS8_A_P  SCONN288_ADR50001P003C01  I124
  U2     DN64  DDR6_SA_DQS_DP8  SOCKET4677_AZIFS054P001C01  I169

M_G_CPU0_SA_DQS_DP<9>   @S9S_MB_2U_LIB.S9S_MB_2U(SCH_1):M_G_CPU0_SA_DQS_DP<9>
  J13    201  DQS9_A_P  SCONN288_ADR50001P013C01  I127
  J14    201  DQS9_A_P  SCONN288_ADR50001P003C01  I124
  U2     DN58  DDR6_SA_DQS_DP9  SOCKET4677_AZIFS054P001C01  I169

M_G_CPU0_SA_PAR   @S9S_MB_2U_LIB.S9S_MB_2U(SCH_1):M_G_CPU0_SA_PAR
  J13     74  PAR_A  SCONN288_ADR50001P013C01  I11
  J14     74  PAR_A  SCONN288_ADR50001P003C01  I47
  U2     DL43  DDR6_SA_PAR  SOCKET4677_AZIFS054P001C01  I169

M_G_CPU0_SA_RSP<0>   @S9S_MB_2U_LIB.S9S_MB_2U(SCH_1):M_G_CPU0_SA_RSP<0>
  J13     86  LBD||RSP_N_A  SCONN288_ADR50001P013C01  I11
  U2     EA48  DDR6_A_RSP0  SOCKET4677_AZIFS054P001C01  I169

M_G_CPU0_SA_RSP<1>   @S9S_MB_2U_LIB.S9S_MB_2U(SCH_1):M_G_CPU0_SA_RSP<1>
  J14     86  LBD||RSP_N_A  SCONN288_ADR50001P003C01  I47
  U2     DY47  DDR6_A_RSP1  SOCKET4677_AZIFS054P001C01  I169

M_G_CPU0_SB_CA<0>   @S9S_MB_2U_LIB.S9S_MB_2U(SCH_1):M_G_CPU0_SB_CA<0>
  J13     76  CA0_B  SCONN288_ADR50001P013C01  I11
  J14     76  CA0_B  SCONN288_ADR50001P003C01  I47
  U2     DN43  DDR6_SB_CA0  SOCKET4677_AZIFS054P001C01  I169

M_G_CPU0_SB_CA<1>   @S9S_MB_2U_LIB.S9S_MB_2U(SCH_1):M_G_CPU0_SB_CA<1>
  J13    221  CA1_B  SCONN288_ADR50001P013C01  I11
  J14    221  CA1_B  SCONN288_ADR50001P003C01  I47
  U2     DP44  DDR6_SB_CA1  SOCKET4677_AZIFS054P001C01  I169

M_G_CPU0_SB_CA<2>   @S9S_MB_2U_LIB.S9S_MB_2U(SCH_1):M_G_CPU0_SB_CA<2>
  J13     78  CA2_B  SCONN288_ADR50001P013C01  I11
  J14     78  CA2_B  SCONN288_ADR50001P003C01  I47
  U2     DV44  DDR6_SB_CA2  SOCKET4677_AZIFS054P001C01  I169

M_G_CPU0_SB_CA<3>   @S9S_MB_2U_LIB.S9S_MB_2U(SCH_1):M_G_CPU0_SB_CA<3>
  J13    223  CA3_B  SCONN288_ADR50001P013C01  I11
  J14    223  CA3_B  SCONN288_ADR50001P003C01  I47
  U2     DY44  DDR6_SB_CA3  SOCKET4677_AZIFS054P001C01  I169

M_G_CPU0_SB_CA<4>   @S9S_MB_2U_LIB.S9S_MB_2U(SCH_1):M_G_CPU0_SB_CA<4>
  J13     80  CA4_B  SCONN288_ADR50001P013C01  I11
  J14     80  CA4_B  SCONN288_ADR50001P003C01  I47
  U2     DU43  DDR6_SB_CA4  SOCKET4677_AZIFS054P001C01  I169

M_G_CPU0_SB_CA<5>   @S9S_MB_2U_LIB.S9S_MB_2U(SCH_1):M_G_CPU0_SB_CA<5>
  J13    225  CA5_B  SCONN288_ADR50001P013C01  I11
  J14    225  CA5_B  SCONN288_ADR50001P003C01  I47
  U2     EA43  DDR6_SB_CA5  SOCKET4677_AZIFS054P001C01  I169

M_G_CPU0_SB_CA<6>   @S9S_MB_2U_LIB.S9S_MB_2U(SCH_1):M_G_CPU0_SB_CA<6>
  J13     82  CA6_B  SCONN288_ADR50001P013C01  I11
  J14     82  CA6_B  SCONN288_ADR50001P003C01  I47
  U2     DT42  DDR6_SB_CA6  SOCKET4677_AZIFS054P001C01  I169

M_G_CPU0_SB_CB<0>   @S9S_MB_2U_LIB.S9S_MB_2U(SCH_1):M_G_CPU0_SB_CB<0>
  J13     96  CB_B0  SCONN288_ADR50001P013C01  I11
  J14     96  CB_B0  SCONN288_ADR50001P003C01  I47
  U2     DU35  DDR6_SB_ECC0  SOCKET4677_AZIFS054P001C01  I169

M_G_CPU0_SB_CB<1>   @S9S_MB_2U_LIB.S9S_MB_2U(SCH_1):M_G_CPU0_SB_CB<1>
  J13     98  CB_B1  SCONN288_ADR50001P013C01  I11
  J14     98  CB_B1  SCONN288_ADR50001P003C01  I47
  U2     DV34  DDR6_SB_ECC1  SOCKET4677_AZIFS054P001C01  I169

M_G_CPU0_SB_CB<2>   @S9S_MB_2U_LIB.S9S_MB_2U(SCH_1):M_G_CPU0_SB_CB<2>
  J13    241  CB_B2  SCONN288_ADR50001P013C01  I11
  J14    241  CB_B2  SCONN288_ADR50001P003C01  I47
  U2     EA35  DDR6_SB_ECC2  SOCKET4677_AZIFS054P001C01  I169

M_G_CPU0_SB_CB<3>   @S9S_MB_2U_LIB.S9S_MB_2U(SCH_1):M_G_CPU0_SB_CB<3>
  J13    243  CB_B3  SCONN288_ADR50001P013C01  I11
  J14    243  CB_B3  SCONN288_ADR50001P003C01  I47
  U2     DY34  DDR6_SB_ECC3  SOCKET4677_AZIFS054P001C01  I169

M_G_CPU0_SB_CB<4>   @S9S_MB_2U_LIB.S9S_MB_2U(SCH_1):M_G_CPU0_SB_CB<4>
  J13     89  CB_B4  SCONN288_ADR50001P013C01  I11
  J14     89  CB_B4  SCONN288_ADR50001P003C01  I47
  U2     DV38  DDR6_SB_ECC4  SOCKET4677_AZIFS054P001C01  I169

M_G_CPU0_SB_CB<5>   @S9S_MB_2U_LIB.S9S_MB_2U(SCH_1):M_G_CPU0_SB_CB<5>
  J13     91  CB_B5  SCONN288_ADR50001P013C01  I11
  J14     91  CB_B5  SCONN288_ADR50001P003C01  I47
  U2     DU37  DDR6_SB_ECC5  SOCKET4677_AZIFS054P001C01  I169

M_G_CPU0_SB_CB<6>   @S9S_MB_2U_LIB.S9S_MB_2U(SCH_1):M_G_CPU0_SB_CB<6>
  J13    234  CB_B6  SCONN288_ADR50001P013C01  I11
  J14    234  CB_B6  SCONN288_ADR50001P003C01  I47
  U2     DY38  DDR6_SB_ECC6  SOCKET4677_AZIFS054P001C01  I169

M_G_CPU0_SB_CB<7>   @S9S_MB_2U_LIB.S9S_MB_2U(SCH_1):M_G_CPU0_SB_CB<7>
  J13    236  CB_B7  SCONN288_ADR50001P013C01  I11
  J14    236  CB_B7  SCONN288_ADR50001P003C01  I47
  U2     EA37  DDR6_SB_ECC7  SOCKET4677_AZIFS054P001C01  I169

M_G_CPU0_SB_CS_N<0>   @S9S_MB_2U_LIB.S9S_MB_2U(SCH_1):M_G_CPU0_SB_CS_N<0>
  J13     84  CS0_N_B  SCONN288_ADR50001P013C01  I11
  U2     EA41  DDR6_SB_CS0_N  SOCKET4677_AZIFS054P001C01  I169

M_G_CPU0_SB_CS_N<1>   @S9S_MB_2U_LIB.S9S_MB_2U(SCH_1):M_G_CPU0_SB_CS_N<1>
  J13    229  CS1_N_B  SCONN288_ADR50001P013C01  I11
  U2     DY40  DDR6_SB_CS1_N  SOCKET4677_AZIFS054P001C01  I169

M_G_CPU0_SB_CS_N<2>   @S9S_MB_2U_LIB.S9S_MB_2U(SCH_1):M_G_CPU0_SB_CS_N<2>
  J14     84  CS0_N_B  SCONN288_ADR50001P003C01  I47
  U2     DU41  DDR6_SB_CS2_N  SOCKET4677_AZIFS054P001C01  I169

M_G_CPU0_SB_CS_N<3>   @S9S_MB_2U_LIB.S9S_MB_2U(SCH_1):M_G_CPU0_SB_CS_N<3>
  J14    229  CS1_N_B  SCONN288_ADR50001P003C01  I47
  U2     DV40  DDR6_SB_CS3_N  SOCKET4677_AZIFS054P001C01  I169

M_G_CPU0_SB_DQ<0>   @S9S_MB_2U_LIB.S9S_MB_2U(SCH_1):M_G_CPU0_SB_DQ<0>
  J13    100  DQ_B0  SCONN288_ADR50001P013C01  I11
  J14    100  DQ_B0  SCONN288_ADR50001P003C01  I47
  U2     DL35  DDR6_SB_DQ0  SOCKET4677_AZIFS054P001C01  I169

M_G_CPU0_SB_DQ<1>   @S9S_MB_2U_LIB.S9S_MB_2U(SCH_1):M_G_CPU0_SB_DQ<1>
  J13    102  DQ_B1  SCONN288_ADR50001P013C01  I11
  J14    102  DQ_B1  SCONN288_ADR50001P003C01  I47
  U2     DK34  DDR6_SB_DQ1  SOCKET4677_AZIFS054P001C01  I169

M_G_CPU0_SB_DQ<2>   @S9S_MB_2U_LIB.S9S_MB_2U(SCH_1):M_G_CPU0_SB_DQ<2>
  J13    245  DQ_B2  SCONN288_ADR50001P013C01  I11
  J14    245  DQ_B2  SCONN288_ADR50001P003C01  I47
  U2     DN35  DDR6_SB_DQ2  SOCKET4677_AZIFS054P001C01  I169

M_G_CPU0_SB_DQ<3>   @S9S_MB_2U_LIB.S9S_MB_2U(SCH_1):M_G_CPU0_SB_DQ<3>
  J13    247  DQ_B3  SCONN288_ADR50001P013C01  I11
  J14    247  DQ_B3  SCONN288_ADR50001P003C01  I47
  U2     DP34  DDR6_SB_DQ3  SOCKET4677_AZIFS054P001C01  I169

M_G_CPU0_SB_DQ<4>   @S9S_MB_2U_LIB.S9S_MB_2U(SCH_1):M_G_CPU0_SB_DQ<4>
  J13    107  DQ_B4  SCONN288_ADR50001P013C01  I11
  J14    107  DQ_B4  SCONN288_ADR50001P003C01  I47
  U2     DK32  DDR6_SB_DQ4  SOCKET4677_AZIFS054P001C01  I169

M_G_CPU0_SB_DQ<5>   @S9S_MB_2U_LIB.S9S_MB_2U(SCH_1):M_G_CPU0_SB_DQ<5>
  J13    109  DQ_B5  SCONN288_ADR50001P013C01  I11
  J14    109  DQ_B5  SCONN288_ADR50001P003C01  I47
  U2     DL31  DDR6_SB_DQ5  SOCKET4677_AZIFS054P001C01  I169

M_G_CPU0_SB_DQ<6>   @S9S_MB_2U_LIB.S9S_MB_2U(SCH_1):M_G_CPU0_SB_DQ<6>
  J13    252  DQ_B6  SCONN288_ADR50001P013C01  I11
  J14    252  DQ_B6  SCONN288_ADR50001P003C01  I47
  U2     DP32  DDR6_SB_DQ6  SOCKET4677_AZIFS054P001C01  I169

M_G_CPU0_SB_DQ<7>   @S9S_MB_2U_LIB.S9S_MB_2U(SCH_1):M_G_CPU0_SB_DQ<7>
  J13    254  DQ_B7  SCONN288_ADR50001P013C01  I11
  J14    254  DQ_B7  SCONN288_ADR50001P003C01  I47
  U2     DN31  DDR6_SB_DQ7  SOCKET4677_AZIFS054P001C01  I169

M_G_CPU0_SB_DQ<8>   @S9S_MB_2U_LIB.S9S_MB_2U(SCH_1):M_G_CPU0_SB_DQ<8>
  J13    111  DQ_B8  SCONN288_ADR50001P013C01  I11
  J14    111  DQ_B8  SCONN288_ADR50001P003C01  I47
  U2     DN29  DDR6_SB_DQ8  SOCKET4677_AZIFS054P001C01  I169

M_G_CPU0_SB_DQ<9>   @S9S_MB_2U_LIB.S9S_MB_2U(SCH_1):M_G_CPU0_SB_DQ<9>
  J13    113  DQ_B9  SCONN288_ADR50001P013C01  I11
  J14    113  DQ_B9  SCONN288_ADR50001P003C01  I47
  U2     DK28  DDR6_SB_DQ9  SOCKET4677_AZIFS054P001C01  I169

M_G_CPU0_SB_DQ<10>   @S9S_MB_2U_LIB.S9S_MB_2U(SCH_1):M_G_CPU0_SB_DQ<10>
  J13    256  DQ_B10  SCONN288_ADR50001P013C01  I11
  J14    256  DQ_B10  SCONN288_ADR50001P003C01  I47
  U2     DL29  DDR6_SB_DQ10  SOCKET4677_AZIFS054P001C01  I169

M_G_CPU0_SB_DQ<11>   @S9S_MB_2U_LIB.S9S_MB_2U(SCH_1):M_G_CPU0_SB_DQ<11>
  J13    258  DQ_B11  SCONN288_ADR50001P013C01  I11
  J14    258  DQ_B11  SCONN288_ADR50001P003C01  I47
  U2     DP28  DDR6_SB_DQ11  SOCKET4677_AZIFS054P001C01  I169

M_G_CPU0_SB_DQ<12>   @S9S_MB_2U_LIB.S9S_MB_2U(SCH_1):M_G_CPU0_SB_DQ<12>
  J13    118  DQ_B12  SCONN288_ADR50001P013C01  I11
  J14    118  DQ_B12  SCONN288_ADR50001P003C01  I47
  U2     DK26  DDR6_SB_DQ12  SOCKET4677_AZIFS054P001C01  I169

M_G_CPU0_SB_DQ<13>   @S9S_MB_2U_LIB.S9S_MB_2U(SCH_1):M_G_CPU0_SB_DQ<13>
  J13    120  DQ_B13  SCONN288_ADR50001P013C01  I11
  J14    120  DQ_B13  SCONN288_ADR50001P003C01  I47
  U2     DL25  DDR6_SB_DQ13  SOCKET4677_AZIFS054P001C01  I169

M_G_CPU0_SB_DQ<14>   @S9S_MB_2U_LIB.S9S_MB_2U(SCH_1):M_G_CPU0_SB_DQ<14>
  J13    263  DQ_B14  SCONN288_ADR50001P013C01  I11
  J14    263  DQ_B14  SCONN288_ADR50001P003C01  I47
  U2     DP26  DDR6_SB_DQ14  SOCKET4677_AZIFS054P001C01  I169

M_G_CPU0_SB_DQ<15>   @S9S_MB_2U_LIB.S9S_MB_2U(SCH_1):M_G_CPU0_SB_DQ<15>
  J13    265  DQ_B15  SCONN288_ADR50001P013C01  I11
  J14    265  DQ_B15  SCONN288_ADR50001P003C01  I47
  U2     DN25  DDR6_SB_DQ15  SOCKET4677_AZIFS054P001C01  I169

M_G_CPU0_SB_DQ<16>   @S9S_MB_2U_LIB.S9S_MB_2U(SCH_1):M_G_CPU0_SB_DQ<16>
  J13    122  DQ_B16  SCONN288_ADR50001P013C01  I11
  J14    122  DQ_B16  SCONN288_ADR50001P003C01  I47
  U2     DV26  DDR6_SB_DQ16  SOCKET4677_AZIFS054P001C01  I169

M_G_CPU0_SB_DQ<17>   @S9S_MB_2U_LIB.S9S_MB_2U(SCH_1):M_G_CPU0_SB_DQ<17>
  J13    124  DQ_B17  SCONN288_ADR50001P013C01  I11
  J14    124  DQ_B17  SCONN288_ADR50001P003C01  I47
  U2     DU25  DDR6_SB_DQ17  SOCKET4677_AZIFS054P001C01  I169

M_G_CPU0_SB_DQ<18>   @S9S_MB_2U_LIB.S9S_MB_2U(SCH_1):M_G_CPU0_SB_DQ<18>
  J13    267  DQ_B18  SCONN288_ADR50001P013C01  I11
  J14    267  DQ_B18  SCONN288_ADR50001P003C01  I47
  U2     DY26  DDR6_SB_DQ18  SOCKET4677_AZIFS054P001C01  I169

M_G_CPU0_SB_DQ<19>   @S9S_MB_2U_LIB.S9S_MB_2U(SCH_1):M_G_CPU0_SB_DQ<19>
  J13    269  DQ_B19  SCONN288_ADR50001P013C01  I11
  J14    269  DQ_B19  SCONN288_ADR50001P003C01  I47
  U2     EA25  DDR6_SB_DQ19  SOCKET4677_AZIFS054P001C01  I169

M_G_CPU0_SB_DQ<20>   @S9S_MB_2U_LIB.S9S_MB_2U(SCH_1):M_G_CPU0_SB_DQ<20>
  J13    129  DQ_B20  SCONN288_ADR50001P013C01  I11
  J14    129  DQ_B20  SCONN288_ADR50001P003C01  I47
  U2     DU23  DDR6_SB_DQ20  SOCKET4677_AZIFS054P001C01  I169

M_G_CPU0_SB_DQ<21>   @S9S_MB_2U_LIB.S9S_MB_2U(SCH_1):M_G_CPU0_SB_DQ<21>
  J13    131  DQ_B21  SCONN288_ADR50001P013C01  I11
  J14    131  DQ_B21  SCONN288_ADR50001P003C01  I47
  U2     DV22  DDR6_SB_DQ21  SOCKET4677_AZIFS054P001C01  I169

M_G_CPU0_SB_DQ<22>   @S9S_MB_2U_LIB.S9S_MB_2U(SCH_1):M_G_CPU0_SB_DQ<22>
  J13    274  DQ_B22  SCONN288_ADR50001P013C01  I11
  J14    274  DQ_B22  SCONN288_ADR50001P003C01  I47
  U2     EA23  DDR6_SB_DQ22  SOCKET4677_AZIFS054P001C01  I169

M_G_CPU0_SB_DQ<23>   @S9S_MB_2U_LIB.S9S_MB_2U(SCH_1):M_G_CPU0_SB_DQ<23>
  J13    276  DQ_B23  SCONN288_ADR50001P013C01  I11
  J14    276  DQ_B23  SCONN288_ADR50001P003C01  I47
  U2     DY22  DDR6_SB_DQ23  SOCKET4677_AZIFS054P001C01  I169

M_G_CPU0_SB_DQ<24>   @S9S_MB_2U_LIB.S9S_MB_2U(SCH_1):M_G_CPU0_SB_DQ<24>
  J13    133  DQ_B24  SCONN288_ADR50001P013C01  I11
  J14    133  DQ_B24  SCONN288_ADR50001P003C01  I47
  U2     EK8  DDR6_SB_DQ24  SOCKET4677_AZIFS054P001C01  I169

M_G_CPU0_SB_DQ<25>   @S9S_MB_2U_LIB.S9S_MB_2U(SCH_1):M_G_CPU0_SB_DQ<25>
  J13    135  DQ_B25  SCONN288_ADR50001P013C01  I11
  J14    135  DQ_B25  SCONN288_ADR50001P003C01  I47
  U2     EH8  DDR6_SB_DQ25  SOCKET4677_AZIFS054P001C01  I169

M_G_CPU0_SB_DQ<26>   @S9S_MB_2U_LIB.S9S_MB_2U(SCH_1):M_G_CPU0_SB_DQ<26>
  J13    278  DQ_B26  SCONN288_ADR50001P013C01  I11
  J14    278  DQ_B26  SCONN288_ADR50001P003C01  I47
  U2     EP8  DDR6_SB_DQ26  SOCKET4677_AZIFS054P001C01  I169

M_G_CPU0_SB_DQ<27>   @S9S_MB_2U_LIB.S9S_MB_2U(SCH_1):M_G_CPU0_SB_DQ<27>
  J13    280  DQ_B27  SCONN288_ADR50001P013C01  I11
  J14    280  DQ_B27  SCONN288_ADR50001P003C01  I47
  U2     ET8  DDR6_SB_DQ27  SOCKET4677_AZIFS054P001C01  I169

M_G_CPU0_SB_DQ<28>   @S9S_MB_2U_LIB.S9S_MB_2U(SCH_1):M_G_CPU0_SB_DQ<28>
  J13    140  DQ_B28  SCONN288_ADR50001P013C01  I11
  J14    140  DQ_B28  SCONN288_ADR50001P003C01  I47
  U2     EK6  DDR6_SB_DQ28  SOCKET4677_AZIFS054P001C01  I169

M_G_CPU0_SB_DQ<29>   @S9S_MB_2U_LIB.S9S_MB_2U(SCH_1):M_G_CPU0_SB_DQ<29>
  J13    142  DQ_B29  SCONN288_ADR50001P013C01  I11
  J14    142  DQ_B29  SCONN288_ADR50001P003C01  I47
  U2     EJ5  DDR6_SB_DQ29  SOCKET4677_AZIFS054P001C01  I169

M_G_CPU0_SB_DQ<30>   @S9S_MB_2U_LIB.S9S_MB_2U(SCH_1):M_G_CPU0_SB_DQ<30>
  J13    285  DQ_B30  SCONN288_ADR50001P013C01  I11
  J14    285  DQ_B30  SCONN288_ADR50001P003C01  I47
  U2     EP4  DDR6_SB_DQ30  SOCKET4677_AZIFS054P001C01  I169

M_G_CPU0_SB_DQ<31>   @S9S_MB_2U_LIB.S9S_MB_2U(SCH_1):M_G_CPU0_SB_DQ<31>
  J13    287  DQ_B31  SCONN288_ADR50001P013C01  I11
  J14    287  DQ_B31  SCONN288_ADR50001P003C01  I47
  U2     EM4  DDR6_SB_DQ31  SOCKET4677_AZIFS054P001C01  I169

M_G_CPU0_SB_DQS_DN<0>   @S9S_MB_2U_LIB.S9S_MB_2U(SCH_1):M_G_CPU0_SB_DQS_DN<0>
  J13    105  DQS0_B_N  SCONN288_ADR50001P013C01  I127
  J14    105  DQS0_B_N  SCONN288_ADR50001P003C01  I124
  U2     DJ33  DDR6_SB_DQS_DN0  SOCKET4677_AZIFS054P001C01  I169

M_G_CPU0_SB_DQS_DN<1>   @S9S_MB_2U_LIB.S9S_MB_2U(SCH_1):M_G_CPU0_SB_DQS_DN<1>
  J13    116  DQS1_B_N  SCONN288_ADR50001P013C01  I127
  J14    116  DQS1_B_N  SCONN288_ADR50001P003C01  I124
  U2     DJ27  DDR6_SB_DQS_DN1  SOCKET4677_AZIFS054P001C01  I169

M_G_CPU0_SB_DQS_DN<2>   @S9S_MB_2U_LIB.S9S_MB_2U(SCH_1):M_G_CPU0_SB_DQS_DN<2>
  J13    127  DQS2_B_N  SCONN288_ADR50001P013C01  I127
  J14    127  DQS2_B_N  SCONN288_ADR50001P003C01  I124
  U2     DV24  DDR6_SB_DQS_DN2  SOCKET4677_AZIFS054P001C01  I169

M_G_CPU0_SB_DQS_DN<3>   @S9S_MB_2U_LIB.S9S_MB_2U(SCH_1):M_G_CPU0_SB_DQS_DN<3>
  J13    138  DQS3_B_N  SCONN288_ADR50001P013C01  I127
  J14    138  DQS3_B_N  SCONN288_ADR50001P003C01  I124
  U2     EP6  DDR6_SB_DQS_DN3  SOCKET4677_AZIFS054P001C01  I169

M_G_CPU0_SB_DQS_DN<4>   @S9S_MB_2U_LIB.S9S_MB_2U(SCH_1):M_G_CPU0_SB_DQS_DN<4>
  J13    238  DQS4_B_N  SCONN288_ADR50001P013C01  I127
  J14    238  DQS4_B_N  SCONN288_ADR50001P003C01  I124
  U2     EB36  DDR6_SB_DQS_DN4  SOCKET4677_AZIFS054P001C01  I169

M_G_CPU0_SB_DQS_DN<5>   @S9S_MB_2U_LIB.S9S_MB_2U(SCH_1):M_G_CPU0_SB_DQS_DN<5>
  J13    249  DQS5_B_N  SCONN288_ADR50001P013C01  I127
  J14    249  DQS5_B_N  SCONN288_ADR50001P003C01  I124
  U2     DR33  DDR6_SB_DQS_DN5  SOCKET4677_AZIFS054P001C01  I169

M_G_CPU0_SB_DQS_DN<6>   @S9S_MB_2U_LIB.S9S_MB_2U(SCH_1):M_G_CPU0_SB_DQS_DN<6>
  J13    260  DQS6_B_N  SCONN288_ADR50001P013C01  I127
  J14    260  DQS6_B_N  SCONN288_ADR50001P003C01  I124
  U2     DN27  DDR6_SB_DQS_DN6  SOCKET4677_AZIFS054P001C01  I169

M_G_CPU0_SB_DQS_DN<7>   @S9S_MB_2U_LIB.S9S_MB_2U(SCH_1):M_G_CPU0_SB_DQS_DN<7>
  J13    271  DQS7_B_N  SCONN288_ADR50001P013C01  I127
  J14    271  DQS7_B_N  SCONN288_ADR50001P003C01  I124
  U2     EB24  DDR6_SB_DQS_DN7  SOCKET4677_AZIFS054P001C01  I169

M_G_CPU0_SB_DQS_DN<8>   @S9S_MB_2U_LIB.S9S_MB_2U(SCH_1):M_G_CPU0_SB_DQS_DN<8>
  J13    282  DQS8_B_N  SCONN288_ADR50001P013C01  I127
  J14    282  DQS8_B_N  SCONN288_ADR50001P003C01  I124
  U2     EM6  DDR6_SB_DQS_DN8  SOCKET4677_AZIFS054P001C01  I169

M_G_CPU0_SB_DQS_DN<9>   @S9S_MB_2U_LIB.S9S_MB_2U(SCH_1):M_G_CPU0_SB_DQS_DN<9>
  J13     94  DQS9_B_N  SCONN288_ADR50001P013C01  I127
  J14     94  DQS9_B_N  SCONN288_ADR50001P003C01  I124
  U2     DV36  DDR6_SB_DQS_DN9  SOCKET4677_AZIFS054P001C01  I169

M_G_CPU0_SB_DQS_DP<0>   @S9S_MB_2U_LIB.S9S_MB_2U(SCH_1):M_G_CPU0_SB_DQS_DP<0>
  J13    104  DQS0_B_P  SCONN288_ADR50001P013C01  I127
  J14    104  DQS0_B_P  SCONN288_ADR50001P003C01  I124
  U2     DL33  DDR6_SB_DQS_DP0  SOCKET4677_AZIFS054P001C01  I169

M_G_CPU0_SB_DQS_DP<1>   @S9S_MB_2U_LIB.S9S_MB_2U(SCH_1):M_G_CPU0_SB_DQS_DP<1>
  J13    115  DQS1_B_P  SCONN288_ADR50001P013C01  I127
  J14    115  DQS1_B_P  SCONN288_ADR50001P003C01  I124
  U2     DL27  DDR6_SB_DQS_DP1  SOCKET4677_AZIFS054P001C01  I169

M_G_CPU0_SB_DQS_DP<2>   @S9S_MB_2U_LIB.S9S_MB_2U(SCH_1):M_G_CPU0_SB_DQS_DP<2>
  J13    126  DQS2_B_P  SCONN288_ADR50001P013C01  I127
  J14    126  DQS2_B_P  SCONN288_ADR50001P003C01  I124
  U2     DT24  DDR6_SB_DQS_DP2  SOCKET4677_AZIFS054P001C01  I169

M_G_CPU0_SB_DQS_DP<3>   @S9S_MB_2U_LIB.S9S_MB_2U(SCH_1):M_G_CPU0_SB_DQS_DP<3>
  J13    137  DQS3_B_P  SCONN288_ADR50001P013C01  I127
  J14    137  DQS3_B_P  SCONN288_ADR50001P003C01  I124
  U2     EN7  DDR6_SB_DQS_DP3  SOCKET4677_AZIFS054P001C01  I169

M_G_CPU0_SB_DQS_DP<4>   @S9S_MB_2U_LIB.S9S_MB_2U(SCH_1):M_G_CPU0_SB_DQS_DP<4>
  J13    239  DQS4_B_P  SCONN288_ADR50001P013C01  I127
  J14    239  DQS4_B_P  SCONN288_ADR50001P003C01  I124
  U2     DY36  DDR6_SB_DQS_DP4  SOCKET4677_AZIFS054P001C01  I169

M_G_CPU0_SB_DQS_DP<5>   @S9S_MB_2U_LIB.S9S_MB_2U(SCH_1):M_G_CPU0_SB_DQS_DP<5>
  J13    250  DQS5_B_P  SCONN288_ADR50001P013C01  I127
  J14    250  DQS5_B_P  SCONN288_ADR50001P003C01  I124
  U2     DN33  DDR6_SB_DQS_DP5  SOCKET4677_AZIFS054P001C01  I169

M_G_CPU0_SB_DQS_DP<6>   @S9S_MB_2U_LIB.S9S_MB_2U(SCH_1):M_G_CPU0_SB_DQS_DP<6>
  J13    261  DQS6_B_P  SCONN288_ADR50001P013C01  I127
  J14    261  DQS6_B_P  SCONN288_ADR50001P003C01  I124
  U2     DR27  DDR6_SB_DQS_DP6  SOCKET4677_AZIFS054P001C01  I169

M_G_CPU0_SB_DQS_DP<7>   @S9S_MB_2U_LIB.S9S_MB_2U(SCH_1):M_G_CPU0_SB_DQS_DP<7>
  J13    272  DQS7_B_P  SCONN288_ADR50001P013C01  I127
  J14    272  DQS7_B_P  SCONN288_ADR50001P003C01  I124
  U2     DY24  DDR6_SB_DQS_DP7  SOCKET4677_AZIFS054P001C01  I169

M_G_CPU0_SB_DQS_DP<8>   @S9S_MB_2U_LIB.S9S_MB_2U(SCH_1):M_G_CPU0_SB_DQS_DP<8>
  J13    283  DQS8_B_P  SCONN288_ADR50001P013C01  I127
  J14    283  DQS8_B_P  SCONN288_ADR50001P003C01  I124
  U2     EN5  DDR6_SB_DQS_DP8  SOCKET4677_AZIFS054P001C01  I169

M_G_CPU0_SB_DQS_DP<9>   @S9S_MB_2U_LIB.S9S_MB_2U(SCH_1):M_G_CPU0_SB_DQS_DP<9>
  J13     93  DQS9_B_P  SCONN288_ADR50001P013C01  I127
  J14     93  DQS9_B_P  SCONN288_ADR50001P003C01  I124
  U2     DT36  DDR6_SB_DQS_DP9  SOCKET4677_AZIFS054P001C01  I169

M_G_CPU0_SB_PAR   @S9S_MB_2U_LIB.S9S_MB_2U(SCH_1):M_G_CPU0_SB_PAR
  J13    227  PAR_B  SCONN288_ADR50001P013C01  I11
  J14    227  PAR_B  SCONN288_ADR50001P003C01  I47
  U2     EB42  DDR6_SB_PAR  SOCKET4677_AZIFS054P001C01  I169

M_G_CPU0_SB_RSP<0>   @S9S_MB_2U_LIB.S9S_MB_2U(SCH_1):M_G_CPU0_SB_RSP<0>
  J13     87  LBS||RSP_N_B  SCONN288_ADR50001P013C01  I11
  U2     DU48  DDR6_B_RSP0  SOCKET4677_AZIFS054P001C01  I169

M_G_CPU0_SB_RSP<1>   @S9S_MB_2U_LIB.S9S_MB_2U(SCH_1):M_G_CPU0_SB_RSP<1>
  J14     87  LBS||RSP_N_B  SCONN288_ADR50001P003C01  I47
  U2     DV47  DDR6_B_RSP1  SOCKET4677_AZIFS054P001C01  I169

M_G_CPU1_ALERT_N   @S9S_MB_2U_LIB.S9S_MB_2U(SCH_1):M_G_CPU1_ALERT_N
  J29     62  ALERT_N  SCONN288_ADR50001P013C01  I179
  J30     62  ALERT_N  SCONN288_ADR50001P003C01  I179
  U1     CW50  DDR6_ALERT_N  SOCKET4677_AZIFS054P001C01  I168

M_G_CPU1_CLK_DN<0>   @S9S_MB_2U_LIB.S9S_MB_2U(SCH_1):M_G_CPU1_CLK_DN<0>
  J29    218   CK_N  SCONN288_ADR50001P013C01  I179
  U1     DR45  DDR6_CLK_DN0  SOCKET4677_AZIFS054P001C01  I168

M_G_CPU1_CLK_DN<1>   @S9S_MB_2U_LIB.S9S_MB_2U(SCH_1):M_G_CPU1_CLK_DN<1>
  J30    218   CK_N  SCONN288_ADR50001P003C01  I179
  U1     DL45  DDR6_CLK_DN1  SOCKET4677_AZIFS054P001C01  I168

M_G_CPU1_CLK_DP<0>   @S9S_MB_2U_LIB.S9S_MB_2U(SCH_1):M_G_CPU1_CLK_DP<0>
  J29    217   CK_P  SCONN288_ADR50001P013C01  I179
  U1     DN45  DDR6_CLK_DP0  SOCKET4677_AZIFS054P001C01  I168

M_G_CPU1_CLK_DP<1>   @S9S_MB_2U_LIB.S9S_MB_2U(SCH_1):M_G_CPU1_CLK_DP<1>
  J30    217   CK_P  SCONN288_ADR50001P003C01  I179
  U1     DJ45  DDR6_CLK_DP1  SOCKET4677_AZIFS054P001C01  I168

M_G_CPU1_SA_CA<0>   @S9S_MB_2U_LIB.S9S_MB_2U(SCH_1):M_G_CPU1_SA_CA<0>
  J29     66  CA0_A  SCONN288_ADR50001P013C01  I179
  J30     66  CA0_A  SCONN288_ADR50001P003C01  I179
  U1     DJ52  DDR6_SA_CA0  SOCKET4677_AZIFS054P001C01  I168

M_G_CPU1_SA_CA<1>   @S9S_MB_2U_LIB.S9S_MB_2U(SCH_1):M_G_CPU1_SA_CA<1>
  J29    211  CA1_A  SCONN288_ADR50001P013C01  I179
  J30    211  CA1_A  SCONN288_ADR50001P003C01  I179
  U1     DR52  DDR6_SA_CA1  SOCKET4677_AZIFS054P001C01  I168

M_G_CPU1_SA_CA<2>   @S9S_MB_2U_LIB.S9S_MB_2U(SCH_1):M_G_CPU1_SA_CA<2>
  J29     68  CA2_A  SCONN288_ADR50001P013C01  I179
  J30     68  CA2_A  SCONN288_ADR50001P003C01  I179
  U1     DK51  DDR6_SA_CA2  SOCKET4677_AZIFS054P001C01  I168

M_G_CPU1_SA_CA<3>   @S9S_MB_2U_LIB.S9S_MB_2U(SCH_1):M_G_CPU1_SA_CA<3>
  J29    213  CA3_A  SCONN288_ADR50001P013C01  I179
  J30    213  CA3_A  SCONN288_ADR50001P003C01  I179
  U1     DP51  DDR6_SA_CA3  SOCKET4677_AZIFS054P001C01  I168

M_G_CPU1_SA_CA<4>   @S9S_MB_2U_LIB.S9S_MB_2U(SCH_1):M_G_CPU1_SA_CA<4>
  J29     70  CA4_A  SCONN288_ADR50001P013C01  I179
  J30     70  CA4_A  SCONN288_ADR50001P003C01  I179
  U1     DL50  DDR6_SA_CA4  SOCKET4677_AZIFS054P001C01  I168

M_G_CPU1_SA_CA<5>   @S9S_MB_2U_LIB.S9S_MB_2U(SCH_1):M_G_CPU1_SA_CA<5>
  J29    215  CA5_A  SCONN288_ADR50001P013C01  I179
  J30    215  CA5_A  SCONN288_ADR50001P003C01  I179
  U1     DN50  DDR6_SA_CA5  SOCKET4677_AZIFS054P001C01  I168

M_G_CPU1_SA_CA<6>   @S9S_MB_2U_LIB.S9S_MB_2U(SCH_1):M_G_CPU1_SA_CA<6>
  J29     72  CA6_A  SCONN288_ADR50001P013C01  I179
  J30     72  CA6_A  SCONN288_ADR50001P003C01  I179
  U1     DK44  DDR6_SA_CA6  SOCKET4677_AZIFS054P001C01  I168

M_G_CPU1_SA_CB<0>   @S9S_MB_2U_LIB.S9S_MB_2U(SCH_1):M_G_CPU1_SA_CB<0>
  J29     51  CB_A0  SCONN288_ADR50001P013C01  I179
  J30     51  CB_A0  SCONN288_ADR50001P003C01  I179
  U1     DL60  DDR6_SA_ECC0  SOCKET4677_AZIFS054P001C01  I168

M_G_CPU1_SA_CB<1>   @S9S_MB_2U_LIB.S9S_MB_2U(SCH_1):M_G_CPU1_SA_CB<1>
  J29     53  CB_A1  SCONN288_ADR50001P013C01  I179
  J30     53  CB_A1  SCONN288_ADR50001P003C01  I179
  U1     DK59  DDR6_SA_ECC1  SOCKET4677_AZIFS054P001C01  I168

M_G_CPU1_SA_CB<2>   @S9S_MB_2U_LIB.S9S_MB_2U(SCH_1):M_G_CPU1_SA_CB<2>
  J29    196  CB_A2  SCONN288_ADR50001P013C01  I179
  J30    196  CB_A2  SCONN288_ADR50001P003C01  I179
  U1     DN60  DDR6_SA_ECC2  SOCKET4677_AZIFS054P001C01  I168

M_G_CPU1_SA_CB<3>   @S9S_MB_2U_LIB.S9S_MB_2U(SCH_1):M_G_CPU1_SA_CB<3>
  J29    198  CB_A3  SCONN288_ADR50001P013C01  I179
  J30    198  CB_A3  SCONN288_ADR50001P003C01  I179
  U1     DP59  DDR6_SA_ECC3  SOCKET4677_AZIFS054P001C01  I168

M_G_CPU1_SA_CB<4>   @S9S_MB_2U_LIB.S9S_MB_2U(SCH_1):M_G_CPU1_SA_CB<4>
  J29     58  CB_A4  SCONN288_ADR50001P013C01  I179
  J30     58  CB_A4  SCONN288_ADR50001P003C01  I179
  U1     DK57  DDR6_SA_ECC4  SOCKET4677_AZIFS054P001C01  I168

M_G_CPU1_SA_CB<5>   @S9S_MB_2U_LIB.S9S_MB_2U(SCH_1):M_G_CPU1_SA_CB<5>
  J29     60  CB_A5  SCONN288_ADR50001P013C01  I179
  J30     60  CB_A5  SCONN288_ADR50001P003C01  I179
  U1     DL56  DDR6_SA_ECC5  SOCKET4677_AZIFS054P001C01  I168

M_G_CPU1_SA_CB<6>   @S9S_MB_2U_LIB.S9S_MB_2U(SCH_1):M_G_CPU1_SA_CB<6>
  J29    203  CB_A6  SCONN288_ADR50001P013C01  I179
  J30    203  CB_A6  SCONN288_ADR50001P003C01  I179
  U1     DP57  DDR6_SA_ECC6  SOCKET4677_AZIFS054P001C01  I168

M_G_CPU1_SA_CB<7>   @S9S_MB_2U_LIB.S9S_MB_2U(SCH_1):M_G_CPU1_SA_CB<7>
  J29    205  CB_A7  SCONN288_ADR50001P013C01  I179
  J30    205  CB_A7  SCONN288_ADR50001P003C01  I179
  U1     DN56  DDR6_SA_ECC7  SOCKET4677_AZIFS054P001C01  I168

M_G_CPU1_SA_CS_N<0>   @S9S_MB_2U_LIB.S9S_MB_2U(SCH_1):M_G_CPU1_SA_CS_N<0>
  J29     64  CS0_N_A  SCONN288_ADR50001P013C01  I179
  U1     DN54  DDR6_SA_CS0_N  SOCKET4677_AZIFS054P001C01  I168

M_G_CPU1_SA_CS_N<1>   @S9S_MB_2U_LIB.S9S_MB_2U(SCH_1):M_G_CPU1_SA_CS_N<1>
  J29    209  CS1_N_A  SCONN288_ADR50001P013C01  I179
  U1     DP53  DDR6_SA_CS1_N  SOCKET4677_AZIFS054P001C01  I168

M_G_CPU1_SA_CS_N<2>   @S9S_MB_2U_LIB.S9S_MB_2U(SCH_1):M_G_CPU1_SA_CS_N<2>
  J30     64  CS0_N_A  SCONN288_ADR50001P003C01  I179
  U1     DL54  DDR6_SA_CS2_N  SOCKET4677_AZIFS054P001C01  I168

M_G_CPU1_SA_CS_N<3>   @S9S_MB_2U_LIB.S9S_MB_2U(SCH_1):M_G_CPU1_SA_CS_N<3>
  J30    209  CS1_N_A  SCONN288_ADR50001P003C01  I179
  U1     DK53  DDR6_SA_CS3_N  SOCKET4677_AZIFS054P001C01  I168

M_G_CPU1_SA_DQ<0>   @S9S_MB_2U_LIB.S9S_MB_2U(SCH_1):M_G_CPU1_SA_DQ<0>
  J29      7  DQ_A0  SCONN288_ADR50001P013C01  I179
  J30      7  DQ_A0  SCONN288_ADR50001P003C01  I179
  U1     DV75  DDR6_SA_DQ0  SOCKET4677_AZIFS054P001C01  I168

M_G_CPU1_SA_DQ<1>   @S9S_MB_2U_LIB.S9S_MB_2U(SCH_1):M_G_CPU1_SA_DQ<1>
  J29      9  DQ_A1  SCONN288_ADR50001P013C01  I179
  J30      9  DQ_A1  SCONN288_ADR50001P003C01  I179
  U1     DU74  DDR6_SA_DQ1  SOCKET4677_AZIFS054P001C01  I168

M_G_CPU1_SA_DQ<2>   @S9S_MB_2U_LIB.S9S_MB_2U(SCH_1):M_G_CPU1_SA_DQ<2>
  J29    152  DQ_A2  SCONN288_ADR50001P013C01  I179
  J30    152  DQ_A2  SCONN288_ADR50001P003C01  I179
  U1     DY75  DDR6_SA_DQ2  SOCKET4677_AZIFS054P001C01  I168

M_G_CPU1_SA_DQ<3>   @S9S_MB_2U_LIB.S9S_MB_2U(SCH_1):M_G_CPU1_SA_DQ<3>
  J29    154  DQ_A3  SCONN288_ADR50001P013C01  I179
  J30    154  DQ_A3  SCONN288_ADR50001P003C01  I179
  U1     EA74  DDR6_SA_DQ3  SOCKET4677_AZIFS054P001C01  I168

M_G_CPU1_SA_DQ<4>   @S9S_MB_2U_LIB.S9S_MB_2U(SCH_1):M_G_CPU1_SA_DQ<4>
  J29     14  DQ_A4  SCONN288_ADR50001P013C01  I179
  J30     14  DQ_A4  SCONN288_ADR50001P003C01  I179
  U1     DU72  DDR6_SA_DQ4  SOCKET4677_AZIFS054P001C01  I168

M_G_CPU1_SA_DQ<5>   @S9S_MB_2U_LIB.S9S_MB_2U(SCH_1):M_G_CPU1_SA_DQ<5>
  J29     16  DQ_A5  SCONN288_ADR50001P013C01  I179
  J30     16  DQ_A5  SCONN288_ADR50001P003C01  I179
  U1     DV71  DDR6_SA_DQ5  SOCKET4677_AZIFS054P001C01  I168

M_G_CPU1_SA_DQ<6>   @S9S_MB_2U_LIB.S9S_MB_2U(SCH_1):M_G_CPU1_SA_DQ<6>
  J29    159  DQ_A6  SCONN288_ADR50001P013C01  I179
  J30    159  DQ_A6  SCONN288_ADR50001P003C01  I179
  U1     EA72  DDR6_SA_DQ6  SOCKET4677_AZIFS054P001C01  I168

M_G_CPU1_SA_DQ<7>   @S9S_MB_2U_LIB.S9S_MB_2U(SCH_1):M_G_CPU1_SA_DQ<7>
  J29    161  DQ_A7  SCONN288_ADR50001P013C01  I179
  J30    161  DQ_A7  SCONN288_ADR50001P003C01  I179
  U1     DY71  DDR6_SA_DQ7  SOCKET4677_AZIFS054P001C01  I168

M_G_CPU1_SA_DQ<8>   @S9S_MB_2U_LIB.S9S_MB_2U(SCH_1):M_G_CPU1_SA_DQ<8>
  J29     18  DQ_A8  SCONN288_ADR50001P013C01  I179
  J30     18  DQ_A8  SCONN288_ADR50001P003C01  I179
  U1     DL72  DDR6_SA_DQ8  SOCKET4677_AZIFS054P001C01  I168

M_G_CPU1_SA_DQ<9>   @S9S_MB_2U_LIB.S9S_MB_2U(SCH_1):M_G_CPU1_SA_DQ<9>
  J29     20  DQ_A9  SCONN288_ADR50001P013C01  I179
  J30     20  DQ_A9  SCONN288_ADR50001P003C01  I179
  U1     DK71  DDR6_SA_DQ9  SOCKET4677_AZIFS054P001C01  I168

M_G_CPU1_SA_DQ<10>   @S9S_MB_2U_LIB.S9S_MB_2U(SCH_1):M_G_CPU1_SA_DQ<10>
  J29    163  DQ_A10  SCONN288_ADR50001P013C01  I179
  J30    163  DQ_A10  SCONN288_ADR50001P003C01  I179
  U1     DN72  DDR6_SA_DQ10  SOCKET4677_AZIFS054P001C01  I168

M_G_CPU1_SA_DQ<11>   @S9S_MB_2U_LIB.S9S_MB_2U(SCH_1):M_G_CPU1_SA_DQ<11>
  J29    165  DQ_A11  SCONN288_ADR50001P013C01  I179
  J30    165  DQ_A11  SCONN288_ADR50001P003C01  I179
  U1     DP71  DDR6_SA_DQ11  SOCKET4677_AZIFS054P001C01  I168

M_G_CPU1_SA_DQ<12>   @S9S_MB_2U_LIB.S9S_MB_2U(SCH_1):M_G_CPU1_SA_DQ<12>
  J29     25  DQ_A12  SCONN288_ADR50001P013C01  I179
  J30     25  DQ_A12  SCONN288_ADR50001P003C01  I179
  U1     DK69  DDR6_SA_DQ12  SOCKET4677_AZIFS054P001C01  I168

M_G_CPU1_SA_DQ<13>   @S9S_MB_2U_LIB.S9S_MB_2U(SCH_1):M_G_CPU1_SA_DQ<13>
  J29     27  DQ_A13  SCONN288_ADR50001P013C01  I179
  J30     27  DQ_A13  SCONN288_ADR50001P003C01  I179
  U1     DL68  DDR6_SA_DQ13  SOCKET4677_AZIFS054P001C01  I168

M_G_CPU1_SA_DQ<14>   @S9S_MB_2U_LIB.S9S_MB_2U(SCH_1):M_G_CPU1_SA_DQ<14>
  J29    170  DQ_A14  SCONN288_ADR50001P013C01  I179
  J30    170  DQ_A14  SCONN288_ADR50001P003C01  I179
  U1     DP69  DDR6_SA_DQ14  SOCKET4677_AZIFS054P001C01  I168

M_G_CPU1_SA_DQ<15>   @S9S_MB_2U_LIB.S9S_MB_2U(SCH_1):M_G_CPU1_SA_DQ<15>
  J29    172  DQ_A15  SCONN288_ADR50001P013C01  I179
  J30    172  DQ_A15  SCONN288_ADR50001P003C01  I179
  U1     DN68  DDR6_SA_DQ15  SOCKET4677_AZIFS054P001C01  I168

M_G_CPU1_SA_DQ<16>   @S9S_MB_2U_LIB.S9S_MB_2U(SCH_1):M_G_CPU1_SA_DQ<16>
  J29     29  DQ_A16  SCONN288_ADR50001P013C01  I179
  J30     29  DQ_A16  SCONN288_ADR50001P003C01  I179
  U1     DV63  DDR6_SA_DQ16  SOCKET4677_AZIFS054P001C01  I168

M_G_CPU1_SA_DQ<17>   @S9S_MB_2U_LIB.S9S_MB_2U(SCH_1):M_G_CPU1_SA_DQ<17>
  J29     31  DQ_A17  SCONN288_ADR50001P013C01  I179
  J30     31  DQ_A17  SCONN288_ADR50001P003C01  I179
  U1     DU62  DDR6_SA_DQ17  SOCKET4677_AZIFS054P001C01  I168

M_G_CPU1_SA_DQ<18>   @S9S_MB_2U_LIB.S9S_MB_2U(SCH_1):M_G_CPU1_SA_DQ<18>
  J29    174  DQ_A18  SCONN288_ADR50001P013C01  I179
  J30    174  DQ_A18  SCONN288_ADR50001P003C01  I179
  U1     DY63  DDR6_SA_DQ18  SOCKET4677_AZIFS054P001C01  I168

M_G_CPU1_SA_DQ<19>   @S9S_MB_2U_LIB.S9S_MB_2U(SCH_1):M_G_CPU1_SA_DQ<19>
  J29    176  DQ_A19  SCONN288_ADR50001P013C01  I179
  J30    176  DQ_A19  SCONN288_ADR50001P003C01  I179
  U1     EA62  DDR6_SA_DQ19  SOCKET4677_AZIFS054P001C01  I168

M_G_CPU1_SA_DQ<20>   @S9S_MB_2U_LIB.S9S_MB_2U(SCH_1):M_G_CPU1_SA_DQ<20>
  J29     36  DQ_A20  SCONN288_ADR50001P013C01  I179
  J30     36  DQ_A20  SCONN288_ADR50001P003C01  I179
  U1     DU60  DDR6_SA_DQ20  SOCKET4677_AZIFS054P001C01  I168

M_G_CPU1_SA_DQ<21>   @S9S_MB_2U_LIB.S9S_MB_2U(SCH_1):M_G_CPU1_SA_DQ<21>
  J29     38  DQ_A21  SCONN288_ADR50001P013C01  I179
  J30     38  DQ_A21  SCONN288_ADR50001P003C01  I179
  U1     DV59  DDR6_SA_DQ21  SOCKET4677_AZIFS054P001C01  I168

M_G_CPU1_SA_DQ<22>   @S9S_MB_2U_LIB.S9S_MB_2U(SCH_1):M_G_CPU1_SA_DQ<22>
  J29    181  DQ_A22  SCONN288_ADR50001P013C01  I179
  J30    181  DQ_A22  SCONN288_ADR50001P003C01  I179
  U1     EA60  DDR6_SA_DQ22  SOCKET4677_AZIFS054P001C01  I168

M_G_CPU1_SA_DQ<23>   @S9S_MB_2U_LIB.S9S_MB_2U(SCH_1):M_G_CPU1_SA_DQ<23>
  J29    183  DQ_A23  SCONN288_ADR50001P013C01  I179
  J30    183  DQ_A23  SCONN288_ADR50001P003C01  I179
  U1     DY59  DDR6_SA_DQ23  SOCKET4677_AZIFS054P001C01  I168

M_G_CPU1_SA_DQ<24>   @S9S_MB_2U_LIB.S9S_MB_2U(SCH_1):M_G_CPU1_SA_DQ<24>
  J29     40  DQ_A24  SCONN288_ADR50001P013C01  I179
  J30     40  DQ_A24  SCONN288_ADR50001P003C01  I179
  U1     DL66  DDR6_SA_DQ24  SOCKET4677_AZIFS054P001C01  I168

M_G_CPU1_SA_DQ<25>   @S9S_MB_2U_LIB.S9S_MB_2U(SCH_1):M_G_CPU1_SA_DQ<25>
  J29     42  DQ_A25  SCONN288_ADR50001P013C01  I179
  J30     42  DQ_A25  SCONN288_ADR50001P003C01  I179
  U1     DK65  DDR6_SA_DQ25  SOCKET4677_AZIFS054P001C01  I168

M_G_CPU1_SA_DQ<26>   @S9S_MB_2U_LIB.S9S_MB_2U(SCH_1):M_G_CPU1_SA_DQ<26>
  J29    185  DQ_A26  SCONN288_ADR50001P013C01  I179
  J30    185  DQ_A26  SCONN288_ADR50001P003C01  I179
  U1     DN66  DDR6_SA_DQ26  SOCKET4677_AZIFS054P001C01  I168

M_G_CPU1_SA_DQ<27>   @S9S_MB_2U_LIB.S9S_MB_2U(SCH_1):M_G_CPU1_SA_DQ<27>
  J29    187  DQ_A27  SCONN288_ADR50001P013C01  I179
  J30    187  DQ_A27  SCONN288_ADR50001P003C01  I179
  U1     DP65  DDR6_SA_DQ27  SOCKET4677_AZIFS054P001C01  I168

M_G_CPU1_SA_DQ<28>   @S9S_MB_2U_LIB.S9S_MB_2U(SCH_1):M_G_CPU1_SA_DQ<28>
  J29     47  DQ_A28  SCONN288_ADR50001P013C01  I179
  J30     47  DQ_A28  SCONN288_ADR50001P003C01  I179
  U1     DK63  DDR6_SA_DQ28  SOCKET4677_AZIFS054P001C01  I168

M_G_CPU1_SA_DQ<29>   @S9S_MB_2U_LIB.S9S_MB_2U(SCH_1):M_G_CPU1_SA_DQ<29>
  J29     49  DQ_A29  SCONN288_ADR50001P013C01  I179
  J30     49  DQ_A29  SCONN288_ADR50001P003C01  I179
  U1     DL62  DDR6_SA_DQ29  SOCKET4677_AZIFS054P001C01  I168

M_G_CPU1_SA_DQ<30>   @S9S_MB_2U_LIB.S9S_MB_2U(SCH_1):M_G_CPU1_SA_DQ<30>
  J29    192  DQ_A30  SCONN288_ADR50001P013C01  I179
  J30    192  DQ_A30  SCONN288_ADR50001P003C01  I179
  U1     DP63  DDR6_SA_DQ30  SOCKET4677_AZIFS054P001C01  I168

M_G_CPU1_SA_DQ<31>   @S9S_MB_2U_LIB.S9S_MB_2U(SCH_1):M_G_CPU1_SA_DQ<31>
  J29    194  DQ_A31  SCONN288_ADR50001P013C01  I179
  J30    194  DQ_A31  SCONN288_ADR50001P003C01  I179
  U1     DN62  DDR6_SA_DQ31  SOCKET4677_AZIFS054P001C01  I168

M_G_CPU1_SA_DQS_DN<0>   @S9S_MB_2U_LIB.S9S_MB_2U(SCH_1):M_G_CPU1_SA_DQS_DN<0>
  J29     12  DQS0_A_N  SCONN288_ADR50001P013C01  I177
  J30     12  DQS0_A_N  SCONN288_ADR50001P003C01  I177
  U1     DV73  DDR6_SA_DQS_DN0  SOCKET4677_AZIFS054P001C01  I168

M_G_CPU1_SA_DQS_DN<1>   @S9S_MB_2U_LIB.S9S_MB_2U(SCH_1):M_G_CPU1_SA_DQS_DN<1>
  J29     23  DQS1_A_N  SCONN288_ADR50001P013C01  I177
  J30     23  DQS1_A_N  SCONN288_ADR50001P003C01  I177
  U1     DJ70  DDR6_SA_DQS_DN1  SOCKET4677_AZIFS054P001C01  I168

M_G_CPU1_SA_DQS_DN<2>   @S9S_MB_2U_LIB.S9S_MB_2U(SCH_1):M_G_CPU1_SA_DQS_DN<2>
  J29     34  DQS2_A_N  SCONN288_ADR50001P013C01  I177
  J30     34  DQS2_A_N  SCONN288_ADR50001P003C01  I177
  U1     DT61  DDR6_SA_DQS_DN2  SOCKET4677_AZIFS054P001C01  I168

M_G_CPU1_SA_DQS_DN<3>   @S9S_MB_2U_LIB.S9S_MB_2U(SCH_1):M_G_CPU1_SA_DQS_DN<3>
  J29     45  DQS3_A_N  SCONN288_ADR50001P013C01  I177
  J30     45  DQS3_A_N  SCONN288_ADR50001P003C01  I177
  U1     DL64  DDR6_SA_DQS_DN3  SOCKET4677_AZIFS054P001C01  I168

M_G_CPU1_SA_DQS_DN<4>   @S9S_MB_2U_LIB.S9S_MB_2U(SCH_1):M_G_CPU1_SA_DQS_DN<4>
  J29     56  DQS4_A_N  SCONN288_ADR50001P013C01  I177
  J30     56  DQS4_A_N  SCONN288_ADR50001P003C01  I177
  U1     DL58  DDR6_SA_DQS_DN4  SOCKET4677_AZIFS054P001C01  I168

M_G_CPU1_SA_DQS_DN<5>   @S9S_MB_2U_LIB.S9S_MB_2U(SCH_1):M_G_CPU1_SA_DQS_DN<5>
  J29    156  DQS5_A_N  SCONN288_ADR50001P013C01  I177
  J30    156  DQS5_A_N  SCONN288_ADR50001P003C01  I177
  U1     EB73  DDR6_SA_DQS_DN5  SOCKET4677_AZIFS054P001C01  I168

M_G_CPU1_SA_DQS_DN<6>   @S9S_MB_2U_LIB.S9S_MB_2U(SCH_1):M_G_CPU1_SA_DQS_DN<6>
  J29    167  DQS6_A_N  SCONN288_ADR50001P013C01  I177
  J30    167  DQS6_A_N  SCONN288_ADR50001P003C01  I177
  U1     DR70  DDR6_SA_DQS_DN6  SOCKET4677_AZIFS054P001C01  I168

M_G_CPU1_SA_DQS_DN<7>   @S9S_MB_2U_LIB.S9S_MB_2U(SCH_1):M_G_CPU1_SA_DQS_DN<7>
  J29    178  DQS7_A_N  SCONN288_ADR50001P013C01  I177
  J30    178  DQS7_A_N  SCONN288_ADR50001P003C01  I177
  U1     EB61  DDR6_SA_DQS_DN7  SOCKET4677_AZIFS054P001C01  I168

M_G_CPU1_SA_DQS_DN<8>   @S9S_MB_2U_LIB.S9S_MB_2U(SCH_1):M_G_CPU1_SA_DQS_DN<8>
  J29    189  DQS8_A_N  SCONN288_ADR50001P013C01  I177
  J30    189  DQS8_A_N  SCONN288_ADR50001P003C01  I177
  U1     DR64  DDR6_SA_DQS_DN8  SOCKET4677_AZIFS054P001C01  I168

M_G_CPU1_SA_DQS_DN<9>   @S9S_MB_2U_LIB.S9S_MB_2U(SCH_1):M_G_CPU1_SA_DQS_DN<9>
  J29    200  DQS9_A_N  SCONN288_ADR50001P013C01  I177
  J30    200  DQS9_A_N  SCONN288_ADR50001P003C01  I177
  U1     DR58  DDR6_SA_DQS_DN9  SOCKET4677_AZIFS054P001C01  I168

M_G_CPU1_SA_DQS_DP<0>   @S9S_MB_2U_LIB.S9S_MB_2U(SCH_1):M_G_CPU1_SA_DQS_DP<0>
  J29     11  DQS0_A_P  SCONN288_ADR50001P013C01  I177
  J30     11  DQS0_A_P  SCONN288_ADR50001P003C01  I177
  U1     DT73  DDR6_SA_DQS_DP0  SOCKET4677_AZIFS054P001C01  I168

M_G_CPU1_SA_DQS_DP<1>   @S9S_MB_2U_LIB.S9S_MB_2U(SCH_1):M_G_CPU1_SA_DQS_DP<1>
  J29     22  DQS1_A_P  SCONN288_ADR50001P013C01  I177
  J30     22  DQS1_A_P  SCONN288_ADR50001P003C01  I177
  U1     DL70  DDR6_SA_DQS_DP1  SOCKET4677_AZIFS054P001C01  I168

M_G_CPU1_SA_DQS_DP<2>   @S9S_MB_2U_LIB.S9S_MB_2U(SCH_1):M_G_CPU1_SA_DQS_DP<2>
  J29     33  DQS2_A_P  SCONN288_ADR50001P013C01  I177
  J30     33  DQS2_A_P  SCONN288_ADR50001P003C01  I177
  U1     DV61  DDR6_SA_DQS_DP2  SOCKET4677_AZIFS054P001C01  I168

M_G_CPU1_SA_DQS_DP<3>   @S9S_MB_2U_LIB.S9S_MB_2U(SCH_1):M_G_CPU1_SA_DQS_DP<3>
  J29     44  DQS3_A_P  SCONN288_ADR50001P013C01  I177
  J30     44  DQS3_A_P  SCONN288_ADR50001P003C01  I177
  U1     DJ64  DDR6_SA_DQS_DP3  SOCKET4677_AZIFS054P001C01  I168

M_G_CPU1_SA_DQS_DP<4>   @S9S_MB_2U_LIB.S9S_MB_2U(SCH_1):M_G_CPU1_SA_DQS_DP<4>
  J29     55  DQS4_A_P  SCONN288_ADR50001P013C01  I177
  J30     55  DQS4_A_P  SCONN288_ADR50001P003C01  I177
  U1     DJ58  DDR6_SA_DQS_DP4  SOCKET4677_AZIFS054P001C01  I168

M_G_CPU1_SA_DQS_DP<5>   @S9S_MB_2U_LIB.S9S_MB_2U(SCH_1):M_G_CPU1_SA_DQS_DP<5>
  J29    157  DQS5_A_P  SCONN288_ADR50001P013C01  I177
  J30    157  DQS5_A_P  SCONN288_ADR50001P003C01  I177
  U1     DY73  DDR6_SA_DQS_DP5  SOCKET4677_AZIFS054P001C01  I168

M_G_CPU1_SA_DQS_DP<6>   @S9S_MB_2U_LIB.S9S_MB_2U(SCH_1):M_G_CPU1_SA_DQS_DP<6>
  J29    168  DQS6_A_P  SCONN288_ADR50001P013C01  I177
  J30    168  DQS6_A_P  SCONN288_ADR50001P003C01  I177
  U1     DN70  DDR6_SA_DQS_DP6  SOCKET4677_AZIFS054P001C01  I168

M_G_CPU1_SA_DQS_DP<7>   @S9S_MB_2U_LIB.S9S_MB_2U(SCH_1):M_G_CPU1_SA_DQS_DP<7>
  J29    179  DQS7_A_P  SCONN288_ADR50001P013C01  I177
  J30    179  DQS7_A_P  SCONN288_ADR50001P003C01  I177
  U1     DY61  DDR6_SA_DQS_DP7  SOCKET4677_AZIFS054P001C01  I168

M_G_CPU1_SA_DQS_DP<8>   @S9S_MB_2U_LIB.S9S_MB_2U(SCH_1):M_G_CPU1_SA_DQS_DP<8>
  J29    190  DQS8_A_P  SCONN288_ADR50001P013C01  I177
  J30    190  DQS8_A_P  SCONN288_ADR50001P003C01  I177
  U1     DN64  DDR6_SA_DQS_DP8  SOCKET4677_AZIFS054P001C01  I168

M_G_CPU1_SA_DQS_DP<9>   @S9S_MB_2U_LIB.S9S_MB_2U(SCH_1):M_G_CPU1_SA_DQS_DP<9>
  J29    201  DQS9_A_P  SCONN288_ADR50001P013C01  I177
  J30    201  DQS9_A_P  SCONN288_ADR50001P003C01  I177
  U1     DN58  DDR6_SA_DQS_DP9  SOCKET4677_AZIFS054P001C01  I168

M_G_CPU1_SA_PAR   @S9S_MB_2U_LIB.S9S_MB_2U(SCH_1):M_G_CPU1_SA_PAR
  J29     74  PAR_A  SCONN288_ADR50001P013C01  I179
  J30     74  PAR_A  SCONN288_ADR50001P003C01  I179
  U1     DL43  DDR6_SA_PAR  SOCKET4677_AZIFS054P001C01  I168

M_G_CPU1_SA_RSP<0>   @S9S_MB_2U_LIB.S9S_MB_2U(SCH_1):M_G_CPU1_SA_RSP<0>
  J29     86  LBD||RSP_N_A  SCONN288_ADR50001P013C01  I179
  U1     EA48  DDR6_A_RSP0  SOCKET4677_AZIFS054P001C01  I168

M_G_CPU1_SA_RSP<1>   @S9S_MB_2U_LIB.S9S_MB_2U(SCH_1):M_G_CPU1_SA_RSP<1>
  J30     86  LBD||RSP_N_A  SCONN288_ADR50001P003C01  I179
  U1     DY47  DDR6_A_RSP1  SOCKET4677_AZIFS054P001C01  I168

M_G_CPU1_SB_CA<0>   @S9S_MB_2U_LIB.S9S_MB_2U(SCH_1):M_G_CPU1_SB_CA<0>
  J29     76  CA0_B  SCONN288_ADR50001P013C01  I179
  J30     76  CA0_B  SCONN288_ADR50001P003C01  I179
  U1     DN43  DDR6_SB_CA0  SOCKET4677_AZIFS054P001C01  I168

M_G_CPU1_SB_CA<1>   @S9S_MB_2U_LIB.S9S_MB_2U(SCH_1):M_G_CPU1_SB_CA<1>
  J29    221  CA1_B  SCONN288_ADR50001P013C01  I179
  J30    221  CA1_B  SCONN288_ADR50001P003C01  I179
  U1     DP44  DDR6_SB_CA1  SOCKET4677_AZIFS054P001C01  I168

M_G_CPU1_SB_CA<2>   @S9S_MB_2U_LIB.S9S_MB_2U(SCH_1):M_G_CPU1_SB_CA<2>
  J29     78  CA2_B  SCONN288_ADR50001P013C01  I179
  J30     78  CA2_B  SCONN288_ADR50001P003C01  I179
  U1     DV44  DDR6_SB_CA2  SOCKET4677_AZIFS054P001C01  I168

M_G_CPU1_SB_CA<3>   @S9S_MB_2U_LIB.S9S_MB_2U(SCH_1):M_G_CPU1_SB_CA<3>
  J29    223  CA3_B  SCONN288_ADR50001P013C01  I179
  J30    223  CA3_B  SCONN288_ADR50001P003C01  I179
  U1     DY44  DDR6_SB_CA3  SOCKET4677_AZIFS054P001C01  I168

M_G_CPU1_SB_CA<4>   @S9S_MB_2U_LIB.S9S_MB_2U(SCH_1):M_G_CPU1_SB_CA<4>
  J29     80  CA4_B  SCONN288_ADR50001P013C01  I179
  J30     80  CA4_B  SCONN288_ADR50001P003C01  I179
  U1     DU43  DDR6_SB_CA4  SOCKET4677_AZIFS054P001C01  I168

M_G_CPU1_SB_CA<5>   @S9S_MB_2U_LIB.S9S_MB_2U(SCH_1):M_G_CPU1_SB_CA<5>
  J29    225  CA5_B  SCONN288_ADR50001P013C01  I179
  J30    225  CA5_B  SCONN288_ADR50001P003C01  I179
  U1     EA43  DDR6_SB_CA5  SOCKET4677_AZIFS054P001C01  I168

M_G_CPU1_SB_CA<6>   @S9S_MB_2U_LIB.S9S_MB_2U(SCH_1):M_G_CPU1_SB_CA<6>
  J29     82  CA6_B  SCONN288_ADR50001P013C01  I179
  J30     82  CA6_B  SCONN288_ADR50001P003C01  I179
  U1     DT42  DDR6_SB_CA6  SOCKET4677_AZIFS054P001C01  I168

M_G_CPU1_SB_CB<0>   @S9S_MB_2U_LIB.S9S_MB_2U(SCH_1):M_G_CPU1_SB_CB<0>
  J29     96  CB_B0  SCONN288_ADR50001P013C01  I179
  J30     96  CB_B0  SCONN288_ADR50001P003C01  I179
  U1     DU35  DDR6_SB_ECC0  SOCKET4677_AZIFS054P001C01  I168

M_G_CPU1_SB_CB<1>   @S9S_MB_2U_LIB.S9S_MB_2U(SCH_1):M_G_CPU1_SB_CB<1>
  J29     98  CB_B1  SCONN288_ADR50001P013C01  I179
  J30     98  CB_B1  SCONN288_ADR50001P003C01  I179
  U1     DV34  DDR6_SB_ECC1  SOCKET4677_AZIFS054P001C01  I168

M_G_CPU1_SB_CB<2>   @S9S_MB_2U_LIB.S9S_MB_2U(SCH_1):M_G_CPU1_SB_CB<2>
  J29    241  CB_B2  SCONN288_ADR50001P013C01  I179
  J30    241  CB_B2  SCONN288_ADR50001P003C01  I179
  U1     EA35  DDR6_SB_ECC2  SOCKET4677_AZIFS054P001C01  I168

M_G_CPU1_SB_CB<3>   @S9S_MB_2U_LIB.S9S_MB_2U(SCH_1):M_G_CPU1_SB_CB<3>
  J29    243  CB_B3  SCONN288_ADR50001P013C01  I179
  J30    243  CB_B3  SCONN288_ADR50001P003C01  I179
  U1     DY34  DDR6_SB_ECC3  SOCKET4677_AZIFS054P001C01  I168

M_G_CPU1_SB_CB<4>   @S9S_MB_2U_LIB.S9S_MB_2U(SCH_1):M_G_CPU1_SB_CB<4>
  J29     89  CB_B4  SCONN288_ADR50001P013C01  I179
  J30     89  CB_B4  SCONN288_ADR50001P003C01  I179
  U1     DV38  DDR6_SB_ECC4  SOCKET4677_AZIFS054P001C01  I168

M_G_CPU1_SB_CB<5>   @S9S_MB_2U_LIB.S9S_MB_2U(SCH_1):M_G_CPU1_SB_CB<5>
  J29     91  CB_B5  SCONN288_ADR50001P013C01  I179
  J30     91  CB_B5  SCONN288_ADR50001P003C01  I179
  U1     DU37  DDR6_SB_ECC5  SOCKET4677_AZIFS054P001C01  I168

M_G_CPU1_SB_CB<6>   @S9S_MB_2U_LIB.S9S_MB_2U(SCH_1):M_G_CPU1_SB_CB<6>
  J29    234  CB_B6  SCONN288_ADR50001P013C01  I179
  J30    234  CB_B6  SCONN288_ADR50001P003C01  I179
  U1     DY38  DDR6_SB_ECC6  SOCKET4677_AZIFS054P001C01  I168

M_G_CPU1_SB_CB<7>   @S9S_MB_2U_LIB.S9S_MB_2U(SCH_1):M_G_CPU1_SB_CB<7>
  J29    236  CB_B7  SCONN288_ADR50001P013C01  I179
  J30    236  CB_B7  SCONN288_ADR50001P003C01  I179
  U1     EA37  DDR6_SB_ECC7  SOCKET4677_AZIFS054P001C01  I168

M_G_CPU1_SB_CS_N<0>   @S9S_MB_2U_LIB.S9S_MB_2U(SCH_1):M_G_CPU1_SB_CS_N<0>
  J29     84  CS0_N_B  SCONN288_ADR50001P013C01  I179
  U1     EA41  DDR6_SB_CS0_N  SOCKET4677_AZIFS054P001C01  I168

M_G_CPU1_SB_CS_N<1>   @S9S_MB_2U_LIB.S9S_MB_2U(SCH_1):M_G_CPU1_SB_CS_N<1>
  J29    229  CS1_N_B  SCONN288_ADR50001P013C01  I179
  U1     DY40  DDR6_SB_CS1_N  SOCKET4677_AZIFS054P001C01  I168

M_G_CPU1_SB_CS_N<2>   @S9S_MB_2U_LIB.S9S_MB_2U(SCH_1):M_G_CPU1_SB_CS_N<2>
  J30     84  CS0_N_B  SCONN288_ADR50001P003C01  I179
  U1     DU41  DDR6_SB_CS2_N  SOCKET4677_AZIFS054P001C01  I168

M_G_CPU1_SB_CS_N<3>   @S9S_MB_2U_LIB.S9S_MB_2U(SCH_1):M_G_CPU1_SB_CS_N<3>
  J30    229  CS1_N_B  SCONN288_ADR50001P003C01  I179
  U1     DV40  DDR6_SB_CS3_N  SOCKET4677_AZIFS054P001C01  I168

M_G_CPU1_SB_DQ<0>   @S9S_MB_2U_LIB.S9S_MB_2U(SCH_1):M_G_CPU1_SB_DQ<0>
  J29    100  DQ_B0  SCONN288_ADR50001P013C01  I179
  J30    100  DQ_B0  SCONN288_ADR50001P003C01  I179
  U1     DL35  DDR6_SB_DQ0  SOCKET4677_AZIFS054P001C01  I168

M_G_CPU1_SB_DQ<1>   @S9S_MB_2U_LIB.S9S_MB_2U(SCH_1):M_G_CPU1_SB_DQ<1>
  J29    102  DQ_B1  SCONN288_ADR50001P013C01  I179
  J30    102  DQ_B1  SCONN288_ADR50001P003C01  I179
  U1     DK34  DDR6_SB_DQ1  SOCKET4677_AZIFS054P001C01  I168

M_G_CPU1_SB_DQ<2>   @S9S_MB_2U_LIB.S9S_MB_2U(SCH_1):M_G_CPU1_SB_DQ<2>
  J29    245  DQ_B2  SCONN288_ADR50001P013C01  I179
  J30    245  DQ_B2  SCONN288_ADR50001P003C01  I179
  U1     DN35  DDR6_SB_DQ2  SOCKET4677_AZIFS054P001C01  I168

M_G_CPU1_SB_DQ<3>   @S9S_MB_2U_LIB.S9S_MB_2U(SCH_1):M_G_CPU1_SB_DQ<3>
  J29    247  DQ_B3  SCONN288_ADR50001P013C01  I179
  J30    247  DQ_B3  SCONN288_ADR50001P003C01  I179
  U1     DP34  DDR6_SB_DQ3  SOCKET4677_AZIFS054P001C01  I168

M_G_CPU1_SB_DQ<4>   @S9S_MB_2U_LIB.S9S_MB_2U(SCH_1):M_G_CPU1_SB_DQ<4>
  J29    107  DQ_B4  SCONN288_ADR50001P013C01  I179
  J30    107  DQ_B4  SCONN288_ADR50001P003C01  I179
  U1     DK32  DDR6_SB_DQ4  SOCKET4677_AZIFS054P001C01  I168

M_G_CPU1_SB_DQ<5>   @S9S_MB_2U_LIB.S9S_MB_2U(SCH_1):M_G_CPU1_SB_DQ<5>
  J29    109  DQ_B5  SCONN288_ADR50001P013C01  I179
  J30    109  DQ_B5  SCONN288_ADR50001P003C01  I179
  U1     DL31  DDR6_SB_DQ5  SOCKET4677_AZIFS054P001C01  I168

M_G_CPU1_SB_DQ<6>   @S9S_MB_2U_LIB.S9S_MB_2U(SCH_1):M_G_CPU1_SB_DQ<6>
  J29    252  DQ_B6  SCONN288_ADR50001P013C01  I179
  J30    252  DQ_B6  SCONN288_ADR50001P003C01  I179
  U1     DP32  DDR6_SB_DQ6  SOCKET4677_AZIFS054P001C01  I168

M_G_CPU1_SB_DQ<7>   @S9S_MB_2U_LIB.S9S_MB_2U(SCH_1):M_G_CPU1_SB_DQ<7>
  J29    254  DQ_B7  SCONN288_ADR50001P013C01  I179
  J30    254  DQ_B7  SCONN288_ADR50001P003C01  I179
  U1     DN31  DDR6_SB_DQ7  SOCKET4677_AZIFS054P001C01  I168

M_G_CPU1_SB_DQ<8>   @S9S_MB_2U_LIB.S9S_MB_2U(SCH_1):M_G_CPU1_SB_DQ<8>
  J29    111  DQ_B8  SCONN288_ADR50001P013C01  I179
  J30    111  DQ_B8  SCONN288_ADR50001P003C01  I179
  U1     DN29  DDR6_SB_DQ8  SOCKET4677_AZIFS054P001C01  I168

M_G_CPU1_SB_DQ<9>   @S9S_MB_2U_LIB.S9S_MB_2U(SCH_1):M_G_CPU1_SB_DQ<9>
  J29    113  DQ_B9  SCONN288_ADR50001P013C01  I179
  J30    113  DQ_B9  SCONN288_ADR50001P003C01  I179
  U1     DK28  DDR6_SB_DQ9  SOCKET4677_AZIFS054P001C01  I168

M_G_CPU1_SB_DQ<10>   @S9S_MB_2U_LIB.S9S_MB_2U(SCH_1):M_G_CPU1_SB_DQ<10>
  J29    256  DQ_B10  SCONN288_ADR50001P013C01  I179
  J30    256  DQ_B10  SCONN288_ADR50001P003C01  I179
  U1     DL29  DDR6_SB_DQ10  SOCKET4677_AZIFS054P001C01  I168

M_G_CPU1_SB_DQ<11>   @S9S_MB_2U_LIB.S9S_MB_2U(SCH_1):M_G_CPU1_SB_DQ<11>
  J29    258  DQ_B11  SCONN288_ADR50001P013C01  I179
  J30    258  DQ_B11  SCONN288_ADR50001P003C01  I179
  U1     DP28  DDR6_SB_DQ11  SOCKET4677_AZIFS054P001C01  I168

M_G_CPU1_SB_DQ<12>   @S9S_MB_2U_LIB.S9S_MB_2U(SCH_1):M_G_CPU1_SB_DQ<12>
  J29    118  DQ_B12  SCONN288_ADR50001P013C01  I179
  J30    118  DQ_B12  SCONN288_ADR50001P003C01  I179
  U1     DK26  DDR6_SB_DQ12  SOCKET4677_AZIFS054P001C01  I168

M_G_CPU1_SB_DQ<13>   @S9S_MB_2U_LIB.S9S_MB_2U(SCH_1):M_G_CPU1_SB_DQ<13>
  J29    120  DQ_B13  SCONN288_ADR50001P013C01  I179
  J30    120  DQ_B13  SCONN288_ADR50001P003C01  I179
  U1     DL25  DDR6_SB_DQ13  SOCKET4677_AZIFS054P001C01  I168

M_G_CPU1_SB_DQ<14>   @S9S_MB_2U_LIB.S9S_MB_2U(SCH_1):M_G_CPU1_SB_DQ<14>
  J29    263  DQ_B14  SCONN288_ADR50001P013C01  I179
  J30    263  DQ_B14  SCONN288_ADR50001P003C01  I179
  U1     DP26  DDR6_SB_DQ14  SOCKET4677_AZIFS054P001C01  I168

M_G_CPU1_SB_DQ<15>   @S9S_MB_2U_LIB.S9S_MB_2U(SCH_1):M_G_CPU1_SB_DQ<15>
  J29    265  DQ_B15  SCONN288_ADR50001P013C01  I179
  J30    265  DQ_B15  SCONN288_ADR50001P003C01  I179
  U1     DN25  DDR6_SB_DQ15  SOCKET4677_AZIFS054P001C01  I168

M_G_CPU1_SB_DQ<16>   @S9S_MB_2U_LIB.S9S_MB_2U(SCH_1):M_G_CPU1_SB_DQ<16>
  J29    122  DQ_B16  SCONN288_ADR50001P013C01  I179
  J30    122  DQ_B16  SCONN288_ADR50001P003C01  I179
  U1     DV26  DDR6_SB_DQ16  SOCKET4677_AZIFS054P001C01  I168

M_G_CPU1_SB_DQ<17>   @S9S_MB_2U_LIB.S9S_MB_2U(SCH_1):M_G_CPU1_SB_DQ<17>
  J29    124  DQ_B17  SCONN288_ADR50001P013C01  I179
  J30    124  DQ_B17  SCONN288_ADR50001P003C01  I179
  U1     DU25  DDR6_SB_DQ17  SOCKET4677_AZIFS054P001C01  I168

M_G_CPU1_SB_DQ<18>   @S9S_MB_2U_LIB.S9S_MB_2U(SCH_1):M_G_CPU1_SB_DQ<18>
  J29    267  DQ_B18  SCONN288_ADR50001P013C01  I179
  J30    267  DQ_B18  SCONN288_ADR50001P003C01  I179
  U1     DY26  DDR6_SB_DQ18  SOCKET4677_AZIFS054P001C01  I168

M_G_CPU1_SB_DQ<19>   @S9S_MB_2U_LIB.S9S_MB_2U(SCH_1):M_G_CPU1_SB_DQ<19>
  J29    269  DQ_B19  SCONN288_ADR50001P013C01  I179
  J30    269  DQ_B19  SCONN288_ADR50001P003C01  I179
  U1     EA25  DDR6_SB_DQ19  SOCKET4677_AZIFS054P001C01  I168

M_G_CPU1_SB_DQ<20>   @S9S_MB_2U_LIB.S9S_MB_2U(SCH_1):M_G_CPU1_SB_DQ<20>
  J29    129  DQ_B20  SCONN288_ADR50001P013C01  I179
  J30    129  DQ_B20  SCONN288_ADR50001P003C01  I179
  U1     DU23  DDR6_SB_DQ20  SOCKET4677_AZIFS054P001C01  I168

M_G_CPU1_SB_DQ<21>   @S9S_MB_2U_LIB.S9S_MB_2U(SCH_1):M_G_CPU1_SB_DQ<21>
  J29    131  DQ_B21  SCONN288_ADR50001P013C01  I179
  J30    131  DQ_B21  SCONN288_ADR50001P003C01  I179
  U1     DV22  DDR6_SB_DQ21  SOCKET4677_AZIFS054P001C01  I168

M_G_CPU1_SB_DQ<22>   @S9S_MB_2U_LIB.S9S_MB_2U(SCH_1):M_G_CPU1_SB_DQ<22>
  J29    274  DQ_B22  SCONN288_ADR50001P013C01  I179
  J30    274  DQ_B22  SCONN288_ADR50001P003C01  I179
  U1     EA23  DDR6_SB_DQ22  SOCKET4677_AZIFS054P001C01  I168

M_G_CPU1_SB_DQ<23>   @S9S_MB_2U_LIB.S9S_MB_2U(SCH_1):M_G_CPU1_SB_DQ<23>
  J29    276  DQ_B23  SCONN288_ADR50001P013C01  I179
  J30    276  DQ_B23  SCONN288_ADR50001P003C01  I179
  U1     DY22  DDR6_SB_DQ23  SOCKET4677_AZIFS054P001C01  I168

M_G_CPU1_SB_DQ<24>   @S9S_MB_2U_LIB.S9S_MB_2U(SCH_1):M_G_CPU1_SB_DQ<24>
  J29    133  DQ_B24  SCONN288_ADR50001P013C01  I179
  J30    133  DQ_B24  SCONN288_ADR50001P003C01  I179
  U1     EK8  DDR6_SB_DQ24  SOCKET4677_AZIFS054P001C01  I168

M_G_CPU1_SB_DQ<25>   @S9S_MB_2U_LIB.S9S_MB_2U(SCH_1):M_G_CPU1_SB_DQ<25>
  J29    135  DQ_B25  SCONN288_ADR50001P013C01  I179
  J30    135  DQ_B25  SCONN288_ADR50001P003C01  I179
  U1     EH8  DDR6_SB_DQ25  SOCKET4677_AZIFS054P001C01  I168

M_G_CPU1_SB_DQ<26>   @S9S_MB_2U_LIB.S9S_MB_2U(SCH_1):M_G_CPU1_SB_DQ<26>
  J29    278  DQ_B26  SCONN288_ADR50001P013C01  I179
  J30    278  DQ_B26  SCONN288_ADR50001P003C01  I179
  U1     EP8  DDR6_SB_DQ26  SOCKET4677_AZIFS054P001C01  I168

M_G_CPU1_SB_DQ<27>   @S9S_MB_2U_LIB.S9S_MB_2U(SCH_1):M_G_CPU1_SB_DQ<27>
  J29    280  DQ_B27  SCONN288_ADR50001P013C01  I179
  J30    280  DQ_B27  SCONN288_ADR50001P003C01  I179
  U1     ET8  DDR6_SB_DQ27  SOCKET4677_AZIFS054P001C01  I168

M_G_CPU1_SB_DQ<28>   @S9S_MB_2U_LIB.S9S_MB_2U(SCH_1):M_G_CPU1_SB_DQ<28>
  J29    140  DQ_B28  SCONN288_ADR50001P013C01  I179
  J30    140  DQ_B28  SCONN288_ADR50001P003C01  I179
  U1     EK6  DDR6_SB_DQ28  SOCKET4677_AZIFS054P001C01  I168

M_G_CPU1_SB_DQ<29>   @S9S_MB_2U_LIB.S9S_MB_2U(SCH_1):M_G_CPU1_SB_DQ<29>
  J29    142  DQ_B29  SCONN288_ADR50001P013C01  I179
  J30    142  DQ_B29  SCONN288_ADR50001P003C01  I179
  U1     EJ5  DDR6_SB_DQ29  SOCKET4677_AZIFS054P001C01  I168

M_G_CPU1_SB_DQ<30>   @S9S_MB_2U_LIB.S9S_MB_2U(SCH_1):M_G_CPU1_SB_DQ<30>
  J29    285  DQ_B30  SCONN288_ADR50001P013C01  I179
  J30    285  DQ_B30  SCONN288_ADR50001P003C01  I179
  U1     EP4  DDR6_SB_DQ30  SOCKET4677_AZIFS054P001C01  I168

M_G_CPU1_SB_DQ<31>   @S9S_MB_2U_LIB.S9S_MB_2U(SCH_1):M_G_CPU1_SB_DQ<31>
  J29    287  DQ_B31  SCONN288_ADR50001P013C01  I179
  J30    287  DQ_B31  SCONN288_ADR50001P003C01  I179
  U1     EM4  DDR6_SB_DQ31  SOCKET4677_AZIFS054P001C01  I168

M_G_CPU1_SB_DQS_DN<0>   @S9S_MB_2U_LIB.S9S_MB_2U(SCH_1):M_G_CPU1_SB_DQS_DN<0>
  J29    105  DQS0_B_N  SCONN288_ADR50001P013C01  I177
  J30    105  DQS0_B_N  SCONN288_ADR50001P003C01  I177
  U1     DJ33  DDR6_SB_DQS_DN0  SOCKET4677_AZIFS054P001C01  I168

M_G_CPU1_SB_DQS_DN<1>   @S9S_MB_2U_LIB.S9S_MB_2U(SCH_1):M_G_CPU1_SB_DQS_DN<1>
  J29    116  DQS1_B_N  SCONN288_ADR50001P013C01  I177
  J30    116  DQS1_B_N  SCONN288_ADR50001P003C01  I177
  U1     DJ27  DDR6_SB_DQS_DN1  SOCKET4677_AZIFS054P001C01  I168

M_G_CPU1_SB_DQS_DN<2>   @S9S_MB_2U_LIB.S9S_MB_2U(SCH_1):M_G_CPU1_SB_DQS_DN<2>
  J29    127  DQS2_B_N  SCONN288_ADR50001P013C01  I177
  J30    127  DQS2_B_N  SCONN288_ADR50001P003C01  I177
  U1     DV24  DDR6_SB_DQS_DN2  SOCKET4677_AZIFS054P001C01  I168

M_G_CPU1_SB_DQS_DN<3>   @S9S_MB_2U_LIB.S9S_MB_2U(SCH_1):M_G_CPU1_SB_DQS_DN<3>
  J29    138  DQS3_B_N  SCONN288_ADR50001P013C01  I177
  J30    138  DQS3_B_N  SCONN288_ADR50001P003C01  I177
  U1     EP6  DDR6_SB_DQS_DN3  SOCKET4677_AZIFS054P001C01  I168

M_G_CPU1_SB_DQS_DN<4>   @S9S_MB_2U_LIB.S9S_MB_2U(SCH_1):M_G_CPU1_SB_DQS_DN<4>
  J29    238  DQS4_B_N  SCONN288_ADR50001P013C01  I177
  J30    238  DQS4_B_N  SCONN288_ADR50001P003C01  I177
  U1     EB36  DDR6_SB_DQS_DN4  SOCKET4677_AZIFS054P001C01  I168

M_G_CPU1_SB_DQS_DN<5>   @S9S_MB_2U_LIB.S9S_MB_2U(SCH_1):M_G_CPU1_SB_DQS_DN<5>
  J29    249  DQS5_B_N  SCONN288_ADR50001P013C01  I177
  J30    249  DQS5_B_N  SCONN288_ADR50001P003C01  I177
  U1     DR33  DDR6_SB_DQS_DN5  SOCKET4677_AZIFS054P001C01  I168

M_G_CPU1_SB_DQS_DN<6>   @S9S_MB_2U_LIB.S9S_MB_2U(SCH_1):M_G_CPU1_SB_DQS_DN<6>
  J29    260  DQS6_B_N  SCONN288_ADR50001P013C01  I177
  J30    260  DQS6_B_N  SCONN288_ADR50001P003C01  I177
  U1     DN27  DDR6_SB_DQS_DN6  SOCKET4677_AZIFS054P001C01  I168

M_G_CPU1_SB_DQS_DN<7>   @S9S_MB_2U_LIB.S9S_MB_2U(SCH_1):M_G_CPU1_SB_DQS_DN<7>
  J29    271  DQS7_B_N  SCONN288_ADR50001P013C01  I177
  J30    271  DQS7_B_N  SCONN288_ADR50001P003C01  I177
  U1     EB24  DDR6_SB_DQS_DN7  SOCKET4677_AZIFS054P001C01  I168

M_G_CPU1_SB_DQS_DN<8>   @S9S_MB_2U_LIB.S9S_MB_2U(SCH_1):M_G_CPU1_SB_DQS_DN<8>
  J29    282  DQS8_B_N  SCONN288_ADR50001P013C01  I177
  J30    282  DQS8_B_N  SCONN288_ADR50001P003C01  I177
  U1     EM6  DDR6_SB_DQS_DN8  SOCKET4677_AZIFS054P001C01  I168

M_G_CPU1_SB_DQS_DN<9>   @S9S_MB_2U_LIB.S9S_MB_2U(SCH_1):M_G_CPU1_SB_DQS_DN<9>
  J29     94  DQS9_B_N  SCONN288_ADR50001P013C01  I177
  J30     94  DQS9_B_N  SCONN288_ADR50001P003C01  I177
  U1     DV36  DDR6_SB_DQS_DN9  SOCKET4677_AZIFS054P001C01  I168

M_G_CPU1_SB_DQS_DP<0>   @S9S_MB_2U_LIB.S9S_MB_2U(SCH_1):M_G_CPU1_SB_DQS_DP<0>
  J29    104  DQS0_B_P  SCONN288_ADR50001P013C01  I177
  J30    104  DQS0_B_P  SCONN288_ADR50001P003C01  I177
  U1     DL33  DDR6_SB_DQS_DP0  SOCKET4677_AZIFS054P001C01  I168

M_G_CPU1_SB_DQS_DP<1>   @S9S_MB_2U_LIB.S9S_MB_2U(SCH_1):M_G_CPU1_SB_DQS_DP<1>
  J29    115  DQS1_B_P  SCONN288_ADR50001P013C01  I177
  J30    115  DQS1_B_P  SCONN288_ADR50001P003C01  I177
  U1     DL27  DDR6_SB_DQS_DP1  SOCKET4677_AZIFS054P001C01  I168

M_G_CPU1_SB_DQS_DP<2>   @S9S_MB_2U_LIB.S9S_MB_2U(SCH_1):M_G_CPU1_SB_DQS_DP<2>
  J29    126  DQS2_B_P  SCONN288_ADR50001P013C01  I177
  J30    126  DQS2_B_P  SCONN288_ADR50001P003C01  I177
  U1     DT24  DDR6_SB_DQS_DP2  SOCKET4677_AZIFS054P001C01  I168

M_G_CPU1_SB_DQS_DP<3>   @S9S_MB_2U_LIB.S9S_MB_2U(SCH_1):M_G_CPU1_SB_DQS_DP<3>
  J29    137  DQS3_B_P  SCONN288_ADR50001P013C01  I177
  J30    137  DQS3_B_P  SCONN288_ADR50001P003C01  I177
  U1     EN7  DDR6_SB_DQS_DP3  SOCKET4677_AZIFS054P001C01  I168

M_G_CPU1_SB_DQS_DP<4>   @S9S_MB_2U_LIB.S9S_MB_2U(SCH_1):M_G_CPU1_SB_DQS_DP<4>
  J29    239  DQS4_B_P  SCONN288_ADR50001P013C01  I177
  J30    239  DQS4_B_P  SCONN288_ADR50001P003C01  I177
  U1     DY36  DDR6_SB_DQS_DP4  SOCKET4677_AZIFS054P001C01  I168

M_G_CPU1_SB_DQS_DP<5>   @S9S_MB_2U_LIB.S9S_MB_2U(SCH_1):M_G_CPU1_SB_DQS_DP<5>
  J29    250  DQS5_B_P  SCONN288_ADR50001P013C01  I177
  J30    250  DQS5_B_P  SCONN288_ADR50001P003C01  I177
  U1     DN33  DDR6_SB_DQS_DP5  SOCKET4677_AZIFS054P001C01  I168

M_G_CPU1_SB_DQS_DP<6>   @S9S_MB_2U_LIB.S9S_MB_2U(SCH_1):M_G_CPU1_SB_DQS_DP<6>
  J29    261  DQS6_B_P  SCONN288_ADR50001P013C01  I177
  J30    261  DQS6_B_P  SCONN288_ADR50001P003C01  I177
  U1     DR27  DDR6_SB_DQS_DP6  SOCKET4677_AZIFS054P001C01  I168

M_G_CPU1_SB_DQS_DP<7>   @S9S_MB_2U_LIB.S9S_MB_2U(SCH_1):M_G_CPU1_SB_DQS_DP<7>
  J29    272  DQS7_B_P  SCONN288_ADR50001P013C01  I177
  J30    272  DQS7_B_P  SCONN288_ADR50001P003C01  I177
  U1     DY24  DDR6_SB_DQS_DP7  SOCKET4677_AZIFS054P001C01  I168

M_G_CPU1_SB_DQS_DP<8>   @S9S_MB_2U_LIB.S9S_MB_2U(SCH_1):M_G_CPU1_SB_DQS_DP<8>
  J29    283  DQS8_B_P  SCONN288_ADR50001P013C01  I177
  J30    283  DQS8_B_P  SCONN288_ADR50001P003C01  I177
  U1     EN5  DDR6_SB_DQS_DP8  SOCKET4677_AZIFS054P001C01  I168

M_G_CPU1_SB_DQS_DP<9>   @S9S_MB_2U_LIB.S9S_MB_2U(SCH_1):M_G_CPU1_SB_DQS_DP<9>
  J29     93  DQS9_B_P  SCONN288_ADR50001P013C01  I177
  J30     93  DQS9_B_P  SCONN288_ADR50001P003C01  I177
  U1     DT36  DDR6_SB_DQS_DP9  SOCKET4677_AZIFS054P001C01  I168

M_G_CPU1_SB_PAR   @S9S_MB_2U_LIB.S9S_MB_2U(SCH_1):M_G_CPU1_SB_PAR
  J29    227  PAR_B  SCONN288_ADR50001P013C01  I179
  J30    227  PAR_B  SCONN288_ADR50001P003C01  I179
  U1     EB42  DDR6_SB_PAR  SOCKET4677_AZIFS054P001C01  I168

M_G_CPU1_SB_RSP<0>   @S9S_MB_2U_LIB.S9S_MB_2U(SCH_1):M_G_CPU1_SB_RSP<0>
  J29     87  LBS||RSP_N_B  SCONN288_ADR50001P013C01  I179
  U1     DU48  DDR6_B_RSP0  SOCKET4677_AZIFS054P001C01  I168

M_G_CPU1_SB_RSP<1>   @S9S_MB_2U_LIB.S9S_MB_2U(SCH_1):M_G_CPU1_SB_RSP<1>
  J30     87  LBS||RSP_N_B  SCONN288_ADR50001P003C01  I179
  U1     DV47  DDR6_B_RSP1  SOCKET4677_AZIFS054P001C01  I168

M_H_CPU0_ALERT_N   @S9S_MB_2U_LIB.S9S_MB_2U(SCH_1):M_H_CPU0_ALERT_N
  J15     62  ALERT_N  SCONN288_ADR50001P013C01  I48
  J16     62  ALERT_N  SCONN288_ADR50001P003C01   I6
  U2     CY51  DDR7_ALERT_N  SOCKET4677_AZIFS054P001C01  I169

M_H_CPU0_CLK_DN<0>   @S9S_MB_2U_LIB.S9S_MB_2U(SCH_1):M_H_CPU0_CLK_DN<0>
  J15    218   CK_N  SCONN288_ADR50001P013C01  I48
  U2     DH42  DDR7_CLK_DN0  SOCKET4677_AZIFS054P001C01  I169

M_H_CPU0_CLK_DN<1>   @S9S_MB_2U_LIB.S9S_MB_2U(SCH_1):M_H_CPU0_CLK_DN<1>
  J16    218   CK_N  SCONN288_ADR50001P003C01   I6
  U2     DD42  DDR7_CLK_DN1  SOCKET4677_AZIFS054P001C01  I169

M_H_CPU0_CLK_DP<0>   @S9S_MB_2U_LIB.S9S_MB_2U(SCH_1):M_H_CPU0_CLK_DP<0>
  J15    217   CK_P  SCONN288_ADR50001P013C01  I48
  U2     DF42  DDR7_CLK_DP0  SOCKET4677_AZIFS054P001C01  I169

M_H_CPU0_CLK_DP<1>   @S9S_MB_2U_LIB.S9S_MB_2U(SCH_1):M_H_CPU0_CLK_DP<1>
  J16    217   CK_P  SCONN288_ADR50001P003C01   I6
  U2     DB42  DDR7_CLK_DP1  SOCKET4677_AZIFS054P001C01  I169

M_H_CPU0_SA_CA<0>   @S9S_MB_2U_LIB.S9S_MB_2U(SCH_1):M_H_CPU0_SA_CA<0>
  J15     66  CA0_A  SCONN288_ADR50001P013C01  I48
  J16     66  CA0_A  SCONN288_ADR50001P003C01   I6
  U2     DB49  DDR7_SA_CA0  SOCKET4677_AZIFS054P001C01  I169

M_H_CPU0_SA_CA<1>   @S9S_MB_2U_LIB.S9S_MB_2U(SCH_1):M_H_CPU0_SA_CA<1>
  J15    211  CA1_A  SCONN288_ADR50001P013C01  I48
  J16    211  CA1_A  SCONN288_ADR50001P003C01   I6
  U2     DH49  DDR7_SA_CA1  SOCKET4677_AZIFS054P001C01  I169

M_H_CPU0_SA_CA<2>   @S9S_MB_2U_LIB.S9S_MB_2U(SCH_1):M_H_CPU0_SA_CA<2>
  J15     68  CA2_A  SCONN288_ADR50001P013C01  I48
  J16     68  CA2_A  SCONN288_ADR50001P003C01   I6
  U2     DC48  DDR7_SA_CA2  SOCKET4677_AZIFS054P001C01  I169

M_H_CPU0_SA_CA<3>   @S9S_MB_2U_LIB.S9S_MB_2U(SCH_1):M_H_CPU0_SA_CA<3>
  J15    213  CA3_A  SCONN288_ADR50001P013C01  I48
  J16    213  CA3_A  SCONN288_ADR50001P003C01   I6
  U2     DG48  DDR7_SA_CA3  SOCKET4677_AZIFS054P001C01  I169

M_H_CPU0_SA_CA<4>   @S9S_MB_2U_LIB.S9S_MB_2U(SCH_1):M_H_CPU0_SA_CA<4>
  J15     70  CA4_A  SCONN288_ADR50001P013C01  I48
  J16     70  CA4_A  SCONN288_ADR50001P003C01   I6
  U2     DD47  DDR7_SA_CA4  SOCKET4677_AZIFS054P001C01  I169

M_H_CPU0_SA_CA<5>   @S9S_MB_2U_LIB.S9S_MB_2U(SCH_1):M_H_CPU0_SA_CA<5>
  J15    215  CA5_A  SCONN288_ADR50001P013C01  I48
  J16    215  CA5_A  SCONN288_ADR50001P003C01   I6
  U2     DF47  DDR7_SA_CA5  SOCKET4677_AZIFS054P001C01  I169

M_H_CPU0_SA_CA<6>   @S9S_MB_2U_LIB.S9S_MB_2U(SCH_1):M_H_CPU0_SA_CA<6>
  J15     72  CA6_A  SCONN288_ADR50001P013C01  I48
  J16     72  CA6_A  SCONN288_ADR50001P003C01   I6
  U2     DC41  DDR7_SA_CA6  SOCKET4677_AZIFS054P001C01  I169

M_H_CPU0_SA_CB<0>   @S9S_MB_2U_LIB.S9S_MB_2U(SCH_1):M_H_CPU0_SA_CB<0>
  J15     51  CB_A0  SCONN288_ADR50001P013C01  I48
  J16     51  CB_A0  SCONN288_ADR50001P003C01   I6
  U2     DD57  DDR7_SA_ECC0  SOCKET4677_AZIFS054P001C01  I169

M_H_CPU0_SA_CB<1>   @S9S_MB_2U_LIB.S9S_MB_2U(SCH_1):M_H_CPU0_SA_CB<1>
  J15     53  CB_A1  SCONN288_ADR50001P013C01  I48
  J16     53  CB_A1  SCONN288_ADR50001P003C01   I6
  U2     DC56  DDR7_SA_ECC1  SOCKET4677_AZIFS054P001C01  I169

M_H_CPU0_SA_CB<2>   @S9S_MB_2U_LIB.S9S_MB_2U(SCH_1):M_H_CPU0_SA_CB<2>
  J15    196  CB_A2  SCONN288_ADR50001P013C01  I48
  J16    196  CB_A2  SCONN288_ADR50001P003C01   I6
  U2     DF57  DDR7_SA_ECC2  SOCKET4677_AZIFS054P001C01  I169

M_H_CPU0_SA_CB<3>   @S9S_MB_2U_LIB.S9S_MB_2U(SCH_1):M_H_CPU0_SA_CB<3>
  J15    198  CB_A3  SCONN288_ADR50001P013C01  I48
  J16    198  CB_A3  SCONN288_ADR50001P003C01   I6
  U2     DG56  DDR7_SA_ECC3  SOCKET4677_AZIFS054P001C01  I169

M_H_CPU0_SA_CB<4>   @S9S_MB_2U_LIB.S9S_MB_2U(SCH_1):M_H_CPU0_SA_CB<4>
  J15     58  CB_A4  SCONN288_ADR50001P013C01  I48
  J16     58  CB_A4  SCONN288_ADR50001P003C01   I6
  U2     DC54  DDR7_SA_ECC4  SOCKET4677_AZIFS054P001C01  I169

M_H_CPU0_SA_CB<5>   @S9S_MB_2U_LIB.S9S_MB_2U(SCH_1):M_H_CPU0_SA_CB<5>
  J15     60  CB_A5  SCONN288_ADR50001P013C01  I48
  J16     60  CB_A5  SCONN288_ADR50001P003C01   I6
  U2     DD53  DDR7_SA_ECC5  SOCKET4677_AZIFS054P001C01  I169

M_H_CPU0_SA_CB<6>   @S9S_MB_2U_LIB.S9S_MB_2U(SCH_1):M_H_CPU0_SA_CB<6>
  J15    203  CB_A6  SCONN288_ADR50001P013C01  I48
  J16    203  CB_A6  SCONN288_ADR50001P003C01   I6
  U2     DG54  DDR7_SA_ECC6  SOCKET4677_AZIFS054P001C01  I169

M_H_CPU0_SA_CB<7>   @S9S_MB_2U_LIB.S9S_MB_2U(SCH_1):M_H_CPU0_SA_CB<7>
  J15    205  CB_A7  SCONN288_ADR50001P013C01  I48
  J16    205  CB_A7  SCONN288_ADR50001P003C01   I6
  U2     DF53  DDR7_SA_ECC7  SOCKET4677_AZIFS054P001C01  I169

M_H_CPU0_SA_CS_N<0>   @S9S_MB_2U_LIB.S9S_MB_2U(SCH_1):M_H_CPU0_SA_CS_N<0>
  J15     64  CS0_N_A  SCONN288_ADR50001P013C01  I48
  U2     DF51  DDR7_SA_CS0_N  SOCKET4677_AZIFS054P001C01  I169

M_H_CPU0_SA_CS_N<1>   @S9S_MB_2U_LIB.S9S_MB_2U(SCH_1):M_H_CPU0_SA_CS_N<1>
  J15    209  CS1_N_A  SCONN288_ADR50001P013C01  I48
  U2     DG50  DDR7_SA_CS1_N  SOCKET4677_AZIFS054P001C01  I169

M_H_CPU0_SA_CS_N<2>   @S9S_MB_2U_LIB.S9S_MB_2U(SCH_1):M_H_CPU0_SA_CS_N<2>
  J16     64  CS0_N_A  SCONN288_ADR50001P003C01   I6
  U2     DD51  DDR7_SA_CS2_N  SOCKET4677_AZIFS054P001C01  I169

M_H_CPU0_SA_CS_N<3>   @S9S_MB_2U_LIB.S9S_MB_2U(SCH_1):M_H_CPU0_SA_CS_N<3>
  J16    209  CS1_N_A  SCONN288_ADR50001P003C01   I6
  U2     DC50  DDR7_SA_CS3_N  SOCKET4677_AZIFS054P001C01  I169

M_H_CPU0_SA_DQ<0>   @S9S_MB_2U_LIB.S9S_MB_2U(SCH_1):M_H_CPU0_SA_DQ<0>
  J15      7  DQ_A0  SCONN288_ADR50001P013C01  I48
  J16      7  DQ_A0  SCONN288_ADR50001P003C01   I6
  U2     DY79  DDR7_SA_DQ0  SOCKET4677_AZIFS054P001C01  I169

M_H_CPU0_SA_DQ<1>   @S9S_MB_2U_LIB.S9S_MB_2U(SCH_1):M_H_CPU0_SA_DQ<1>
  J15      9  DQ_A1  SCONN288_ADR50001P013C01  I48
  J16      9  DQ_A1  SCONN288_ADR50001P003C01   I6
  U2     DT77  DDR7_SA_DQ1  SOCKET4677_AZIFS054P001C01  I169

M_H_CPU0_SA_DQ<2>   @S9S_MB_2U_LIB.S9S_MB_2U(SCH_1):M_H_CPU0_SA_DQ<2>
  J15    152  DQ_A2  SCONN288_ADR50001P013C01  I48
  J16    152  DQ_A2  SCONN288_ADR50001P003C01   I6
  U2     DW78  DDR7_SA_DQ2  SOCKET4677_AZIFS054P001C01  I169

M_H_CPU0_SA_DQ<3>   @S9S_MB_2U_LIB.S9S_MB_2U(SCH_1):M_H_CPU0_SA_DQ<3>
  J15    154  DQ_A3  SCONN288_ADR50001P013C01  I48
  J16    154  DQ_A3  SCONN288_ADR50001P003C01   I6
  U2     DP77  DDR7_SA_DQ3  SOCKET4677_AZIFS054P001C01  I169

M_H_CPU0_SA_DQ<4>   @S9S_MB_2U_LIB.S9S_MB_2U(SCH_1):M_H_CPU0_SA_DQ<4>
  J15     14  DQ_A4  SCONN288_ADR50001P013C01  I48
  J16     14  DQ_A4  SCONN288_ADR50001P003C01   I6
  U2     DK75  DDR7_SA_DQ4  SOCKET4677_AZIFS054P001C01  I169

M_H_CPU0_SA_DQ<5>   @S9S_MB_2U_LIB.S9S_MB_2U(SCH_1):M_H_CPU0_SA_DQ<5>
  J15     16  DQ_A5  SCONN288_ADR50001P013C01  I48
  J16     16  DQ_A5  SCONN288_ADR50001P003C01   I6
  U2     DL74  DDR7_SA_DQ5  SOCKET4677_AZIFS054P001C01  I169

M_H_CPU0_SA_DQ<6>   @S9S_MB_2U_LIB.S9S_MB_2U(SCH_1):M_H_CPU0_SA_DQ<6>
  J15    159  DQ_A6  SCONN288_ADR50001P013C01  I48
  J16    159  DQ_A6  SCONN288_ADR50001P003C01   I6
  U2     DP75  DDR7_SA_DQ6  SOCKET4677_AZIFS054P001C01  I169

M_H_CPU0_SA_DQ<7>   @S9S_MB_2U_LIB.S9S_MB_2U(SCH_1):M_H_CPU0_SA_DQ<7>
  J15    161  DQ_A7  SCONN288_ADR50001P013C01  I48
  J16    161  DQ_A7  SCONN288_ADR50001P003C01   I6
  U2     DN74  DDR7_SA_DQ7  SOCKET4677_AZIFS054P001C01  I169

M_H_CPU0_SA_DQ<8>   @S9S_MB_2U_LIB.S9S_MB_2U(SCH_1):M_H_CPU0_SA_DQ<8>
  J15     18  DQ_A8  SCONN288_ADR50001P013C01  I48
  J16     18  DQ_A8  SCONN288_ADR50001P003C01   I6
  U2     DD75  DDR7_SA_DQ8  SOCKET4677_AZIFS054P001C01  I169

M_H_CPU0_SA_DQ<9>   @S9S_MB_2U_LIB.S9S_MB_2U(SCH_1):M_H_CPU0_SA_DQ<9>
  J15     20  DQ_A9  SCONN288_ADR50001P013C01  I48
  J16     20  DQ_A9  SCONN288_ADR50001P003C01   I6
  U2     DC74  DDR7_SA_DQ9  SOCKET4677_AZIFS054P001C01  I169

M_H_CPU0_SA_DQ<10>   @S9S_MB_2U_LIB.S9S_MB_2U(SCH_1):M_H_CPU0_SA_DQ<10>
  J15    163  DQ_A10  SCONN288_ADR50001P013C01  I48
  J16    163  DQ_A10  SCONN288_ADR50001P003C01   I6
  U2     DF75  DDR7_SA_DQ10  SOCKET4677_AZIFS054P001C01  I169

M_H_CPU0_SA_DQ<11>   @S9S_MB_2U_LIB.S9S_MB_2U(SCH_1):M_H_CPU0_SA_DQ<11>
  J15    165  DQ_A11  SCONN288_ADR50001P013C01  I48
  J16    165  DQ_A11  SCONN288_ADR50001P003C01   I6
  U2     DG74  DDR7_SA_DQ11  SOCKET4677_AZIFS054P001C01  I169

M_H_CPU0_SA_DQ<12>   @S9S_MB_2U_LIB.S9S_MB_2U(SCH_1):M_H_CPU0_SA_DQ<12>
  J15     25  DQ_A12  SCONN288_ADR50001P013C01  I48
  J16     25  DQ_A12  SCONN288_ADR50001P003C01   I6
  U2     DC72  DDR7_SA_DQ12  SOCKET4677_AZIFS054P001C01  I169

M_H_CPU0_SA_DQ<13>   @S9S_MB_2U_LIB.S9S_MB_2U(SCH_1):M_H_CPU0_SA_DQ<13>
  J15     27  DQ_A13  SCONN288_ADR50001P013C01  I48
  J16     27  DQ_A13  SCONN288_ADR50001P003C01   I6
  U2     DD71  DDR7_SA_DQ13  SOCKET4677_AZIFS054P001C01  I169

M_H_CPU0_SA_DQ<14>   @S9S_MB_2U_LIB.S9S_MB_2U(SCH_1):M_H_CPU0_SA_DQ<14>
  J15    170  DQ_A14  SCONN288_ADR50001P013C01  I48
  J16    170  DQ_A14  SCONN288_ADR50001P003C01   I6
  U2     DG72  DDR7_SA_DQ14  SOCKET4677_AZIFS054P001C01  I169

M_H_CPU0_SA_DQ<15>   @S9S_MB_2U_LIB.S9S_MB_2U(SCH_1):M_H_CPU0_SA_DQ<15>
  J15    172  DQ_A15  SCONN288_ADR50001P013C01  I48
  J16    172  DQ_A15  SCONN288_ADR50001P003C01   I6
  U2     DF71  DDR7_SA_DQ15  SOCKET4677_AZIFS054P001C01  I169

M_H_CPU0_SA_DQ<16>   @S9S_MB_2U_LIB.S9S_MB_2U(SCH_1):M_H_CPU0_SA_DQ<16>
  J15     29  DQ_A16  SCONN288_ADR50001P013C01  I48
  J16     29  DQ_A16  SCONN288_ADR50001P003C01   I6
  U2     DD69  DDR7_SA_DQ16  SOCKET4677_AZIFS054P001C01  I169

M_H_CPU0_SA_DQ<17>   @S9S_MB_2U_LIB.S9S_MB_2U(SCH_1):M_H_CPU0_SA_DQ<17>
  J15     31  DQ_A17  SCONN288_ADR50001P013C01  I48
  J16     31  DQ_A17  SCONN288_ADR50001P003C01   I6
  U2     DC68  DDR7_SA_DQ17  SOCKET4677_AZIFS054P001C01  I169

M_H_CPU0_SA_DQ<18>   @S9S_MB_2U_LIB.S9S_MB_2U(SCH_1):M_H_CPU0_SA_DQ<18>
  J15    174  DQ_A18  SCONN288_ADR50001P013C01  I48
  J16    174  DQ_A18  SCONN288_ADR50001P003C01   I6
  U2     DF69  DDR7_SA_DQ18  SOCKET4677_AZIFS054P001C01  I169

M_H_CPU0_SA_DQ<19>   @S9S_MB_2U_LIB.S9S_MB_2U(SCH_1):M_H_CPU0_SA_DQ<19>
  J15    176  DQ_A19  SCONN288_ADR50001P013C01  I48
  J16    176  DQ_A19  SCONN288_ADR50001P003C01   I6
  U2     DG68  DDR7_SA_DQ19  SOCKET4677_AZIFS054P001C01  I169

M_H_CPU0_SA_DQ<20>   @S9S_MB_2U_LIB.S9S_MB_2U(SCH_1):M_H_CPU0_SA_DQ<20>
  J15     36  DQ_A20  SCONN288_ADR50001P013C01  I48
  J16     36  DQ_A20  SCONN288_ADR50001P003C01   I6
  U2     DC66  DDR7_SA_DQ20  SOCKET4677_AZIFS054P001C01  I169

M_H_CPU0_SA_DQ<21>   @S9S_MB_2U_LIB.S9S_MB_2U(SCH_1):M_H_CPU0_SA_DQ<21>
  J15     38  DQ_A21  SCONN288_ADR50001P013C01  I48
  J16     38  DQ_A21  SCONN288_ADR50001P003C01   I6
  U2     DD65  DDR7_SA_DQ21  SOCKET4677_AZIFS054P001C01  I169

M_H_CPU0_SA_DQ<22>   @S9S_MB_2U_LIB.S9S_MB_2U(SCH_1):M_H_CPU0_SA_DQ<22>
  J15    181  DQ_A22  SCONN288_ADR50001P013C01  I48
  J16    181  DQ_A22  SCONN288_ADR50001P003C01   I6
  U2     DG66  DDR7_SA_DQ22  SOCKET4677_AZIFS054P001C01  I169

M_H_CPU0_SA_DQ<23>   @S9S_MB_2U_LIB.S9S_MB_2U(SCH_1):M_H_CPU0_SA_DQ<23>
  J15    183  DQ_A23  SCONN288_ADR50001P013C01  I48
  J16    183  DQ_A23  SCONN288_ADR50001P003C01   I6
  U2     DF65  DDR7_SA_DQ23  SOCKET4677_AZIFS054P001C01  I169

M_H_CPU0_SA_DQ<24>   @S9S_MB_2U_LIB.S9S_MB_2U(SCH_1):M_H_CPU0_SA_DQ<24>
  J15     40  DQ_A24  SCONN288_ADR50001P013C01  I48
  J16     40  DQ_A24  SCONN288_ADR50001P003C01   I6
  U2     DD63  DDR7_SA_DQ24  SOCKET4677_AZIFS054P001C01  I169

M_H_CPU0_SA_DQ<25>   @S9S_MB_2U_LIB.S9S_MB_2U(SCH_1):M_H_CPU0_SA_DQ<25>
  J15     42  DQ_A25  SCONN288_ADR50001P013C01  I48
  J16     42  DQ_A25  SCONN288_ADR50001P003C01   I6
  U2     DC62  DDR7_SA_DQ25  SOCKET4677_AZIFS054P001C01  I169

M_H_CPU0_SA_DQ<26>   @S9S_MB_2U_LIB.S9S_MB_2U(SCH_1):M_H_CPU0_SA_DQ<26>
  J15    185  DQ_A26  SCONN288_ADR50001P013C01  I48
  J16    185  DQ_A26  SCONN288_ADR50001P003C01   I6
  U2     DF63  DDR7_SA_DQ26  SOCKET4677_AZIFS054P001C01  I169

M_H_CPU0_SA_DQ<27>   @S9S_MB_2U_LIB.S9S_MB_2U(SCH_1):M_H_CPU0_SA_DQ<27>
  J15    187  DQ_A27  SCONN288_ADR50001P013C01  I48
  J16    187  DQ_A27  SCONN288_ADR50001P003C01   I6
  U2     DG62  DDR7_SA_DQ27  SOCKET4677_AZIFS054P001C01  I169

M_H_CPU0_SA_DQ<28>   @S9S_MB_2U_LIB.S9S_MB_2U(SCH_1):M_H_CPU0_SA_DQ<28>
  J15     47  DQ_A28  SCONN288_ADR50001P013C01  I48
  J16     47  DQ_A28  SCONN288_ADR50001P003C01   I6
  U2     DC60  DDR7_SA_DQ28  SOCKET4677_AZIFS054P001C01  I169

M_H_CPU0_SA_DQ<29>   @S9S_MB_2U_LIB.S9S_MB_2U(SCH_1):M_H_CPU0_SA_DQ<29>
  J15     49  DQ_A29  SCONN288_ADR50001P013C01  I48
  J16     49  DQ_A29  SCONN288_ADR50001P003C01   I6
  U2     DD59  DDR7_SA_DQ29  SOCKET4677_AZIFS054P001C01  I169

M_H_CPU0_SA_DQ<30>   @S9S_MB_2U_LIB.S9S_MB_2U(SCH_1):M_H_CPU0_SA_DQ<30>
  J15    192  DQ_A30  SCONN288_ADR50001P013C01  I48
  J16    192  DQ_A30  SCONN288_ADR50001P003C01   I6
  U2     DG60  DDR7_SA_DQ30  SOCKET4677_AZIFS054P001C01  I169

M_H_CPU0_SA_DQ<31>   @S9S_MB_2U_LIB.S9S_MB_2U(SCH_1):M_H_CPU0_SA_DQ<31>
  J15    194  DQ_A31  SCONN288_ADR50001P013C01  I48
  J16    194  DQ_A31  SCONN288_ADR50001P003C01   I6
  U2     DF59  DDR7_SA_DQ31  SOCKET4677_AZIFS054P001C01  I169

M_H_CPU0_SA_DQS_DN<0>   @S9S_MB_2U_LIB.S9S_MB_2U(SCH_1):M_H_CPU0_SA_DQS_DN<0>
  J15     12  DQS0_A_N  SCONN288_ADR50001P013C01  I124
  J16     12  DQS0_A_N  SCONN288_ADR50001P003C01  I132
  U2     DJ76  DDR7_SA_DQS_DN0  SOCKET4677_AZIFS054P001C01  I169

M_H_CPU0_SA_DQS_DN<1>   @S9S_MB_2U_LIB.S9S_MB_2U(SCH_1):M_H_CPU0_SA_DQS_DN<1>
  J15     23  DQS1_A_N  SCONN288_ADR50001P013C01  I124
  J16     23  DQS1_A_N  SCONN288_ADR50001P003C01  I132
  U2     DB73  DDR7_SA_DQS_DN1  SOCKET4677_AZIFS054P001C01  I169

M_H_CPU0_SA_DQS_DN<2>   @S9S_MB_2U_LIB.S9S_MB_2U(SCH_1):M_H_CPU0_SA_DQS_DN<2>
  J15     34  DQS2_A_N  SCONN288_ADR50001P013C01  I124
  J16     34  DQS2_A_N  SCONN288_ADR50001P003C01  I132
  U2     DD67  DDR7_SA_DQS_DN2  SOCKET4677_AZIFS054P001C01  I169

M_H_CPU0_SA_DQS_DN<3>   @S9S_MB_2U_LIB.S9S_MB_2U(SCH_1):M_H_CPU0_SA_DQS_DN<3>
  J15     45  DQS3_A_N  SCONN288_ADR50001P013C01  I124
  J16     45  DQS3_A_N  SCONN288_ADR50001P003C01  I132
  U2     DD61  DDR7_SA_DQS_DN3  SOCKET4677_AZIFS054P001C01  I169

M_H_CPU0_SA_DQS_DN<4>   @S9S_MB_2U_LIB.S9S_MB_2U(SCH_1):M_H_CPU0_SA_DQS_DN<4>
  J15     56  DQS4_A_N  SCONN288_ADR50001P013C01  I124
  J16     56  DQS4_A_N  SCONN288_ADR50001P003C01  I132
  U2     DD55  DDR7_SA_DQS_DN4  SOCKET4677_AZIFS054P001C01  I169

M_H_CPU0_SA_DQS_DN<5>   @S9S_MB_2U_LIB.S9S_MB_2U(SCH_1):M_H_CPU0_SA_DQS_DN<5>
  J15    156  DQS5_A_N  SCONN288_ADR50001P013C01  I124
  J16    156  DQS5_A_N  SCONN288_ADR50001P003C01  I132
  U2     DR76  DDR7_SA_DQS_DN5  SOCKET4677_AZIFS054P001C01  I169

M_H_CPU0_SA_DQS_DN<6>   @S9S_MB_2U_LIB.S9S_MB_2U(SCH_1):M_H_CPU0_SA_DQS_DN<6>
  J15    167  DQS6_A_N  SCONN288_ADR50001P013C01  I124
  J16    167  DQS6_A_N  SCONN288_ADR50001P003C01  I132
  U2     DH73  DDR7_SA_DQS_DN6  SOCKET4677_AZIFS054P001C01  I169

M_H_CPU0_SA_DQS_DN<7>   @S9S_MB_2U_LIB.S9S_MB_2U(SCH_1):M_H_CPU0_SA_DQS_DN<7>
  J15    178  DQS7_A_N  SCONN288_ADR50001P013C01  I124
  J16    178  DQS7_A_N  SCONN288_ADR50001P003C01  I132
  U2     DH67  DDR7_SA_DQS_DN7  SOCKET4677_AZIFS054P001C01  I169

M_H_CPU0_SA_DQS_DN<8>   @S9S_MB_2U_LIB.S9S_MB_2U(SCH_1):M_H_CPU0_SA_DQS_DN<8>
  J15    189  DQS8_A_N  SCONN288_ADR50001P013C01  I124
  J16    189  DQS8_A_N  SCONN288_ADR50001P003C01  I132
  U2     DH61  DDR7_SA_DQS_DN8  SOCKET4677_AZIFS054P001C01  I169

M_H_CPU0_SA_DQS_DN<9>   @S9S_MB_2U_LIB.S9S_MB_2U(SCH_1):M_H_CPU0_SA_DQS_DN<9>
  J15    200  DQS9_A_N  SCONN288_ADR50001P013C01  I124
  J16    200  DQS9_A_N  SCONN288_ADR50001P003C01  I132
  U2     DH55  DDR7_SA_DQS_DN9  SOCKET4677_AZIFS054P001C01  I169

M_H_CPU0_SA_DQS_DP<0>   @S9S_MB_2U_LIB.S9S_MB_2U(SCH_1):M_H_CPU0_SA_DQS_DP<0>
  J15     11  DQS0_A_P  SCONN288_ADR50001P013C01  I124
  J16     11  DQS0_A_P  SCONN288_ADR50001P003C01  I132
  U2     DL76  DDR7_SA_DQS_DP0  SOCKET4677_AZIFS054P001C01  I169

M_H_CPU0_SA_DQS_DP<1>   @S9S_MB_2U_LIB.S9S_MB_2U(SCH_1):M_H_CPU0_SA_DQS_DP<1>
  J15     22  DQS1_A_P  SCONN288_ADR50001P013C01  I124
  J16     22  DQS1_A_P  SCONN288_ADR50001P003C01  I132
  U2     DD73  DDR7_SA_DQS_DP1  SOCKET4677_AZIFS054P001C01  I169

M_H_CPU0_SA_DQS_DP<2>   @S9S_MB_2U_LIB.S9S_MB_2U(SCH_1):M_H_CPU0_SA_DQS_DP<2>
  J15     33  DQS2_A_P  SCONN288_ADR50001P013C01  I124
  J16     33  DQS2_A_P  SCONN288_ADR50001P003C01  I132
  U2     DB67  DDR7_SA_DQS_DP2  SOCKET4677_AZIFS054P001C01  I169

M_H_CPU0_SA_DQS_DP<3>   @S9S_MB_2U_LIB.S9S_MB_2U(SCH_1):M_H_CPU0_SA_DQS_DP<3>
  J15     44  DQS3_A_P  SCONN288_ADR50001P013C01  I124
  J16     44  DQS3_A_P  SCONN288_ADR50001P003C01  I132
  U2     DB61  DDR7_SA_DQS_DP3  SOCKET4677_AZIFS054P001C01  I169

M_H_CPU0_SA_DQS_DP<4>   @S9S_MB_2U_LIB.S9S_MB_2U(SCH_1):M_H_CPU0_SA_DQS_DP<4>
  J15     55  DQS4_A_P  SCONN288_ADR50001P013C01  I124
  J16     55  DQS4_A_P  SCONN288_ADR50001P003C01  I132
  U2     DB55  DDR7_SA_DQS_DP4  SOCKET4677_AZIFS054P001C01  I169

M_H_CPU0_SA_DQS_DP<5>   @S9S_MB_2U_LIB.S9S_MB_2U(SCH_1):M_H_CPU0_SA_DQS_DP<5>
  J15    157  DQS5_A_P  SCONN288_ADR50001P013C01  I124
  J16    157  DQS5_A_P  SCONN288_ADR50001P003C01  I132
  U2     DN76  DDR7_SA_DQS_DP5  SOCKET4677_AZIFS054P001C01  I169

M_H_CPU0_SA_DQS_DP<6>   @S9S_MB_2U_LIB.S9S_MB_2U(SCH_1):M_H_CPU0_SA_DQS_DP<6>
  J15    168  DQS6_A_P  SCONN288_ADR50001P013C01  I124
  J16    168  DQS6_A_P  SCONN288_ADR50001P003C01  I132
  U2     DF73  DDR7_SA_DQS_DP6  SOCKET4677_AZIFS054P001C01  I169

M_H_CPU0_SA_DQS_DP<7>   @S9S_MB_2U_LIB.S9S_MB_2U(SCH_1):M_H_CPU0_SA_DQS_DP<7>
  J15    179  DQS7_A_P  SCONN288_ADR50001P013C01  I124
  J16    179  DQS7_A_P  SCONN288_ADR50001P003C01  I132
  U2     DF67  DDR7_SA_DQS_DP7  SOCKET4677_AZIFS054P001C01  I169

M_H_CPU0_SA_DQS_DP<8>   @S9S_MB_2U_LIB.S9S_MB_2U(SCH_1):M_H_CPU0_SA_DQS_DP<8>
  J15    190  DQS8_A_P  SCONN288_ADR50001P013C01  I124
  J16    190  DQS8_A_P  SCONN288_ADR50001P003C01  I132
  U2     DF61  DDR7_SA_DQS_DP8  SOCKET4677_AZIFS054P001C01  I169

M_H_CPU0_SA_DQS_DP<9>   @S9S_MB_2U_LIB.S9S_MB_2U(SCH_1):M_H_CPU0_SA_DQS_DP<9>
  J15    201  DQS9_A_P  SCONN288_ADR50001P013C01  I124
  J16    201  DQS9_A_P  SCONN288_ADR50001P003C01  I132
  U2     DF55  DDR7_SA_DQS_DP9  SOCKET4677_AZIFS054P001C01  I169

M_H_CPU0_SA_PAR   @S9S_MB_2U_LIB.S9S_MB_2U(SCH_1):M_H_CPU0_SA_PAR
  J15     74  PAR_A  SCONN288_ADR50001P013C01  I48
  J16     74  PAR_A  SCONN288_ADR50001P003C01   I6
  U2     DD40  DDR7_SA_PAR  SOCKET4677_AZIFS054P001C01  I169

M_H_CPU0_SA_RSP<0>   @S9S_MB_2U_LIB.S9S_MB_2U(SCH_1):M_H_CPU0_SA_RSP<0>
  J15     86  LBD||RSP_N_A  SCONN288_ADR50001P013C01  I48
  U2     EG48  DDR7_A_RSP0  SOCKET4677_AZIFS054P001C01  I169

M_H_CPU0_SA_RSP<1>   @S9S_MB_2U_LIB.S9S_MB_2U(SCH_1):M_H_CPU0_SA_RSP<1>
  J16     86  LBD||RSP_N_A  SCONN288_ADR50001P003C01   I6
  U2     EH47  DDR7_A_RSP1  SOCKET4677_AZIFS054P001C01  I169

M_H_CPU0_SB_CA<0>   @S9S_MB_2U_LIB.S9S_MB_2U(SCH_1):M_H_CPU0_SB_CA<0>
  J15     76  CA0_B  SCONN288_ADR50001P013C01  I48
  J16     76  CA0_B  SCONN288_ADR50001P003C01   I6
  U2     DF40  DDR7_SB_CA0  SOCKET4677_AZIFS054P001C01  I169

M_H_CPU0_SB_CA<1>   @S9S_MB_2U_LIB.S9S_MB_2U(SCH_1):M_H_CPU0_SB_CA<1>
  J15    221  CA1_B  SCONN288_ADR50001P013C01  I48
  J16    221  CA1_B  SCONN288_ADR50001P003C01   I6
  U2     DG41  DDR7_SB_CA1  SOCKET4677_AZIFS054P001C01  I169

M_H_CPU0_SB_CA<2>   @S9S_MB_2U_LIB.S9S_MB_2U(SCH_1):M_H_CPU0_SB_CA<2>
  J15     78  CA2_B  SCONN288_ADR50001P013C01  I48
  J16     78  CA2_B  SCONN288_ADR50001P003C01   I6
  U2     DL41  DDR7_SB_CA2  SOCKET4677_AZIFS054P001C01  I169

M_H_CPU0_SB_CA<3>   @S9S_MB_2U_LIB.S9S_MB_2U(SCH_1):M_H_CPU0_SB_CA<3>
  J15    223  CA3_B  SCONN288_ADR50001P013C01  I48
  J16    223  CA3_B  SCONN288_ADR50001P003C01   I6
  U2     DN41  DDR7_SB_CA3  SOCKET4677_AZIFS054P001C01  I169

M_H_CPU0_SB_CA<4>   @S9S_MB_2U_LIB.S9S_MB_2U(SCH_1):M_H_CPU0_SB_CA<4>
  J15     80  CA4_B  SCONN288_ADR50001P013C01  I48
  J16     80  CA4_B  SCONN288_ADR50001P003C01   I6
  U2     DK40  DDR7_SB_CA4  SOCKET4677_AZIFS054P001C01  I169

M_H_CPU0_SB_CA<5>   @S9S_MB_2U_LIB.S9S_MB_2U(SCH_1):M_H_CPU0_SB_CA<5>
  J15    225  CA5_B  SCONN288_ADR50001P013C01  I48
  J16    225  CA5_B  SCONN288_ADR50001P003C01   I6
  U2     DP40  DDR7_SB_CA5  SOCKET4677_AZIFS054P001C01  I169

M_H_CPU0_SB_CA<6>   @S9S_MB_2U_LIB.S9S_MB_2U(SCH_1):M_H_CPU0_SB_CA<6>
  J15     82  CA6_B  SCONN288_ADR50001P013C01  I48
  J16     82  CA6_B  SCONN288_ADR50001P003C01   I6
  U2     DJ39  DDR7_SB_CA6  SOCKET4677_AZIFS054P001C01  I169

M_H_CPU0_SB_CB<0>   @S9S_MB_2U_LIB.S9S_MB_2U(SCH_1):M_H_CPU0_SB_CB<0>
  J15     96  CB_B0  SCONN288_ADR50001P013C01  I48
  J16     96  CB_B0  SCONN288_ADR50001P003C01   I6
  U2     DC35  DDR7_SB_ECC0  SOCKET4677_AZIFS054P001C01  I169

M_H_CPU0_SB_CB<1>   @S9S_MB_2U_LIB.S9S_MB_2U(SCH_1):M_H_CPU0_SB_CB<1>
  J15     98  CB_B1  SCONN288_ADR50001P013C01  I48
  J16     98  CB_B1  SCONN288_ADR50001P003C01   I6
  U2     DD34  DDR7_SB_ECC1  SOCKET4677_AZIFS054P001C01  I169

M_H_CPU0_SB_CB<2>   @S9S_MB_2U_LIB.S9S_MB_2U(SCH_1):M_H_CPU0_SB_CB<2>
  J15    241  CB_B2  SCONN288_ADR50001P013C01  I48
  J16    241  CB_B2  SCONN288_ADR50001P003C01   I6
  U2     DG35  DDR7_SB_ECC2  SOCKET4677_AZIFS054P001C01  I169

M_H_CPU0_SB_CB<3>   @S9S_MB_2U_LIB.S9S_MB_2U(SCH_1):M_H_CPU0_SB_CB<3>
  J15    243  CB_B3  SCONN288_ADR50001P013C01  I48
  J16    243  CB_B3  SCONN288_ADR50001P003C01   I6
  U2     DF34  DDR7_SB_ECC3  SOCKET4677_AZIFS054P001C01  I169

M_H_CPU0_SB_CB<4>   @S9S_MB_2U_LIB.S9S_MB_2U(SCH_1):M_H_CPU0_SB_CB<4>
  J15     89  CB_B4  SCONN288_ADR50001P013C01  I48
  J16     89  CB_B4  SCONN288_ADR50001P003C01   I6
  U2     DF38  DDR7_SB_ECC4  SOCKET4677_AZIFS054P001C01  I169

M_H_CPU0_SB_CB<5>   @S9S_MB_2U_LIB.S9S_MB_2U(SCH_1):M_H_CPU0_SB_CB<5>
  J15     91  CB_B5  SCONN288_ADR50001P013C01  I48
  J16     91  CB_B5  SCONN288_ADR50001P003C01   I6
  U2     DG37  DDR7_SB_ECC5  SOCKET4677_AZIFS054P001C01  I169

M_H_CPU0_SB_CB<6>   @S9S_MB_2U_LIB.S9S_MB_2U(SCH_1):M_H_CPU0_SB_CB<6>
  J15    234  CB_B6  SCONN288_ADR50001P013C01  I48
  J16    234  CB_B6  SCONN288_ADR50001P003C01   I6
  U2     DD38  DDR7_SB_ECC6  SOCKET4677_AZIFS054P001C01  I169

M_H_CPU0_SB_CB<7>   @S9S_MB_2U_LIB.S9S_MB_2U(SCH_1):M_H_CPU0_SB_CB<7>
  J15    236  CB_B7  SCONN288_ADR50001P013C01  I48
  J16    236  CB_B7  SCONN288_ADR50001P003C01   I6
  U2     DC37  DDR7_SB_ECC7  SOCKET4677_AZIFS054P001C01  I169

M_H_CPU0_SB_CS_N<0>   @S9S_MB_2U_LIB.S9S_MB_2U(SCH_1):M_H_CPU0_SB_CS_N<0>
  J15     84  CS0_N_B  SCONN288_ADR50001P013C01  I48
  U2     DL37  DDR7_SB_CS0_N  SOCKET4677_AZIFS054P001C01  I169

M_H_CPU0_SB_CS_N<1>   @S9S_MB_2U_LIB.S9S_MB_2U(SCH_1):M_H_CPU0_SB_CS_N<1>
  J15    229  CS1_N_B  SCONN288_ADR50001P013C01  I48
  U2     DN37  DDR7_SB_CS1_N  SOCKET4677_AZIFS054P001C01  I169

M_H_CPU0_SB_CS_N<2>   @S9S_MB_2U_LIB.S9S_MB_2U(SCH_1):M_H_CPU0_SB_CS_N<2>
  J16     84  CS0_N_B  SCONN288_ADR50001P003C01   I6
  U2     DK38  DDR7_SB_CS2_N  SOCKET4677_AZIFS054P001C01  I169

M_H_CPU0_SB_CS_N<3>   @S9S_MB_2U_LIB.S9S_MB_2U(SCH_1):M_H_CPU0_SB_CS_N<3>
  J16    229  CS1_N_B  SCONN288_ADR50001P003C01   I6
  U2     DP38  DDR7_SB_CS3_N  SOCKET4677_AZIFS054P001C01  I169

M_H_CPU0_SB_DQ<0>   @S9S_MB_2U_LIB.S9S_MB_2U(SCH_1):M_H_CPU0_SB_DQ<0>
  J15    100  DQ_B0  SCONN288_ADR50001P013C01  I48
  J16    100  DQ_B0  SCONN288_ADR50001P003C01   I6
  U2     DD32  DDR7_SB_DQ0  SOCKET4677_AZIFS054P001C01  I169

M_H_CPU0_SB_DQ<1>   @S9S_MB_2U_LIB.S9S_MB_2U(SCH_1):M_H_CPU0_SB_DQ<1>
  J15    102  DQ_B1  SCONN288_ADR50001P013C01  I48
  J16    102  DQ_B1  SCONN288_ADR50001P003C01   I6
  U2     DC31  DDR7_SB_DQ1  SOCKET4677_AZIFS054P001C01  I169

M_H_CPU0_SB_DQ<2>   @S9S_MB_2U_LIB.S9S_MB_2U(SCH_1):M_H_CPU0_SB_DQ<2>
  J15    245  DQ_B2  SCONN288_ADR50001P013C01  I48
  J16    245  DQ_B2  SCONN288_ADR50001P003C01   I6
  U2     DF32  DDR7_SB_DQ2  SOCKET4677_AZIFS054P001C01  I169

M_H_CPU0_SB_DQ<3>   @S9S_MB_2U_LIB.S9S_MB_2U(SCH_1):M_H_CPU0_SB_DQ<3>
  J15    247  DQ_B3  SCONN288_ADR50001P013C01  I48
  J16    247  DQ_B3  SCONN288_ADR50001P003C01   I6
  U2     DG31  DDR7_SB_DQ3  SOCKET4677_AZIFS054P001C01  I169

M_H_CPU0_SB_DQ<4>   @S9S_MB_2U_LIB.S9S_MB_2U(SCH_1):M_H_CPU0_SB_DQ<4>
  J15    107  DQ_B4  SCONN288_ADR50001P013C01  I48
  J16    107  DQ_B4  SCONN288_ADR50001P003C01   I6
  U2     DC29  DDR7_SB_DQ4  SOCKET4677_AZIFS054P001C01  I169

M_H_CPU0_SB_DQ<5>   @S9S_MB_2U_LIB.S9S_MB_2U(SCH_1):M_H_CPU0_SB_DQ<5>
  J15    109  DQ_B5  SCONN288_ADR50001P013C01  I48
  J16    109  DQ_B5  SCONN288_ADR50001P003C01   I6
  U2     DF28  DDR7_SB_DQ5  SOCKET4677_AZIFS054P001C01  I169

M_H_CPU0_SB_DQ<6>   @S9S_MB_2U_LIB.S9S_MB_2U(SCH_1):M_H_CPU0_SB_DQ<6>
  J15    252  DQ_B6  SCONN288_ADR50001P013C01  I48
  J16    252  DQ_B6  SCONN288_ADR50001P003C01   I6
  U2     DG29  DDR7_SB_DQ6  SOCKET4677_AZIFS054P001C01  I169

M_H_CPU0_SB_DQ<7>   @S9S_MB_2U_LIB.S9S_MB_2U(SCH_1):M_H_CPU0_SB_DQ<7>
  J15    254  DQ_B7  SCONN288_ADR50001P013C01  I48
  J16    254  DQ_B7  SCONN288_ADR50001P003C01   I6
  U2     DD28  DDR7_SB_DQ7  SOCKET4677_AZIFS054P001C01  I169

M_H_CPU0_SB_DQ<8>   @S9S_MB_2U_LIB.S9S_MB_2U(SCH_1):M_H_CPU0_SB_DQ<8>
  J15    111  DQ_B8  SCONN288_ADR50001P013C01  I48
  J16    111  DQ_B8  SCONN288_ADR50001P003C01   I6
  U2     DD26  DDR7_SB_DQ8  SOCKET4677_AZIFS054P001C01  I169

M_H_CPU0_SB_DQ<9>   @S9S_MB_2U_LIB.S9S_MB_2U(SCH_1):M_H_CPU0_SB_DQ<9>
  J15    113  DQ_B9  SCONN288_ADR50001P013C01  I48
  J16    113  DQ_B9  SCONN288_ADR50001P003C01   I6
  U2     DC25  DDR7_SB_DQ9  SOCKET4677_AZIFS054P001C01  I169

M_H_CPU0_SB_DQ<10>   @S9S_MB_2U_LIB.S9S_MB_2U(SCH_1):M_H_CPU0_SB_DQ<10>
  J15    256  DQ_B10  SCONN288_ADR50001P013C01  I48
  J16    256  DQ_B10  SCONN288_ADR50001P003C01   I6
  U2     DF26  DDR7_SB_DQ10  SOCKET4677_AZIFS054P001C01  I169

M_H_CPU0_SB_DQ<11>   @S9S_MB_2U_LIB.S9S_MB_2U(SCH_1):M_H_CPU0_SB_DQ<11>
  J15    258  DQ_B11  SCONN288_ADR50001P013C01  I48
  J16    258  DQ_B11  SCONN288_ADR50001P003C01   I6
  U2     DG25  DDR7_SB_DQ11  SOCKET4677_AZIFS054P001C01  I169

M_H_CPU0_SB_DQ<12>   @S9S_MB_2U_LIB.S9S_MB_2U(SCH_1):M_H_CPU0_SB_DQ<12>
  J15    118  DQ_B12  SCONN288_ADR50001P013C01  I48
  J16    118  DQ_B12  SCONN288_ADR50001P003C01   I6
  U2     DC23  DDR7_SB_DQ12  SOCKET4677_AZIFS054P001C01  I169

M_H_CPU0_SB_DQ<13>   @S9S_MB_2U_LIB.S9S_MB_2U(SCH_1):M_H_CPU0_SB_DQ<13>
  J15    120  DQ_B13  SCONN288_ADR50001P013C01  I48
  J16    120  DQ_B13  SCONN288_ADR50001P003C01   I6
  U2     DD22  DDR7_SB_DQ13  SOCKET4677_AZIFS054P001C01  I169

M_H_CPU0_SB_DQ<14>   @S9S_MB_2U_LIB.S9S_MB_2U(SCH_1):M_H_CPU0_SB_DQ<14>
  J15    263  DQ_B14  SCONN288_ADR50001P013C01  I48
  J16    263  DQ_B14  SCONN288_ADR50001P003C01   I6
  U2     DG23  DDR7_SB_DQ14  SOCKET4677_AZIFS054P001C01  I169

M_H_CPU0_SB_DQ<15>   @S9S_MB_2U_LIB.S9S_MB_2U(SCH_1):M_H_CPU0_SB_DQ<15>
  J15    265  DQ_B15  SCONN288_ADR50001P013C01  I48
  J16    265  DQ_B15  SCONN288_ADR50001P003C01   I6
  U2     DF22  DDR7_SB_DQ15  SOCKET4677_AZIFS054P001C01  I169

M_H_CPU0_SB_DQ<16>   @S9S_MB_2U_LIB.S9S_MB_2U(SCH_1):M_H_CPU0_SB_DQ<16>
  J15    122  DQ_B16  SCONN288_ADR50001P013C01  I48
  J16    122  DQ_B16  SCONN288_ADR50001P003C01   I6
  U2     DL23  DDR7_SB_DQ16  SOCKET4677_AZIFS054P001C01  I169

M_H_CPU0_SB_DQ<17>   @S9S_MB_2U_LIB.S9S_MB_2U(SCH_1):M_H_CPU0_SB_DQ<17>
  J15    124  DQ_B17  SCONN288_ADR50001P013C01  I48
  J16    124  DQ_B17  SCONN288_ADR50001P003C01   I6
  U2     DK22  DDR7_SB_DQ17  SOCKET4677_AZIFS054P001C01  I169

M_H_CPU0_SB_DQ<18>   @S9S_MB_2U_LIB.S9S_MB_2U(SCH_1):M_H_CPU0_SB_DQ<18>
  J15    267  DQ_B18  SCONN288_ADR50001P013C01  I48
  J16    267  DQ_B18  SCONN288_ADR50001P003C01   I6
  U2     DN23  DDR7_SB_DQ18  SOCKET4677_AZIFS054P001C01  I169

M_H_CPU0_SB_DQ<19>   @S9S_MB_2U_LIB.S9S_MB_2U(SCH_1):M_H_CPU0_SB_DQ<19>
  J15    269  DQ_B19  SCONN288_ADR50001P013C01  I48
  J16    269  DQ_B19  SCONN288_ADR50001P003C01   I6
  U2     DP22  DDR7_SB_DQ19  SOCKET4677_AZIFS054P001C01  I169

M_H_CPU0_SB_DQ<20>   @S9S_MB_2U_LIB.S9S_MB_2U(SCH_1):M_H_CPU0_SB_DQ<20>
  J15    129  DQ_B20  SCONN288_ADR50001P013C01  I48
  J16    129  DQ_B20  SCONN288_ADR50001P003C01   I6
  U2     DK20  DDR7_SB_DQ20  SOCKET4677_AZIFS054P001C01  I169

M_H_CPU0_SB_DQ<21>   @S9S_MB_2U_LIB.S9S_MB_2U(SCH_1):M_H_CPU0_SB_DQ<21>
  J15    131  DQ_B21  SCONN288_ADR50001P013C01  I48
  J16    131  DQ_B21  SCONN288_ADR50001P003C01   I6
  U2     DL19  DDR7_SB_DQ21  SOCKET4677_AZIFS054P001C01  I169

M_H_CPU0_SB_DQ<22>   @S9S_MB_2U_LIB.S9S_MB_2U(SCH_1):M_H_CPU0_SB_DQ<22>
  J15    274  DQ_B22  SCONN288_ADR50001P013C01  I48
  J16    274  DQ_B22  SCONN288_ADR50001P003C01   I6
  U2     DP20  DDR7_SB_DQ22  SOCKET4677_AZIFS054P001C01  I169

M_H_CPU0_SB_DQ<23>   @S9S_MB_2U_LIB.S9S_MB_2U(SCH_1):M_H_CPU0_SB_DQ<23>
  J15    276  DQ_B23  SCONN288_ADR50001P013C01  I48
  J16    276  DQ_B23  SCONN288_ADR50001P003C01   I6
  U2     DN19  DDR7_SB_DQ23  SOCKET4677_AZIFS054P001C01  I169

M_H_CPU0_SB_DQ<24>   @S9S_MB_2U_LIB.S9S_MB_2U(SCH_1):M_H_CPU0_SB_DQ<24>
  J15    133  DQ_B24  SCONN288_ADR50001P013C01  I48
  J16    133  DQ_B24  SCONN288_ADR50001P003C01   I6
  U2     DD20  DDR7_SB_DQ24  SOCKET4677_AZIFS054P001C01  I169

M_H_CPU0_SB_DQ<25>   @S9S_MB_2U_LIB.S9S_MB_2U(SCH_1):M_H_CPU0_SB_DQ<25>
  J15    135  DQ_B25  SCONN288_ADR50001P013C01  I48
  J16    135  DQ_B25  SCONN288_ADR50001P003C01   I6
  U2     DC19  DDR7_SB_DQ25  SOCKET4677_AZIFS054P001C01  I169

M_H_CPU0_SB_DQ<26>   @S9S_MB_2U_LIB.S9S_MB_2U(SCH_1):M_H_CPU0_SB_DQ<26>
  J15    278  DQ_B26  SCONN288_ADR50001P013C01  I48
  J16    278  DQ_B26  SCONN288_ADR50001P003C01   I6
  U2     DF20  DDR7_SB_DQ26  SOCKET4677_AZIFS054P001C01  I169

M_H_CPU0_SB_DQ<27>   @S9S_MB_2U_LIB.S9S_MB_2U(SCH_1):M_H_CPU0_SB_DQ<27>
  J15    280  DQ_B27  SCONN288_ADR50001P013C01  I48
  J16    280  DQ_B27  SCONN288_ADR50001P003C01   I6
  U2     DG19  DDR7_SB_DQ27  SOCKET4677_AZIFS054P001C01  I169

M_H_CPU0_SB_DQ<28>   @S9S_MB_2U_LIB.S9S_MB_2U(SCH_1):M_H_CPU0_SB_DQ<28>
  J15    140  DQ_B28  SCONN288_ADR50001P013C01  I48
  J16    140  DQ_B28  SCONN288_ADR50001P003C01   I6
  U2     DG17  DDR7_SB_DQ28  SOCKET4677_AZIFS054P001C01  I169

M_H_CPU0_SB_DQ<29>   @S9S_MB_2U_LIB.S9S_MB_2U(SCH_1):M_H_CPU0_SB_DQ<29>
  J15    142  DQ_B29  SCONN288_ADR50001P013C01  I48
  J16    142  DQ_B29  SCONN288_ADR50001P003C01   I6
  U2     DA17  DDR7_SB_DQ29  SOCKET4677_AZIFS054P001C01  I169

M_H_CPU0_SB_DQ<30>   @S9S_MB_2U_LIB.S9S_MB_2U(SCH_1):M_H_CPU0_SB_DQ<30>
  J15    285  DQ_B30  SCONN288_ADR50001P013C01  I48
  J16    285  DQ_B30  SCONN288_ADR50001P003C01   I6
  U2     DJ17  DDR7_SB_DQ30  SOCKET4677_AZIFS054P001C01  I169

M_H_CPU0_SB_DQ<31>   @S9S_MB_2U_LIB.S9S_MB_2U(SCH_1):M_H_CPU0_SB_DQ<31>
  J15    287  DQ_B31  SCONN288_ADR50001P013C01  I48
  J16    287  DQ_B31  SCONN288_ADR50001P003C01   I6
  U2     DC17  DDR7_SB_DQ31  SOCKET4677_AZIFS054P001C01  I169

M_H_CPU0_SB_DQS_DN<0>   @S9S_MB_2U_LIB.S9S_MB_2U(SCH_1):M_H_CPU0_SB_DQS_DN<0>
  J15    105  DQS0_B_N  SCONN288_ADR50001P013C01  I124
  J16    105  DQS0_B_N  SCONN288_ADR50001P003C01  I132
  U2     DD30  DDR7_SB_DQS_DN0  SOCKET4677_AZIFS054P001C01  I169

M_H_CPU0_SB_DQS_DN<1>   @S9S_MB_2U_LIB.S9S_MB_2U(SCH_1):M_H_CPU0_SB_DQS_DN<1>
  J15    116  DQS1_B_N  SCONN288_ADR50001P013C01  I124
  J16    116  DQS1_B_N  SCONN288_ADR50001P003C01  I132
  U2     DD24  DDR7_SB_DQS_DN1  SOCKET4677_AZIFS054P001C01  I169

M_H_CPU0_SB_DQS_DN<2>   @S9S_MB_2U_LIB.S9S_MB_2U(SCH_1):M_H_CPU0_SB_DQS_DN<2>
  J15    127  DQS2_B_N  SCONN288_ADR50001P013C01  I124
  J16    127  DQS2_B_N  SCONN288_ADR50001P003C01  I132
  U2     DL21  DDR7_SB_DQS_DN2  SOCKET4677_AZIFS054P001C01  I169

M_H_CPU0_SB_DQS_DN<3>   @S9S_MB_2U_LIB.S9S_MB_2U(SCH_1):M_H_CPU0_SB_DQS_DN<3>
  J15    138  DQS3_B_N  SCONN288_ADR50001P013C01  I124
  J16    138  DQS3_B_N  SCONN288_ADR50001P003C01  I132
  U2     DB18  DDR7_SB_DQS_DN3  SOCKET4677_AZIFS054P001C01  I169

M_H_CPU0_SB_DQS_DN<4>   @S9S_MB_2U_LIB.S9S_MB_2U(SCH_1):M_H_CPU0_SB_DQS_DN<4>
  J15    238  DQS4_B_N  SCONN288_ADR50001P013C01  I124
  J16    238  DQS4_B_N  SCONN288_ADR50001P003C01  I132
  U2     DH36  DDR7_SB_DQS_DN4  SOCKET4677_AZIFS054P001C01  I169

M_H_CPU0_SB_DQS_DN<5>   @S9S_MB_2U_LIB.S9S_MB_2U(SCH_1):M_H_CPU0_SB_DQS_DN<5>
  J15    249  DQS5_B_N  SCONN288_ADR50001P013C01  I124
  J16    249  DQS5_B_N  SCONN288_ADR50001P003C01  I132
  U2     DH30  DDR7_SB_DQS_DN5  SOCKET4677_AZIFS054P001C01  I169

M_H_CPU0_SB_DQS_DN<6>   @S9S_MB_2U_LIB.S9S_MB_2U(SCH_1):M_H_CPU0_SB_DQS_DN<6>
  J15    260  DQS6_B_N  SCONN288_ADR50001P013C01  I124
  J16    260  DQS6_B_N  SCONN288_ADR50001P003C01  I132
  U2     DH24  DDR7_SB_DQS_DN6  SOCKET4677_AZIFS054P001C01  I169

M_H_CPU0_SB_DQS_DN<7>   @S9S_MB_2U_LIB.S9S_MB_2U(SCH_1):M_H_CPU0_SB_DQS_DN<7>
  J15    271  DQS7_B_N  SCONN288_ADR50001P013C01  I124
  J16    271  DQS7_B_N  SCONN288_ADR50001P003C01  I132
  U2     DR21  DDR7_SB_DQS_DN7  SOCKET4677_AZIFS054P001C01  I169

M_H_CPU0_SB_DQS_DN<8>   @S9S_MB_2U_LIB.S9S_MB_2U(SCH_1):M_H_CPU0_SB_DQS_DN<8>
  J15    282  DQS8_B_N  SCONN288_ADR50001P013C01  I124
  J16    282  DQS8_B_N  SCONN288_ADR50001P003C01  I132
  U2     DF18  DDR7_SB_DQS_DN8  SOCKET4677_AZIFS054P001C01  I169

M_H_CPU0_SB_DQS_DN<9>   @S9S_MB_2U_LIB.S9S_MB_2U(SCH_1):M_H_CPU0_SB_DQS_DN<9>
  J15     94  DQS9_B_N  SCONN288_ADR50001P013C01  I124
  J16     94  DQS9_B_N  SCONN288_ADR50001P003C01  I132
  U2     DD36  DDR7_SB_DQS_DN9  SOCKET4677_AZIFS054P001C01  I169

M_H_CPU0_SB_DQS_DP<0>   @S9S_MB_2U_LIB.S9S_MB_2U(SCH_1):M_H_CPU0_SB_DQS_DP<0>
  J15    104  DQS0_B_P  SCONN288_ADR50001P013C01  I124
  J16    104  DQS0_B_P  SCONN288_ADR50001P003C01  I132
  U2     DB30  DDR7_SB_DQS_DP0  SOCKET4677_AZIFS054P001C01  I169

M_H_CPU0_SB_DQS_DP<1>   @S9S_MB_2U_LIB.S9S_MB_2U(SCH_1):M_H_CPU0_SB_DQS_DP<1>
  J15    115  DQS1_B_P  SCONN288_ADR50001P013C01  I124
  J16    115  DQS1_B_P  SCONN288_ADR50001P003C01  I132
  U2     DB24  DDR7_SB_DQS_DP1  SOCKET4677_AZIFS054P001C01  I169

M_H_CPU0_SB_DQS_DP<2>   @S9S_MB_2U_LIB.S9S_MB_2U(SCH_1):M_H_CPU0_SB_DQS_DP<2>
  J15    126  DQS2_B_P  SCONN288_ADR50001P013C01  I124
  J16    126  DQS2_B_P  SCONN288_ADR50001P003C01  I132
  U2     DJ21  DDR7_SB_DQS_DP2  SOCKET4677_AZIFS054P001C01  I169

M_H_CPU0_SB_DQS_DP<3>   @S9S_MB_2U_LIB.S9S_MB_2U(SCH_1):M_H_CPU0_SB_DQS_DP<3>
  J15    137  DQS3_B_P  SCONN288_ADR50001P013C01  I124
  J16    137  DQS3_B_P  SCONN288_ADR50001P003C01  I132
  U2     DD18  DDR7_SB_DQS_DP3  SOCKET4677_AZIFS054P001C01  I169

M_H_CPU0_SB_DQS_DP<4>   @S9S_MB_2U_LIB.S9S_MB_2U(SCH_1):M_H_CPU0_SB_DQS_DP<4>
  J15    239  DQS4_B_P  SCONN288_ADR50001P013C01  I124
  J16    239  DQS4_B_P  SCONN288_ADR50001P003C01  I132
  U2     DF36  DDR7_SB_DQS_DP4  SOCKET4677_AZIFS054P001C01  I169

M_H_CPU0_SB_DQS_DP<5>   @S9S_MB_2U_LIB.S9S_MB_2U(SCH_1):M_H_CPU0_SB_DQS_DP<5>
  J15    250  DQS5_B_P  SCONN288_ADR50001P013C01  I124
  J16    250  DQS5_B_P  SCONN288_ADR50001P003C01  I132
  U2     DF30  DDR7_SB_DQS_DP5  SOCKET4677_AZIFS054P001C01  I169

M_H_CPU0_SB_DQS_DP<6>   @S9S_MB_2U_LIB.S9S_MB_2U(SCH_1):M_H_CPU0_SB_DQS_DP<6>
  J15    261  DQS6_B_P  SCONN288_ADR50001P013C01  I124
  J16    261  DQS6_B_P  SCONN288_ADR50001P003C01  I132
  U2     DF24  DDR7_SB_DQS_DP6  SOCKET4677_AZIFS054P001C01  I169

M_H_CPU0_SB_DQS_DP<7>   @S9S_MB_2U_LIB.S9S_MB_2U(SCH_1):M_H_CPU0_SB_DQS_DP<7>
  J15    272  DQS7_B_P  SCONN288_ADR50001P013C01  I124
  J16    272  DQS7_B_P  SCONN288_ADR50001P003C01  I132
  U2     DN21  DDR7_SB_DQS_DP7  SOCKET4677_AZIFS054P001C01  I169

M_H_CPU0_SB_DQS_DP<8>   @S9S_MB_2U_LIB.S9S_MB_2U(SCH_1):M_H_CPU0_SB_DQS_DP<8>
  J15    283  DQS8_B_P  SCONN288_ADR50001P013C01  I124
  J16    283  DQS8_B_P  SCONN288_ADR50001P003C01  I132
  U2     DH18  DDR7_SB_DQS_DP8  SOCKET4677_AZIFS054P001C01  I169

M_H_CPU0_SB_DQS_DP<9>   @S9S_MB_2U_LIB.S9S_MB_2U(SCH_1):M_H_CPU0_SB_DQS_DP<9>
  J15     93  DQS9_B_P  SCONN288_ADR50001P013C01  I124
  J16     93  DQS9_B_P  SCONN288_ADR50001P003C01  I132
  U2     DB36  DDR7_SB_DQS_DP9  SOCKET4677_AZIFS054P001C01  I169

M_H_CPU0_SB_PAR   @S9S_MB_2U_LIB.S9S_MB_2U(SCH_1):M_H_CPU0_SB_PAR
  J15    227  PAR_B  SCONN288_ADR50001P013C01  I48
  J16    227  PAR_B  SCONN288_ADR50001P003C01   I6
  U2     DR39  DDR7_SB_PAR  SOCKET4677_AZIFS054P001C01  I169

M_H_CPU0_SB_RSP<0>   @S9S_MB_2U_LIB.S9S_MB_2U(SCH_1):M_H_CPU0_SB_RSP<0>
  J15     87  LBS||RSP_N_B  SCONN288_ADR50001P013C01  I48
  U2     EE48  DDR7_B_RSP0  SOCKET4677_AZIFS054P001C01  I169

M_H_CPU0_SB_RSP<1>   @S9S_MB_2U_LIB.S9S_MB_2U(SCH_1):M_H_CPU0_SB_RSP<1>
  J16     87  LBS||RSP_N_B  SCONN288_ADR50001P003C01   I6
  U2     ED47  DDR7_B_RSP1  SOCKET4677_AZIFS054P001C01  I169

M_H_CPU1_ALERT_N   @S9S_MB_2U_LIB.S9S_MB_2U(SCH_1):M_H_CPU1_ALERT_N
  J31     62  ALERT_N  SCONN288_ADR50001P013C01  I180
  J32     62  ALERT_N  SCONN288_ADR50001P003C01  I179
  U1     CY51  DDR7_ALERT_N  SOCKET4677_AZIFS054P001C01  I20

M_H_CPU1_CLK_DN<0>   @S9S_MB_2U_LIB.S9S_MB_2U(SCH_1):M_H_CPU1_CLK_DN<0>
  J31    218   CK_N  SCONN288_ADR50001P013C01  I180
  U1     DH42  DDR7_CLK_DN0  SOCKET4677_AZIFS054P001C01  I20

M_H_CPU1_CLK_DN<1>   @S9S_MB_2U_LIB.S9S_MB_2U(SCH_1):M_H_CPU1_CLK_DN<1>
  J32    218   CK_N  SCONN288_ADR50001P003C01  I179
  U1     DD42  DDR7_CLK_DN1  SOCKET4677_AZIFS054P001C01  I20

M_H_CPU1_CLK_DP<0>   @S9S_MB_2U_LIB.S9S_MB_2U(SCH_1):M_H_CPU1_CLK_DP<0>
  J31    217   CK_P  SCONN288_ADR50001P013C01  I180
  U1     DF42  DDR7_CLK_DP0  SOCKET4677_AZIFS054P001C01  I20

M_H_CPU1_CLK_DP<1>   @S9S_MB_2U_LIB.S9S_MB_2U(SCH_1):M_H_CPU1_CLK_DP<1>
  J32    217   CK_P  SCONN288_ADR50001P003C01  I179
  U1     DB42  DDR7_CLK_DP1  SOCKET4677_AZIFS054P001C01  I20

M_H_CPU1_SA_CA<0>   @S9S_MB_2U_LIB.S9S_MB_2U(SCH_1):M_H_CPU1_SA_CA<0>
  J31     66  CA0_A  SCONN288_ADR50001P013C01  I180
  J32     66  CA0_A  SCONN288_ADR50001P003C01  I179
  U1     DB49  DDR7_SA_CA0  SOCKET4677_AZIFS054P001C01  I20

M_H_CPU1_SA_CA<1>   @S9S_MB_2U_LIB.S9S_MB_2U(SCH_1):M_H_CPU1_SA_CA<1>
  J31    211  CA1_A  SCONN288_ADR50001P013C01  I180
  J32    211  CA1_A  SCONN288_ADR50001P003C01  I179
  U1     DH49  DDR7_SA_CA1  SOCKET4677_AZIFS054P001C01  I20

M_H_CPU1_SA_CA<2>   @S9S_MB_2U_LIB.S9S_MB_2U(SCH_1):M_H_CPU1_SA_CA<2>
  J31     68  CA2_A  SCONN288_ADR50001P013C01  I180
  J32     68  CA2_A  SCONN288_ADR50001P003C01  I179
  U1     DC48  DDR7_SA_CA2  SOCKET4677_AZIFS054P001C01  I20

M_H_CPU1_SA_CA<3>   @S9S_MB_2U_LIB.S9S_MB_2U(SCH_1):M_H_CPU1_SA_CA<3>
  J31    213  CA3_A  SCONN288_ADR50001P013C01  I180
  J32    213  CA3_A  SCONN288_ADR50001P003C01  I179
  U1     DG48  DDR7_SA_CA3  SOCKET4677_AZIFS054P001C01  I20

M_H_CPU1_SA_CA<4>   @S9S_MB_2U_LIB.S9S_MB_2U(SCH_1):M_H_CPU1_SA_CA<4>
  J31     70  CA4_A  SCONN288_ADR50001P013C01  I180
  J32     70  CA4_A  SCONN288_ADR50001P003C01  I179
  U1     DD47  DDR7_SA_CA4  SOCKET4677_AZIFS054P001C01  I20

M_H_CPU1_SA_CA<5>   @S9S_MB_2U_LIB.S9S_MB_2U(SCH_1):M_H_CPU1_SA_CA<5>
  J31    215  CA5_A  SCONN288_ADR50001P013C01  I180
  J32    215  CA5_A  SCONN288_ADR50001P003C01  I179
  U1     DF47  DDR7_SA_CA5  SOCKET4677_AZIFS054P001C01  I20

M_H_CPU1_SA_CA<6>   @S9S_MB_2U_LIB.S9S_MB_2U(SCH_1):M_H_CPU1_SA_CA<6>
  J31     72  CA6_A  SCONN288_ADR50001P013C01  I180
  J32     72  CA6_A  SCONN288_ADR50001P003C01  I179
  U1     DC41  DDR7_SA_CA6  SOCKET4677_AZIFS054P001C01  I20

M_H_CPU1_SA_CB<0>   @S9S_MB_2U_LIB.S9S_MB_2U(SCH_1):M_H_CPU1_SA_CB<0>
  J31     51  CB_A0  SCONN288_ADR50001P013C01  I180
  J32     51  CB_A0  SCONN288_ADR50001P003C01  I179
  U1     DD57  DDR7_SA_ECC0  SOCKET4677_AZIFS054P001C01  I20

M_H_CPU1_SA_CB<1>   @S9S_MB_2U_LIB.S9S_MB_2U(SCH_1):M_H_CPU1_SA_CB<1>
  J31     53  CB_A1  SCONN288_ADR50001P013C01  I180
  J32     53  CB_A1  SCONN288_ADR50001P003C01  I179
  U1     DC56  DDR7_SA_ECC1  SOCKET4677_AZIFS054P001C01  I20

M_H_CPU1_SA_CB<2>   @S9S_MB_2U_LIB.S9S_MB_2U(SCH_1):M_H_CPU1_SA_CB<2>
  J31    196  CB_A2  SCONN288_ADR50001P013C01  I180
  J32    196  CB_A2  SCONN288_ADR50001P003C01  I179
  U1     DF57  DDR7_SA_ECC2  SOCKET4677_AZIFS054P001C01  I20

M_H_CPU1_SA_CB<3>   @S9S_MB_2U_LIB.S9S_MB_2U(SCH_1):M_H_CPU1_SA_CB<3>
  J31    198  CB_A3  SCONN288_ADR50001P013C01  I180
  J32    198  CB_A3  SCONN288_ADR50001P003C01  I179
  U1     DG56  DDR7_SA_ECC3  SOCKET4677_AZIFS054P001C01  I20

M_H_CPU1_SA_CB<4>   @S9S_MB_2U_LIB.S9S_MB_2U(SCH_1):M_H_CPU1_SA_CB<4>
  J31     58  CB_A4  SCONN288_ADR50001P013C01  I180
  J32     58  CB_A4  SCONN288_ADR50001P003C01  I179
  U1     DC54  DDR7_SA_ECC4  SOCKET4677_AZIFS054P001C01  I20

M_H_CPU1_SA_CB<5>   @S9S_MB_2U_LIB.S9S_MB_2U(SCH_1):M_H_CPU1_SA_CB<5>
  J31     60  CB_A5  SCONN288_ADR50001P013C01  I180
  J32     60  CB_A5  SCONN288_ADR50001P003C01  I179
  U1     DD53  DDR7_SA_ECC5  SOCKET4677_AZIFS054P001C01  I20

M_H_CPU1_SA_CB<6>   @S9S_MB_2U_LIB.S9S_MB_2U(SCH_1):M_H_CPU1_SA_CB<6>
  J31    203  CB_A6  SCONN288_ADR50001P013C01  I180
  J32    203  CB_A6  SCONN288_ADR50001P003C01  I179
  U1     DG54  DDR7_SA_ECC6  SOCKET4677_AZIFS054P001C01  I20

M_H_CPU1_SA_CB<7>   @S9S_MB_2U_LIB.S9S_MB_2U(SCH_1):M_H_CPU1_SA_CB<7>
  J31    205  CB_A7  SCONN288_ADR50001P013C01  I180
  J32    205  CB_A7  SCONN288_ADR50001P003C01  I179
  U1     DF53  DDR7_SA_ECC7  SOCKET4677_AZIFS054P001C01  I20

M_H_CPU1_SA_CS_N<0>   @S9S_MB_2U_LIB.S9S_MB_2U(SCH_1):M_H_CPU1_SA_CS_N<0>
  J31     64  CS0_N_A  SCONN288_ADR50001P013C01  I180
  U1     DF51  DDR7_SA_CS0_N  SOCKET4677_AZIFS054P001C01  I20

M_H_CPU1_SA_CS_N<1>   @S9S_MB_2U_LIB.S9S_MB_2U(SCH_1):M_H_CPU1_SA_CS_N<1>
  J31    209  CS1_N_A  SCONN288_ADR50001P013C01  I180
  U1     DG50  DDR7_SA_CS1_N  SOCKET4677_AZIFS054P001C01  I20

M_H_CPU1_SA_CS_N<2>   @S9S_MB_2U_LIB.S9S_MB_2U(SCH_1):M_H_CPU1_SA_CS_N<2>
  J32     64  CS0_N_A  SCONN288_ADR50001P003C01  I179
  U1     DD51  DDR7_SA_CS2_N  SOCKET4677_AZIFS054P001C01  I20

M_H_CPU1_SA_CS_N<3>   @S9S_MB_2U_LIB.S9S_MB_2U(SCH_1):M_H_CPU1_SA_CS_N<3>
  J32    209  CS1_N_A  SCONN288_ADR50001P003C01  I179
  U1     DC50  DDR7_SA_CS3_N  SOCKET4677_AZIFS054P001C01  I20

M_H_CPU1_SA_DQ<0>   @S9S_MB_2U_LIB.S9S_MB_2U(SCH_1):M_H_CPU1_SA_DQ<0>
  J31      7  DQ_A0  SCONN288_ADR50001P013C01  I180
  J32      7  DQ_A0  SCONN288_ADR50001P003C01  I179
  U1     DY79  DDR7_SA_DQ0  SOCKET4677_AZIFS054P001C01  I20

M_H_CPU1_SA_DQ<1>   @S9S_MB_2U_LIB.S9S_MB_2U(SCH_1):M_H_CPU1_SA_DQ<1>
  J31      9  DQ_A1  SCONN288_ADR50001P013C01  I180
  J32      9  DQ_A1  SCONN288_ADR50001P003C01  I179
  U1     DT77  DDR7_SA_DQ1  SOCKET4677_AZIFS054P001C01  I20

M_H_CPU1_SA_DQ<2>   @S9S_MB_2U_LIB.S9S_MB_2U(SCH_1):M_H_CPU1_SA_DQ<2>
  J31    152  DQ_A2  SCONN288_ADR50001P013C01  I180
  J32    152  DQ_A2  SCONN288_ADR50001P003C01  I179
  U1     DW78  DDR7_SA_DQ2  SOCKET4677_AZIFS054P001C01  I20

M_H_CPU1_SA_DQ<3>   @S9S_MB_2U_LIB.S9S_MB_2U(SCH_1):M_H_CPU1_SA_DQ<3>
  J31    154  DQ_A3  SCONN288_ADR50001P013C01  I180
  J32    154  DQ_A3  SCONN288_ADR50001P003C01  I179
  U1     DP77  DDR7_SA_DQ3  SOCKET4677_AZIFS054P001C01  I20

M_H_CPU1_SA_DQ<4>   @S9S_MB_2U_LIB.S9S_MB_2U(SCH_1):M_H_CPU1_SA_DQ<4>
  J31     14  DQ_A4  SCONN288_ADR50001P013C01  I180
  J32     14  DQ_A4  SCONN288_ADR50001P003C01  I179
  U1     DK75  DDR7_SA_DQ4  SOCKET4677_AZIFS054P001C01  I20

M_H_CPU1_SA_DQ<5>   @S9S_MB_2U_LIB.S9S_MB_2U(SCH_1):M_H_CPU1_SA_DQ<5>
  J31     16  DQ_A5  SCONN288_ADR50001P013C01  I180
  J32     16  DQ_A5  SCONN288_ADR50001P003C01  I179
  U1     DL74  DDR7_SA_DQ5  SOCKET4677_AZIFS054P001C01  I20

M_H_CPU1_SA_DQ<6>   @S9S_MB_2U_LIB.S9S_MB_2U(SCH_1):M_H_CPU1_SA_DQ<6>
  J31    159  DQ_A6  SCONN288_ADR50001P013C01  I180
  J32    159  DQ_A6  SCONN288_ADR50001P003C01  I179
  U1     DP75  DDR7_SA_DQ6  SOCKET4677_AZIFS054P001C01  I20

M_H_CPU1_SA_DQ<7>   @S9S_MB_2U_LIB.S9S_MB_2U(SCH_1):M_H_CPU1_SA_DQ<7>
  J31    161  DQ_A7  SCONN288_ADR50001P013C01  I180
  J32    161  DQ_A7  SCONN288_ADR50001P003C01  I179
  U1     DN74  DDR7_SA_DQ7  SOCKET4677_AZIFS054P001C01  I20

M_H_CPU1_SA_DQ<8>   @S9S_MB_2U_LIB.S9S_MB_2U(SCH_1):M_H_CPU1_SA_DQ<8>
  J31     18  DQ_A8  SCONN288_ADR50001P013C01  I180
  J32     18  DQ_A8  SCONN288_ADR50001P003C01  I179
  U1     DD75  DDR7_SA_DQ8  SOCKET4677_AZIFS054P001C01  I20

M_H_CPU1_SA_DQ<9>   @S9S_MB_2U_LIB.S9S_MB_2U(SCH_1):M_H_CPU1_SA_DQ<9>
  J31     20  DQ_A9  SCONN288_ADR50001P013C01  I180
  J32     20  DQ_A9  SCONN288_ADR50001P003C01  I179
  U1     DC74  DDR7_SA_DQ9  SOCKET4677_AZIFS054P001C01  I20

M_H_CPU1_SA_DQ<10>   @S9S_MB_2U_LIB.S9S_MB_2U(SCH_1):M_H_CPU1_SA_DQ<10>
  J31    163  DQ_A10  SCONN288_ADR50001P013C01  I180
  J32    163  DQ_A10  SCONN288_ADR50001P003C01  I179
  U1     DF75  DDR7_SA_DQ10  SOCKET4677_AZIFS054P001C01  I20

M_H_CPU1_SA_DQ<11>   @S9S_MB_2U_LIB.S9S_MB_2U(SCH_1):M_H_CPU1_SA_DQ<11>
  J31    165  DQ_A11  SCONN288_ADR50001P013C01  I180
  J32    165  DQ_A11  SCONN288_ADR50001P003C01  I179
  U1     DG74  DDR7_SA_DQ11  SOCKET4677_AZIFS054P001C01  I20

M_H_CPU1_SA_DQ<12>   @S9S_MB_2U_LIB.S9S_MB_2U(SCH_1):M_H_CPU1_SA_DQ<12>
  J31     25  DQ_A12  SCONN288_ADR50001P013C01  I180
  J32     25  DQ_A12  SCONN288_ADR50001P003C01  I179
  U1     DC72  DDR7_SA_DQ12  SOCKET4677_AZIFS054P001C01  I20

M_H_CPU1_SA_DQ<13>   @S9S_MB_2U_LIB.S9S_MB_2U(SCH_1):M_H_CPU1_SA_DQ<13>
  J31     27  DQ_A13  SCONN288_ADR50001P013C01  I180
  J32     27  DQ_A13  SCONN288_ADR50001P003C01  I179
  U1     DD71  DDR7_SA_DQ13  SOCKET4677_AZIFS054P001C01  I20

M_H_CPU1_SA_DQ<14>   @S9S_MB_2U_LIB.S9S_MB_2U(SCH_1):M_H_CPU1_SA_DQ<14>
  J31    170  DQ_A14  SCONN288_ADR50001P013C01  I180
  J32    170  DQ_A14  SCONN288_ADR50001P003C01  I179
  U1     DG72  DDR7_SA_DQ14  SOCKET4677_AZIFS054P001C01  I20

M_H_CPU1_SA_DQ<15>   @S9S_MB_2U_LIB.S9S_MB_2U(SCH_1):M_H_CPU1_SA_DQ<15>
  J31    172  DQ_A15  SCONN288_ADR50001P013C01  I180
  J32    172  DQ_A15  SCONN288_ADR50001P003C01  I179
  U1     DF71  DDR7_SA_DQ15  SOCKET4677_AZIFS054P001C01  I20

M_H_CPU1_SA_DQ<16>   @S9S_MB_2U_LIB.S9S_MB_2U(SCH_1):M_H_CPU1_SA_DQ<16>
  J31     29  DQ_A16  SCONN288_ADR50001P013C01  I180
  J32     29  DQ_A16  SCONN288_ADR50001P003C01  I179
  U1     DD69  DDR7_SA_DQ16  SOCKET4677_AZIFS054P001C01  I20

M_H_CPU1_SA_DQ<17>   @S9S_MB_2U_LIB.S9S_MB_2U(SCH_1):M_H_CPU1_SA_DQ<17>
  J31     31  DQ_A17  SCONN288_ADR50001P013C01  I180
  J32     31  DQ_A17  SCONN288_ADR50001P003C01  I179
  U1     DC68  DDR7_SA_DQ17  SOCKET4677_AZIFS054P001C01  I20

M_H_CPU1_SA_DQ<18>   @S9S_MB_2U_LIB.S9S_MB_2U(SCH_1):M_H_CPU1_SA_DQ<18>
  J31    174  DQ_A18  SCONN288_ADR50001P013C01  I180
  J32    174  DQ_A18  SCONN288_ADR50001P003C01  I179
  U1     DF69  DDR7_SA_DQ18  SOCKET4677_AZIFS054P001C01  I20

M_H_CPU1_SA_DQ<19>   @S9S_MB_2U_LIB.S9S_MB_2U(SCH_1):M_H_CPU1_SA_DQ<19>
  J31    176  DQ_A19  SCONN288_ADR50001P013C01  I180
  J32    176  DQ_A19  SCONN288_ADR50001P003C01  I179
  U1     DG68  DDR7_SA_DQ19  SOCKET4677_AZIFS054P001C01  I20

M_H_CPU1_SA_DQ<20>   @S9S_MB_2U_LIB.S9S_MB_2U(SCH_1):M_H_CPU1_SA_DQ<20>
  J31     36  DQ_A20  SCONN288_ADR50001P013C01  I180
  J32     36  DQ_A20  SCONN288_ADR50001P003C01  I179
  U1     DC66  DDR7_SA_DQ20  SOCKET4677_AZIFS054P001C01  I20

M_H_CPU1_SA_DQ<21>   @S9S_MB_2U_LIB.S9S_MB_2U(SCH_1):M_H_CPU1_SA_DQ<21>
  J31     38  DQ_A21  SCONN288_ADR50001P013C01  I180
  J32     38  DQ_A21  SCONN288_ADR50001P003C01  I179
  U1     DD65  DDR7_SA_DQ21  SOCKET4677_AZIFS054P001C01  I20

M_H_CPU1_SA_DQ<22>   @S9S_MB_2U_LIB.S9S_MB_2U(SCH_1):M_H_CPU1_SA_DQ<22>
  J31    181  DQ_A22  SCONN288_ADR50001P013C01  I180
  J32    181  DQ_A22  SCONN288_ADR50001P003C01  I179
  U1     DG66  DDR7_SA_DQ22  SOCKET4677_AZIFS054P001C01  I20

M_H_CPU1_SA_DQ<23>   @S9S_MB_2U_LIB.S9S_MB_2U(SCH_1):M_H_CPU1_SA_DQ<23>
  J31    183  DQ_A23  SCONN288_ADR50001P013C01  I180
  J32    183  DQ_A23  SCONN288_ADR50001P003C01  I179
  U1     DF65  DDR7_SA_DQ23  SOCKET4677_AZIFS054P001C01  I20

M_H_CPU1_SA_DQ<24>   @S9S_MB_2U_LIB.S9S_MB_2U(SCH_1):M_H_CPU1_SA_DQ<24>
  J31     40  DQ_A24  SCONN288_ADR50001P013C01  I180
  J32     40  DQ_A24  SCONN288_ADR50001P003C01  I179
  U1     DD63  DDR7_SA_DQ24  SOCKET4677_AZIFS054P001C01  I20

M_H_CPU1_SA_DQ<25>   @S9S_MB_2U_LIB.S9S_MB_2U(SCH_1):M_H_CPU1_SA_DQ<25>
  J31     42  DQ_A25  SCONN288_ADR50001P013C01  I180
  J32     42  DQ_A25  SCONN288_ADR50001P003C01  I179
  U1     DC62  DDR7_SA_DQ25  SOCKET4677_AZIFS054P001C01  I20

M_H_CPU1_SA_DQ<26>   @S9S_MB_2U_LIB.S9S_MB_2U(SCH_1):M_H_CPU1_SA_DQ<26>
  J31    185  DQ_A26  SCONN288_ADR50001P013C01  I180
  J32    185  DQ_A26  SCONN288_ADR50001P003C01  I179
  U1     DF63  DDR7_SA_DQ26  SOCKET4677_AZIFS054P001C01  I20

M_H_CPU1_SA_DQ<27>   @S9S_MB_2U_LIB.S9S_MB_2U(SCH_1):M_H_CPU1_SA_DQ<27>
  J31    187  DQ_A27  SCONN288_ADR50001P013C01  I180
  J32    187  DQ_A27  SCONN288_ADR50001P003C01  I179
  U1     DG62  DDR7_SA_DQ27  SOCKET4677_AZIFS054P001C01  I20

M_H_CPU1_SA_DQ<28>   @S9S_MB_2U_LIB.S9S_MB_2U(SCH_1):M_H_CPU1_SA_DQ<28>
  J31     47  DQ_A28  SCONN288_ADR50001P013C01  I180
  J32     47  DQ_A28  SCONN288_ADR50001P003C01  I179
  U1     DC60  DDR7_SA_DQ28  SOCKET4677_AZIFS054P001C01  I20

M_H_CPU1_SA_DQ<29>   @S9S_MB_2U_LIB.S9S_MB_2U(SCH_1):M_H_CPU1_SA_DQ<29>
  J31     49  DQ_A29  SCONN288_ADR50001P013C01  I180
  J32     49  DQ_A29  SCONN288_ADR50001P003C01  I179
  U1     DD59  DDR7_SA_DQ29  SOCKET4677_AZIFS054P001C01  I20

M_H_CPU1_SA_DQ<30>   @S9S_MB_2U_LIB.S9S_MB_2U(SCH_1):M_H_CPU1_SA_DQ<30>
  J31    192  DQ_A30  SCONN288_ADR50001P013C01  I180
  J32    192  DQ_A30  SCONN288_ADR50001P003C01  I179
  U1     DG60  DDR7_SA_DQ30  SOCKET4677_AZIFS054P001C01  I20

M_H_CPU1_SA_DQ<31>   @S9S_MB_2U_LIB.S9S_MB_2U(SCH_1):M_H_CPU1_SA_DQ<31>
  J31    194  DQ_A31  SCONN288_ADR50001P013C01  I180
  J32    194  DQ_A31  SCONN288_ADR50001P003C01  I179
  U1     DF59  DDR7_SA_DQ31  SOCKET4677_AZIFS054P001C01  I20

M_H_CPU1_SA_DQS_DN<0>   @S9S_MB_2U_LIB.S9S_MB_2U(SCH_1):M_H_CPU1_SA_DQS_DN<0>
  J31     12  DQS0_A_N  SCONN288_ADR50001P013C01  I179
  J32     12  DQS0_A_N  SCONN288_ADR50001P003C01  I178
  U1     DJ76  DDR7_SA_DQS_DN0  SOCKET4677_AZIFS054P001C01  I20

M_H_CPU1_SA_DQS_DN<1>   @S9S_MB_2U_LIB.S9S_MB_2U(SCH_1):M_H_CPU1_SA_DQS_DN<1>
  J31     23  DQS1_A_N  SCONN288_ADR50001P013C01  I179
  J32     23  DQS1_A_N  SCONN288_ADR50001P003C01  I178
  U1     DB73  DDR7_SA_DQS_DN1  SOCKET4677_AZIFS054P001C01  I20

M_H_CPU1_SA_DQS_DN<2>   @S9S_MB_2U_LIB.S9S_MB_2U(SCH_1):M_H_CPU1_SA_DQS_DN<2>
  J31     34  DQS2_A_N  SCONN288_ADR50001P013C01  I179
  J32     34  DQS2_A_N  SCONN288_ADR50001P003C01  I178
  U1     DD67  DDR7_SA_DQS_DN2  SOCKET4677_AZIFS054P001C01  I20

M_H_CPU1_SA_DQS_DN<3>   @S9S_MB_2U_LIB.S9S_MB_2U(SCH_1):M_H_CPU1_SA_DQS_DN<3>
  J31     45  DQS3_A_N  SCONN288_ADR50001P013C01  I179
  J32     45  DQS3_A_N  SCONN288_ADR50001P003C01  I178
  U1     DD61  DDR7_SA_DQS_DN3  SOCKET4677_AZIFS054P001C01  I20

M_H_CPU1_SA_DQS_DN<4>   @S9S_MB_2U_LIB.S9S_MB_2U(SCH_1):M_H_CPU1_SA_DQS_DN<4>
  J31     56  DQS4_A_N  SCONN288_ADR50001P013C01  I179
  J32     56  DQS4_A_N  SCONN288_ADR50001P003C01  I178
  U1     DD55  DDR7_SA_DQS_DN4  SOCKET4677_AZIFS054P001C01  I20

M_H_CPU1_SA_DQS_DN<5>   @S9S_MB_2U_LIB.S9S_MB_2U(SCH_1):M_H_CPU1_SA_DQS_DN<5>
  J31    156  DQS5_A_N  SCONN288_ADR50001P013C01  I179
  J32    156  DQS5_A_N  SCONN288_ADR50001P003C01  I178
  U1     DR76  DDR7_SA_DQS_DN5  SOCKET4677_AZIFS054P001C01  I20

M_H_CPU1_SA_DQS_DN<6>   @S9S_MB_2U_LIB.S9S_MB_2U(SCH_1):M_H_CPU1_SA_DQS_DN<6>
  J31    167  DQS6_A_N  SCONN288_ADR50001P013C01  I179
  J32    167  DQS6_A_N  SCONN288_ADR50001P003C01  I178
  U1     DH73  DDR7_SA_DQS_DN6  SOCKET4677_AZIFS054P001C01  I20

M_H_CPU1_SA_DQS_DN<7>   @S9S_MB_2U_LIB.S9S_MB_2U(SCH_1):M_H_CPU1_SA_DQS_DN<7>
  J31    178  DQS7_A_N  SCONN288_ADR50001P013C01  I179
  J32    178  DQS7_A_N  SCONN288_ADR50001P003C01  I178
  U1     DH67  DDR7_SA_DQS_DN7  SOCKET4677_AZIFS054P001C01  I20

M_H_CPU1_SA_DQS_DN<8>   @S9S_MB_2U_LIB.S9S_MB_2U(SCH_1):M_H_CPU1_SA_DQS_DN<8>
  J31    189  DQS8_A_N  SCONN288_ADR50001P013C01  I179
  J32    189  DQS8_A_N  SCONN288_ADR50001P003C01  I178
  U1     DH61  DDR7_SA_DQS_DN8  SOCKET4677_AZIFS054P001C01  I20

M_H_CPU1_SA_DQS_DN<9>   @S9S_MB_2U_LIB.S9S_MB_2U(SCH_1):M_H_CPU1_SA_DQS_DN<9>
  J31    200  DQS9_A_N  SCONN288_ADR50001P013C01  I179
  J32    200  DQS9_A_N  SCONN288_ADR50001P003C01  I178
  U1     DH55  DDR7_SA_DQS_DN9  SOCKET4677_AZIFS054P001C01  I20

M_H_CPU1_SA_DQS_DP<0>   @S9S_MB_2U_LIB.S9S_MB_2U(SCH_1):M_H_CPU1_SA_DQS_DP<0>
  J31     11  DQS0_A_P  SCONN288_ADR50001P013C01  I179
  J32     11  DQS0_A_P  SCONN288_ADR50001P003C01  I178
  U1     DL76  DDR7_SA_DQS_DP0  SOCKET4677_AZIFS054P001C01  I20

M_H_CPU1_SA_DQS_DP<1>   @S9S_MB_2U_LIB.S9S_MB_2U(SCH_1):M_H_CPU1_SA_DQS_DP<1>
  J31     22  DQS1_A_P  SCONN288_ADR50001P013C01  I179
  J32     22  DQS1_A_P  SCONN288_ADR50001P003C01  I178
  U1     DD73  DDR7_SA_DQS_DP1  SOCKET4677_AZIFS054P001C01  I20

M_H_CPU1_SA_DQS_DP<2>   @S9S_MB_2U_LIB.S9S_MB_2U(SCH_1):M_H_CPU1_SA_DQS_DP<2>
  J31     33  DQS2_A_P  SCONN288_ADR50001P013C01  I179
  J32     33  DQS2_A_P  SCONN288_ADR50001P003C01  I178
  U1     DB67  DDR7_SA_DQS_DP2  SOCKET4677_AZIFS054P001C01  I20

M_H_CPU1_SA_DQS_DP<3>   @S9S_MB_2U_LIB.S9S_MB_2U(SCH_1):M_H_CPU1_SA_DQS_DP<3>
  J31     44  DQS3_A_P  SCONN288_ADR50001P013C01  I179
  J32     44  DQS3_A_P  SCONN288_ADR50001P003C01  I178
  U1     DB61  DDR7_SA_DQS_DP3  SOCKET4677_AZIFS054P001C01  I20

M_H_CPU1_SA_DQS_DP<4>   @S9S_MB_2U_LIB.S9S_MB_2U(SCH_1):M_H_CPU1_SA_DQS_DP<4>
  J31     55  DQS4_A_P  SCONN288_ADR50001P013C01  I179
  J32     55  DQS4_A_P  SCONN288_ADR50001P003C01  I178
  U1     DB55  DDR7_SA_DQS_DP4  SOCKET4677_AZIFS054P001C01  I20

M_H_CPU1_SA_DQS_DP<5>   @S9S_MB_2U_LIB.S9S_MB_2U(SCH_1):M_H_CPU1_SA_DQS_DP<5>
  J31    157  DQS5_A_P  SCONN288_ADR50001P013C01  I179
  J32    157  DQS5_A_P  SCONN288_ADR50001P003C01  I178
  U1     DN76  DDR7_SA_DQS_DP5  SOCKET4677_AZIFS054P001C01  I20

M_H_CPU1_SA_DQS_DP<6>   @S9S_MB_2U_LIB.S9S_MB_2U(SCH_1):M_H_CPU1_SA_DQS_DP<6>
  J31    168  DQS6_A_P  SCONN288_ADR50001P013C01  I179
  J32    168  DQS6_A_P  SCONN288_ADR50001P003C01  I178
  U1     DF73  DDR7_SA_DQS_DP6  SOCKET4677_AZIFS054P001C01  I20

M_H_CPU1_SA_DQS_DP<7>   @S9S_MB_2U_LIB.S9S_MB_2U(SCH_1):M_H_CPU1_SA_DQS_DP<7>
  J31    179  DQS7_A_P  SCONN288_ADR50001P013C01  I179
  J32    179  DQS7_A_P  SCONN288_ADR50001P003C01  I178
  U1     DF67  DDR7_SA_DQS_DP7  SOCKET4677_AZIFS054P001C01  I20

M_H_CPU1_SA_DQS_DP<8>   @S9S_MB_2U_LIB.S9S_MB_2U(SCH_1):M_H_CPU1_SA_DQS_DP<8>
  J31    190  DQS8_A_P  SCONN288_ADR50001P013C01  I179
  J32    190  DQS8_A_P  SCONN288_ADR50001P003C01  I178
  U1     DF61  DDR7_SA_DQS_DP8  SOCKET4677_AZIFS054P001C01  I20

M_H_CPU1_SA_DQS_DP<9>   @S9S_MB_2U_LIB.S9S_MB_2U(SCH_1):M_H_CPU1_SA_DQS_DP<9>
  J31    201  DQS9_A_P  SCONN288_ADR50001P013C01  I179
  J32    201  DQS9_A_P  SCONN288_ADR50001P003C01  I178
  U1     DF55  DDR7_SA_DQS_DP9  SOCKET4677_AZIFS054P001C01  I20

M_H_CPU1_SA_PAR   @S9S_MB_2U_LIB.S9S_MB_2U(SCH_1):M_H_CPU1_SA_PAR
  J31     74  PAR_A  SCONN288_ADR50001P013C01  I180
  J32     74  PAR_A  SCONN288_ADR50001P003C01  I179
  U1     DD40  DDR7_SA_PAR  SOCKET4677_AZIFS054P001C01  I20

M_H_CPU1_SA_RSP<0>   @S9S_MB_2U_LIB.S9S_MB_2U(SCH_1):M_H_CPU1_SA_RSP<0>
  J31     86  LBD||RSP_N_A  SCONN288_ADR50001P013C01  I180
  U1     EG48  DDR7_A_RSP0  SOCKET4677_AZIFS054P001C01  I20

M_H_CPU1_SA_RSP<1>   @S9S_MB_2U_LIB.S9S_MB_2U(SCH_1):M_H_CPU1_SA_RSP<1>
  J32     86  LBD||RSP_N_A  SCONN288_ADR50001P003C01  I179
  U1     EH47  DDR7_A_RSP1  SOCKET4677_AZIFS054P001C01  I20

M_H_CPU1_SB_CA<0>   @S9S_MB_2U_LIB.S9S_MB_2U(SCH_1):M_H_CPU1_SB_CA<0>
  J31     76  CA0_B  SCONN288_ADR50001P013C01  I180
  J32     76  CA0_B  SCONN288_ADR50001P003C01  I179
  U1     DF40  DDR7_SB_CA0  SOCKET4677_AZIFS054P001C01  I20

M_H_CPU1_SB_CA<1>   @S9S_MB_2U_LIB.S9S_MB_2U(SCH_1):M_H_CPU1_SB_CA<1>
  J31    221  CA1_B  SCONN288_ADR50001P013C01  I180
  J32    221  CA1_B  SCONN288_ADR50001P003C01  I179
  U1     DG41  DDR7_SB_CA1  SOCKET4677_AZIFS054P001C01  I20

M_H_CPU1_SB_CA<2>   @S9S_MB_2U_LIB.S9S_MB_2U(SCH_1):M_H_CPU1_SB_CA<2>
  J31     78  CA2_B  SCONN288_ADR50001P013C01  I180
  J32     78  CA2_B  SCONN288_ADR50001P003C01  I179
  U1     DL41  DDR7_SB_CA2  SOCKET4677_AZIFS054P001C01  I20

M_H_CPU1_SB_CA<3>   @S9S_MB_2U_LIB.S9S_MB_2U(SCH_1):M_H_CPU1_SB_CA<3>
  J31    223  CA3_B  SCONN288_ADR50001P013C01  I180
  J32    223  CA3_B  SCONN288_ADR50001P003C01  I179
  U1     DN41  DDR7_SB_CA3  SOCKET4677_AZIFS054P001C01  I20

M_H_CPU1_SB_CA<4>   @S9S_MB_2U_LIB.S9S_MB_2U(SCH_1):M_H_CPU1_SB_CA<4>
  J31     80  CA4_B  SCONN288_ADR50001P013C01  I180
  J32     80  CA4_B  SCONN288_ADR50001P003C01  I179
  U1     DK40  DDR7_SB_CA4  SOCKET4677_AZIFS054P001C01  I20

M_H_CPU1_SB_CA<5>   @S9S_MB_2U_LIB.S9S_MB_2U(SCH_1):M_H_CPU1_SB_CA<5>
  J31    225  CA5_B  SCONN288_ADR50001P013C01  I180
  J32    225  CA5_B  SCONN288_ADR50001P003C01  I179
  U1     DP40  DDR7_SB_CA5  SOCKET4677_AZIFS054P001C01  I20

M_H_CPU1_SB_CA<6>   @S9S_MB_2U_LIB.S9S_MB_2U(SCH_1):M_H_CPU1_SB_CA<6>
  J31     82  CA6_B  SCONN288_ADR50001P013C01  I180
  J32     82  CA6_B  SCONN288_ADR50001P003C01  I179
  U1     DJ39  DDR7_SB_CA6  SOCKET4677_AZIFS054P001C01  I20

M_H_CPU1_SB_CB<0>   @S9S_MB_2U_LIB.S9S_MB_2U(SCH_1):M_H_CPU1_SB_CB<0>
  J31     96  CB_B0  SCONN288_ADR50001P013C01  I180
  J32     96  CB_B0  SCONN288_ADR50001P003C01  I179
  U1     DC35  DDR7_SB_ECC0  SOCKET4677_AZIFS054P001C01  I20

M_H_CPU1_SB_CB<1>   @S9S_MB_2U_LIB.S9S_MB_2U(SCH_1):M_H_CPU1_SB_CB<1>
  J31     98  CB_B1  SCONN288_ADR50001P013C01  I180
  J32     98  CB_B1  SCONN288_ADR50001P003C01  I179
  U1     DD34  DDR7_SB_ECC1  SOCKET4677_AZIFS054P001C01  I20

M_H_CPU1_SB_CB<2>   @S9S_MB_2U_LIB.S9S_MB_2U(SCH_1):M_H_CPU1_SB_CB<2>
  J31    241  CB_B2  SCONN288_ADR50001P013C01  I180
  J32    241  CB_B2  SCONN288_ADR50001P003C01  I179
  U1     DG35  DDR7_SB_ECC2  SOCKET4677_AZIFS054P001C01  I20

M_H_CPU1_SB_CB<3>   @S9S_MB_2U_LIB.S9S_MB_2U(SCH_1):M_H_CPU1_SB_CB<3>
  J31    243  CB_B3  SCONN288_ADR50001P013C01  I180
  J32    243  CB_B3  SCONN288_ADR50001P003C01  I179
  U1     DF34  DDR7_SB_ECC3  SOCKET4677_AZIFS054P001C01  I20

M_H_CPU1_SB_CB<4>   @S9S_MB_2U_LIB.S9S_MB_2U(SCH_1):M_H_CPU1_SB_CB<4>
  J31     89  CB_B4  SCONN288_ADR50001P013C01  I180
  J32     89  CB_B4  SCONN288_ADR50001P003C01  I179
  U1     DF38  DDR7_SB_ECC4  SOCKET4677_AZIFS054P001C01  I20

M_H_CPU1_SB_CB<5>   @S9S_MB_2U_LIB.S9S_MB_2U(SCH_1):M_H_CPU1_SB_CB<5>
  J31     91  CB_B5  SCONN288_ADR50001P013C01  I180
  J32     91  CB_B5  SCONN288_ADR50001P003C01  I179
  U1     DG37  DDR7_SB_ECC5  SOCKET4677_AZIFS054P001C01  I20

M_H_CPU1_SB_CB<6>   @S9S_MB_2U_LIB.S9S_MB_2U(SCH_1):M_H_CPU1_SB_CB<6>
  J31    234  CB_B6  SCONN288_ADR50001P013C01  I180
  J32    234  CB_B6  SCONN288_ADR50001P003C01  I179
  U1     DD38  DDR7_SB_ECC6  SOCKET4677_AZIFS054P001C01  I20

M_H_CPU1_SB_CB<7>   @S9S_MB_2U_LIB.S9S_MB_2U(SCH_1):M_H_CPU1_SB_CB<7>
  J31    236  CB_B7  SCONN288_ADR50001P013C01  I180
  J32    236  CB_B7  SCONN288_ADR50001P003C01  I179
  U1     DC37  DDR7_SB_ECC7  SOCKET4677_AZIFS054P001C01  I20

M_H_CPU1_SB_CS_N<0>   @S9S_MB_2U_LIB.S9S_MB_2U(SCH_1):M_H_CPU1_SB_CS_N<0>
  J31     84  CS0_N_B  SCONN288_ADR50001P013C01  I180
  U1     DL37  DDR7_SB_CS0_N  SOCKET4677_AZIFS054P001C01  I20

M_H_CPU1_SB_CS_N<1>   @S9S_MB_2U_LIB.S9S_MB_2U(SCH_1):M_H_CPU1_SB_CS_N<1>
  J31    229  CS1_N_B  SCONN288_ADR50001P013C01  I180
  U1     DN37  DDR7_SB_CS1_N  SOCKET4677_AZIFS054P001C01  I20

M_H_CPU1_SB_CS_N<2>   @S9S_MB_2U_LIB.S9S_MB_2U(SCH_1):M_H_CPU1_SB_CS_N<2>
  J32     84  CS0_N_B  SCONN288_ADR50001P003C01  I179
  U1     DK38  DDR7_SB_CS2_N  SOCKET4677_AZIFS054P001C01  I20

M_H_CPU1_SB_CS_N<3>   @S9S_MB_2U_LIB.S9S_MB_2U(SCH_1):M_H_CPU1_SB_CS_N<3>
  J32    229  CS1_N_B  SCONN288_ADR50001P003C01  I179
  U1     DP38  DDR7_SB_CS3_N  SOCKET4677_AZIFS054P001C01  I20

M_H_CPU1_SB_DQ<0>   @S9S_MB_2U_LIB.S9S_MB_2U(SCH_1):M_H_CPU1_SB_DQ<0>
  J31    100  DQ_B0  SCONN288_ADR50001P013C01  I180
  J32    100  DQ_B0  SCONN288_ADR50001P003C01  I179
  U1     DD32  DDR7_SB_DQ0  SOCKET4677_AZIFS054P001C01  I20

M_H_CPU1_SB_DQ<1>   @S9S_MB_2U_LIB.S9S_MB_2U(SCH_1):M_H_CPU1_SB_DQ<1>
  J31    102  DQ_B1  SCONN288_ADR50001P013C01  I180
  J32    102  DQ_B1  SCONN288_ADR50001P003C01  I179
  U1     DC31  DDR7_SB_DQ1  SOCKET4677_AZIFS054P001C01  I20

M_H_CPU1_SB_DQ<2>   @S9S_MB_2U_LIB.S9S_MB_2U(SCH_1):M_H_CPU1_SB_DQ<2>
  J31    245  DQ_B2  SCONN288_ADR50001P013C01  I180
  J32    245  DQ_B2  SCONN288_ADR50001P003C01  I179
  U1     DF32  DDR7_SB_DQ2  SOCKET4677_AZIFS054P001C01  I20

M_H_CPU1_SB_DQ<3>   @S9S_MB_2U_LIB.S9S_MB_2U(SCH_1):M_H_CPU1_SB_DQ<3>
  J31    247  DQ_B3  SCONN288_ADR50001P013C01  I180
  J32    247  DQ_B3  SCONN288_ADR50001P003C01  I179
  U1     DG31  DDR7_SB_DQ3  SOCKET4677_AZIFS054P001C01  I20

M_H_CPU1_SB_DQ<4>   @S9S_MB_2U_LIB.S9S_MB_2U(SCH_1):M_H_CPU1_SB_DQ<4>
  J31    107  DQ_B4  SCONN288_ADR50001P013C01  I180
  J32    107  DQ_B4  SCONN288_ADR50001P003C01  I179
  U1     DC29  DDR7_SB_DQ4  SOCKET4677_AZIFS054P001C01  I20

M_H_CPU1_SB_DQ<5>   @S9S_MB_2U_LIB.S9S_MB_2U(SCH_1):M_H_CPU1_SB_DQ<5>
  J31    109  DQ_B5  SCONN288_ADR50001P013C01  I180
  J32    109  DQ_B5  SCONN288_ADR50001P003C01  I179
  U1     DF28  DDR7_SB_DQ5  SOCKET4677_AZIFS054P001C01  I20

M_H_CPU1_SB_DQ<6>   @S9S_MB_2U_LIB.S9S_MB_2U(SCH_1):M_H_CPU1_SB_DQ<6>
  J31    252  DQ_B6  SCONN288_ADR50001P013C01  I180
  J32    252  DQ_B6  SCONN288_ADR50001P003C01  I179
  U1     DG29  DDR7_SB_DQ6  SOCKET4677_AZIFS054P001C01  I20

M_H_CPU1_SB_DQ<7>   @S9S_MB_2U_LIB.S9S_MB_2U(SCH_1):M_H_CPU1_SB_DQ<7>
  J31    254  DQ_B7  SCONN288_ADR50001P013C01  I180
  J32    254  DQ_B7  SCONN288_ADR50001P003C01  I179
  U1     DD28  DDR7_SB_DQ7  SOCKET4677_AZIFS054P001C01  I20

M_H_CPU1_SB_DQ<8>   @S9S_MB_2U_LIB.S9S_MB_2U(SCH_1):M_H_CPU1_SB_DQ<8>
  J31    111  DQ_B8  SCONN288_ADR50001P013C01  I180
  J32    111  DQ_B8  SCONN288_ADR50001P003C01  I179
  U1     DD26  DDR7_SB_DQ8  SOCKET4677_AZIFS054P001C01  I20

M_H_CPU1_SB_DQ<9>   @S9S_MB_2U_LIB.S9S_MB_2U(SCH_1):M_H_CPU1_SB_DQ<9>
  J31    113  DQ_B9  SCONN288_ADR50001P013C01  I180
  J32    113  DQ_B9  SCONN288_ADR50001P003C01  I179
  U1     DC25  DDR7_SB_DQ9  SOCKET4677_AZIFS054P001C01  I20

M_H_CPU1_SB_DQ<10>   @S9S_MB_2U_LIB.S9S_MB_2U(SCH_1):M_H_CPU1_SB_DQ<10>
  J31    256  DQ_B10  SCONN288_ADR50001P013C01  I180
  J32    256  DQ_B10  SCONN288_ADR50001P003C01  I179
  U1     DF26  DDR7_SB_DQ10  SOCKET4677_AZIFS054P001C01  I20

M_H_CPU1_SB_DQ<11>   @S9S_MB_2U_LIB.S9S_MB_2U(SCH_1):M_H_CPU1_SB_DQ<11>
  J31    258  DQ_B11  SCONN288_ADR50001P013C01  I180
  J32    258  DQ_B11  SCONN288_ADR50001P003C01  I179
  U1     DG25  DDR7_SB_DQ11  SOCKET4677_AZIFS054P001C01  I20

M_H_CPU1_SB_DQ<12>   @S9S_MB_2U_LIB.S9S_MB_2U(SCH_1):M_H_CPU1_SB_DQ<12>
  J31    118  DQ_B12  SCONN288_ADR50001P013C01  I180
  J32    118  DQ_B12  SCONN288_ADR50001P003C01  I179
  U1     DC23  DDR7_SB_DQ12  SOCKET4677_AZIFS054P001C01  I20

M_H_CPU1_SB_DQ<13>   @S9S_MB_2U_LIB.S9S_MB_2U(SCH_1):M_H_CPU1_SB_DQ<13>
  J31    120  DQ_B13  SCONN288_ADR50001P013C01  I180
  J32    120  DQ_B13  SCONN288_ADR50001P003C01  I179
  U1     DD22  DDR7_SB_DQ13  SOCKET4677_AZIFS054P001C01  I20

M_H_CPU1_SB_DQ<14>   @S9S_MB_2U_LIB.S9S_MB_2U(SCH_1):M_H_CPU1_SB_DQ<14>
  J31    263  DQ_B14  SCONN288_ADR50001P013C01  I180
  J32    263  DQ_B14  SCONN288_ADR50001P003C01  I179
  U1     DG23  DDR7_SB_DQ14  SOCKET4677_AZIFS054P001C01  I20

M_H_CPU1_SB_DQ<15>   @S9S_MB_2U_LIB.S9S_MB_2U(SCH_1):M_H_CPU1_SB_DQ<15>
  J31    265  DQ_B15  SCONN288_ADR50001P013C01  I180
  J32    265  DQ_B15  SCONN288_ADR50001P003C01  I179
  U1     DF22  DDR7_SB_DQ15  SOCKET4677_AZIFS054P001C01  I20

M_H_CPU1_SB_DQ<16>   @S9S_MB_2U_LIB.S9S_MB_2U(SCH_1):M_H_CPU1_SB_DQ<16>
  J31    122  DQ_B16  SCONN288_ADR50001P013C01  I180
  J32    122  DQ_B16  SCONN288_ADR50001P003C01  I179
  U1     DL23  DDR7_SB_DQ16  SOCKET4677_AZIFS054P001C01  I20

M_H_CPU1_SB_DQ<17>   @S9S_MB_2U_LIB.S9S_MB_2U(SCH_1):M_H_CPU1_SB_DQ<17>
  J31    124  DQ_B17  SCONN288_ADR50001P013C01  I180
  J32    124  DQ_B17  SCONN288_ADR50001P003C01  I179
  U1     DK22  DDR7_SB_DQ17  SOCKET4677_AZIFS054P001C01  I20

M_H_CPU1_SB_DQ<18>   @S9S_MB_2U_LIB.S9S_MB_2U(SCH_1):M_H_CPU1_SB_DQ<18>
  J31    267  DQ_B18  SCONN288_ADR50001P013C01  I180
  J32    267  DQ_B18  SCONN288_ADR50001P003C01  I179
  U1     DN23  DDR7_SB_DQ18  SOCKET4677_AZIFS054P001C01  I20

M_H_CPU1_SB_DQ<19>   @S9S_MB_2U_LIB.S9S_MB_2U(SCH_1):M_H_CPU1_SB_DQ<19>
  J31    269  DQ_B19  SCONN288_ADR50001P013C01  I180
  J32    269  DQ_B19  SCONN288_ADR50001P003C01  I179
  U1     DP22  DDR7_SB_DQ19  SOCKET4677_AZIFS054P001C01  I20

M_H_CPU1_SB_DQ<20>   @S9S_MB_2U_LIB.S9S_MB_2U(SCH_1):M_H_CPU1_SB_DQ<20>
  J31    129  DQ_B20  SCONN288_ADR50001P013C01  I180
  J32    129  DQ_B20  SCONN288_ADR50001P003C01  I179
  U1     DK20  DDR7_SB_DQ20  SOCKET4677_AZIFS054P001C01  I20

M_H_CPU1_SB_DQ<21>   @S9S_MB_2U_LIB.S9S_MB_2U(SCH_1):M_H_CPU1_SB_DQ<21>
  J31    131  DQ_B21  SCONN288_ADR50001P013C01  I180
  J32    131  DQ_B21  SCONN288_ADR50001P003C01  I179
  U1     DL19  DDR7_SB_DQ21  SOCKET4677_AZIFS054P001C01  I20

M_H_CPU1_SB_DQ<22>   @S9S_MB_2U_LIB.S9S_MB_2U(SCH_1):M_H_CPU1_SB_DQ<22>
  J31    274  DQ_B22  SCONN288_ADR50001P013C01  I180
  J32    274  DQ_B22  SCONN288_ADR50001P003C01  I179
  U1     DP20  DDR7_SB_DQ22  SOCKET4677_AZIFS054P001C01  I20

M_H_CPU1_SB_DQ<23>   @S9S_MB_2U_LIB.S9S_MB_2U(SCH_1):M_H_CPU1_SB_DQ<23>
  J31    276  DQ_B23  SCONN288_ADR50001P013C01  I180
  J32    276  DQ_B23  SCONN288_ADR50001P003C01  I179
  U1     DN19  DDR7_SB_DQ23  SOCKET4677_AZIFS054P001C01  I20

M_H_CPU1_SB_DQ<24>   @S9S_MB_2U_LIB.S9S_MB_2U(SCH_1):M_H_CPU1_SB_DQ<24>
  J31    133  DQ_B24  SCONN288_ADR50001P013C01  I180
  J32    133  DQ_B24  SCONN288_ADR50001P003C01  I179
  U1     DD20  DDR7_SB_DQ24  SOCKET4677_AZIFS054P001C01  I20

M_H_CPU1_SB_DQ<25>   @S9S_MB_2U_LIB.S9S_MB_2U(SCH_1):M_H_CPU1_SB_DQ<25>
  J31    135  DQ_B25  SCONN288_ADR50001P013C01  I180
  J32    135  DQ_B25  SCONN288_ADR50001P003C01  I179
  U1     DC19  DDR7_SB_DQ25  SOCKET4677_AZIFS054P001C01  I20

M_H_CPU1_SB_DQ<26>   @S9S_MB_2U_LIB.S9S_MB_2U(SCH_1):M_H_CPU1_SB_DQ<26>
  J31    278  DQ_B26  SCONN288_ADR50001P013C01  I180
  J32    278  DQ_B26  SCONN288_ADR50001P003C01  I179
  U1     DF20  DDR7_SB_DQ26  SOCKET4677_AZIFS054P001C01  I20

M_H_CPU1_SB_DQ<27>   @S9S_MB_2U_LIB.S9S_MB_2U(SCH_1):M_H_CPU1_SB_DQ<27>
  J31    280  DQ_B27  SCONN288_ADR50001P013C01  I180
  J32    280  DQ_B27  SCONN288_ADR50001P003C01  I179
  U1     DG19  DDR7_SB_DQ27  SOCKET4677_AZIFS054P001C01  I20

M_H_CPU1_SB_DQ<28>   @S9S_MB_2U_LIB.S9S_MB_2U(SCH_1):M_H_CPU1_SB_DQ<28>
  J31    140  DQ_B28  SCONN288_ADR50001P013C01  I180
  J32    140  DQ_B28  SCONN288_ADR50001P003C01  I179
  U1     DG17  DDR7_SB_DQ28  SOCKET4677_AZIFS054P001C01  I20

M_H_CPU1_SB_DQ<29>   @S9S_MB_2U_LIB.S9S_MB_2U(SCH_1):M_H_CPU1_SB_DQ<29>
  J31    142  DQ_B29  SCONN288_ADR50001P013C01  I180
  J32    142  DQ_B29  SCONN288_ADR50001P003C01  I179
  U1     DA17  DDR7_SB_DQ29  SOCKET4677_AZIFS054P001C01  I20

M_H_CPU1_SB_DQ<30>   @S9S_MB_2U_LIB.S9S_MB_2U(SCH_1):M_H_CPU1_SB_DQ<30>
  J31    285  DQ_B30  SCONN288_ADR50001P013C01  I180
  J32    285  DQ_B30  SCONN288_ADR50001P003C01  I179
  U1     DJ17  DDR7_SB_DQ30  SOCKET4677_AZIFS054P001C01  I20

M_H_CPU1_SB_DQ<31>   @S9S_MB_2U_LIB.S9S_MB_2U(SCH_1):M_H_CPU1_SB_DQ<31>
  J31    287  DQ_B31  SCONN288_ADR50001P013C01  I180
  J32    287  DQ_B31  SCONN288_ADR50001P003C01  I179
  U1     DC17  DDR7_SB_DQ31  SOCKET4677_AZIFS054P001C01  I20

M_H_CPU1_SB_DQS_DN<0>   @S9S_MB_2U_LIB.S9S_MB_2U(SCH_1):M_H_CPU1_SB_DQS_DN<0>
  J31    105  DQS0_B_N  SCONN288_ADR50001P013C01  I179
  J32    105  DQS0_B_N  SCONN288_ADR50001P003C01  I178
  U1     DD30  DDR7_SB_DQS_DN0  SOCKET4677_AZIFS054P001C01  I20

M_H_CPU1_SB_DQS_DN<1>   @S9S_MB_2U_LIB.S9S_MB_2U(SCH_1):M_H_CPU1_SB_DQS_DN<1>
  J31    116  DQS1_B_N  SCONN288_ADR50001P013C01  I179
  J32    116  DQS1_B_N  SCONN288_ADR50001P003C01  I178
  U1     DD24  DDR7_SB_DQS_DN1  SOCKET4677_AZIFS054P001C01  I20

M_H_CPU1_SB_DQS_DN<2>   @S9S_MB_2U_LIB.S9S_MB_2U(SCH_1):M_H_CPU1_SB_DQS_DN<2>
  J31    127  DQS2_B_N  SCONN288_ADR50001P013C01  I179
  J32    127  DQS2_B_N  SCONN288_ADR50001P003C01  I178
  U1     DL21  DDR7_SB_DQS_DN2  SOCKET4677_AZIFS054P001C01  I20

M_H_CPU1_SB_DQS_DN<3>   @S9S_MB_2U_LIB.S9S_MB_2U(SCH_1):M_H_CPU1_SB_DQS_DN<3>
  J31    138  DQS3_B_N  SCONN288_ADR50001P013C01  I179
  J32    138  DQS3_B_N  SCONN288_ADR50001P003C01  I178
  U1     DB18  DDR7_SB_DQS_DN3  SOCKET4677_AZIFS054P001C01  I20

M_H_CPU1_SB_DQS_DN<4>   @S9S_MB_2U_LIB.S9S_MB_2U(SCH_1):M_H_CPU1_SB_DQS_DN<4>
  J31    238  DQS4_B_N  SCONN288_ADR50001P013C01  I179
  J32    238  DQS4_B_N  SCONN288_ADR50001P003C01  I178
  U1     DH36  DDR7_SB_DQS_DN4  SOCKET4677_AZIFS054P001C01  I20

M_H_CPU1_SB_DQS_DN<5>   @S9S_MB_2U_LIB.S9S_MB_2U(SCH_1):M_H_CPU1_SB_DQS_DN<5>
  J31    249  DQS5_B_N  SCONN288_ADR50001P013C01  I179
  J32    249  DQS5_B_N  SCONN288_ADR50001P003C01  I178
  U1     DH30  DDR7_SB_DQS_DN5  SOCKET4677_AZIFS054P001C01  I20

M_H_CPU1_SB_DQS_DN<6>   @S9S_MB_2U_LIB.S9S_MB_2U(SCH_1):M_H_CPU1_SB_DQS_DN<6>
  J31    260  DQS6_B_N  SCONN288_ADR50001P013C01  I179
  J32    260  DQS6_B_N  SCONN288_ADR50001P003C01  I178
  U1     DH24  DDR7_SB_DQS_DN6  SOCKET4677_AZIFS054P001C01  I20

M_H_CPU1_SB_DQS_DN<7>   @S9S_MB_2U_LIB.S9S_MB_2U(SCH_1):M_H_CPU1_SB_DQS_DN<7>
  J31    271  DQS7_B_N  SCONN288_ADR50001P013C01  I179
  J32    271  DQS7_B_N  SCONN288_ADR50001P003C01  I178
  U1     DR21  DDR7_SB_DQS_DN7  SOCKET4677_AZIFS054P001C01  I20

M_H_CPU1_SB_DQS_DN<8>   @S9S_MB_2U_LIB.S9S_MB_2U(SCH_1):M_H_CPU1_SB_DQS_DN<8>
  J31    282  DQS8_B_N  SCONN288_ADR50001P013C01  I179
  J32    282  DQS8_B_N  SCONN288_ADR50001P003C01  I178
  U1     DF18  DDR7_SB_DQS_DN8  SOCKET4677_AZIFS054P001C01  I20

M_H_CPU1_SB_DQS_DN<9>   @S9S_MB_2U_LIB.S9S_MB_2U(SCH_1):M_H_CPU1_SB_DQS_DN<9>
  J31     94  DQS9_B_N  SCONN288_ADR50001P013C01  I179
  J32     94  DQS9_B_N  SCONN288_ADR50001P003C01  I178
  U1     DD36  DDR7_SB_DQS_DN9  SOCKET4677_AZIFS054P001C01  I20

M_H_CPU1_SB_DQS_DP<0>   @S9S_MB_2U_LIB.S9S_MB_2U(SCH_1):M_H_CPU1_SB_DQS_DP<0>
  J31    104  DQS0_B_P  SCONN288_ADR50001P013C01  I179
  J32    104  DQS0_B_P  SCONN288_ADR50001P003C01  I178
  U1     DB30  DDR7_SB_DQS_DP0  SOCKET4677_AZIFS054P001C01  I20

M_H_CPU1_SB_DQS_DP<1>   @S9S_MB_2U_LIB.S9S_MB_2U(SCH_1):M_H_CPU1_SB_DQS_DP<1>
  J31    115  DQS1_B_P  SCONN288_ADR50001P013C01  I179
  J32    115  DQS1_B_P  SCONN288_ADR50001P003C01  I178
  U1     DB24  DDR7_SB_DQS_DP1  SOCKET4677_AZIFS054P001C01  I20

M_H_CPU1_SB_DQS_DP<2>   @S9S_MB_2U_LIB.S9S_MB_2U(SCH_1):M_H_CPU1_SB_DQS_DP<2>
  J31    126  DQS2_B_P  SCONN288_ADR50001P013C01  I179
  J32    126  DQS2_B_P  SCONN288_ADR50001P003C01  I178
  U1     DJ21  DDR7_SB_DQS_DP2  SOCKET4677_AZIFS054P001C01  I20

M_H_CPU1_SB_DQS_DP<3>   @S9S_MB_2U_LIB.S9S_MB_2U(SCH_1):M_H_CPU1_SB_DQS_DP<3>
  J31    137  DQS3_B_P  SCONN288_ADR50001P013C01  I179
  J32    137  DQS3_B_P  SCONN288_ADR50001P003C01  I178
  U1     DD18  DDR7_SB_DQS_DP3  SOCKET4677_AZIFS054P001C01  I20

M_H_CPU1_SB_DQS_DP<4>   @S9S_MB_2U_LIB.S9S_MB_2U(SCH_1):M_H_CPU1_SB_DQS_DP<4>
  J31    239  DQS4_B_P  SCONN288_ADR50001P013C01  I179
  J32    239  DQS4_B_P  SCONN288_ADR50001P003C01  I178
  U1     DF36  DDR7_SB_DQS_DP4  SOCKET4677_AZIFS054P001C01  I20

M_H_CPU1_SB_DQS_DP<5>   @S9S_MB_2U_LIB.S9S_MB_2U(SCH_1):M_H_CPU1_SB_DQS_DP<5>
  J31    250  DQS5_B_P  SCONN288_ADR50001P013C01  I179
  J32    250  DQS5_B_P  SCONN288_ADR50001P003C01  I178
  U1     DF30  DDR7_SB_DQS_DP5  SOCKET4677_AZIFS054P001C01  I20

M_H_CPU1_SB_DQS_DP<6>   @S9S_MB_2U_LIB.S9S_MB_2U(SCH_1):M_H_CPU1_SB_DQS_DP<6>
  J31    261  DQS6_B_P  SCONN288_ADR50001P013C01  I179
  J32    261  DQS6_B_P  SCONN288_ADR50001P003C01  I178
  U1     DF24  DDR7_SB_DQS_DP6  SOCKET4677_AZIFS054P001C01  I20

M_H_CPU1_SB_DQS_DP<7>   @S9S_MB_2U_LIB.S9S_MB_2U(SCH_1):M_H_CPU1_SB_DQS_DP<7>
  J31    272  DQS7_B_P  SCONN288_ADR50001P013C01  I179
  J32    272  DQS7_B_P  SCONN288_ADR50001P003C01  I178
  U1     DN21  DDR7_SB_DQS_DP7  SOCKET4677_AZIFS054P001C01  I20

M_H_CPU1_SB_DQS_DP<8>   @S9S_MB_2U_LIB.S9S_MB_2U(SCH_1):M_H_CPU1_SB_DQS_DP<8>
  J31    283  DQS8_B_P  SCONN288_ADR50001P013C01  I179
  J32    283  DQS8_B_P  SCONN288_ADR50001P003C01  I178
  U1     DH18  DDR7_SB_DQS_DP8  SOCKET4677_AZIFS054P001C01  I20

M_H_CPU1_SB_DQS_DP<9>   @S9S_MB_2U_LIB.S9S_MB_2U(SCH_1):M_H_CPU1_SB_DQS_DP<9>
  J31     93  DQS9_B_P  SCONN288_ADR50001P013C01  I179
  J32     93  DQS9_B_P  SCONN288_ADR50001P003C01  I178
  U1     DB36  DDR7_SB_DQS_DP9  SOCKET4677_AZIFS054P001C01  I20

M_H_CPU1_SB_PAR   @S9S_MB_2U_LIB.S9S_MB_2U(SCH_1):M_H_CPU1_SB_PAR
  J31    227  PAR_B  SCONN288_ADR50001P013C01  I180
  J32    227  PAR_B  SCONN288_ADR50001P003C01  I179
  U1     DR39  DDR7_SB_PAR  SOCKET4677_AZIFS054P001C01  I20

M_H_CPU1_SB_RSP<0>   @S9S_MB_2U_LIB.S9S_MB_2U(SCH_1):M_H_CPU1_SB_RSP<0>
  J31     87  LBS||RSP_N_B  SCONN288_ADR50001P013C01  I180
  U1     EE48  DDR7_B_RSP0  SOCKET4677_AZIFS054P001C01  I20

M_H_CPU1_SB_RSP<1>   @S9S_MB_2U_LIB.S9S_MB_2U(SCH_1):M_H_CPU1_SB_RSP<1>
  J32     87  LBS||RSP_N_B  SCONN288_ADR50001P003C01  I179
  U1     ED47  DDR7_B_RSP1  SOCKET4677_AZIFS054P001C01  I20

NC              NC
  U4     AD37  SATA_8_PCIE3_8_USB3_8_TXP  EMMITSBURG_REV0P9  I119
  U4     AE36  SATA_8_PCIE3_8_USB3_8_TXN  EMMITSBURG_REV0P9  I119
  U4     U43  SATA_8_PCIE3_8_USB3_8_RXP  EMMITSBURG_REV0P9  I119
  U4     U41  SATA_8_PCIE3_8_USB3_8_RXN  EMMITSBURG_REV0P9  I119
  U4     AK40  USB2P_7  EMMITSBURG_REV0P9  I11
  U4     AK42  USB2N_7  EMMITSBURG_REV0P9  I11
  U4     AV41  USB2P_6  EMMITSBURG_REV0P9  I11
  U4     AV43  USB2N_6  EMMITSBURG_REV0P9  I11
  U4     AT41  USB2P_2  EMMITSBURG_REV0P9  I11
  U4     AT43  USB2N_2  EMMITSBURG_REV0P9  I11
  U4     AG41  USB2P_13  EMMITSBURG_REV0P9  I11
  U4     AG43  USB2N_13  EMMITSBURG_REV0P9  I11
  U4     BA40  USB2P_12  EMMITSBURG_REV0P9  I11
  U4     BA42  USB2N_12  EMMITSBURG_REV0P9  I11
  U4     AH40  USB2P_11  EMMITSBURG_REV0P9  I11
  U4     AH42  USB2N_11  EMMITSBURG_REV0P9  I11
  U4     AY41  USB2P_10  EMMITSBURG_REV0P9  I11
  U4     AY43  USB2N_10  EMMITSBURG_REV0P9  I11
  J41    OCP_B5  DATA_OUT  SCONN168_623403212  I115
  J41    OCP_B6    CLK  SCONN168_623403212  I115
  U1     BT28  PTI_DIE009  SOCKET4677_AZIFS054P001C01  I23
  U1     BU27  PTI_DIE008  SOCKET4677_AZIFS054P001C01  I23
  U1     BV28  PTI_DIE007  SOCKET4677_AZIFS054P001C01  I23
  U1     CA27  PTI_DIE006  SOCKET4677_AZIFS054P001C01  I23
  U1     BV30  PTI_DIE005  SOCKET4677_AZIFS054P001C01  I23
  U1     CA29  PTI_DIE004  SOCKET4677_AZIFS054P001C01  I23
  U1     BY30  PTI_DIE003  SOCKET4677_AZIFS054P001C01  I23
  U1     BN66  PTI_DIE0115  SOCKET4677_AZIFS054P001C01  I23
  U1     BM67  PTI_DIE0114  SOCKET4677_AZIFS054P001C01  I23
  U1     CC27  PTI_DIE002  SOCKET4677_AZIFS054P001C01  I23
  U1     BL66  PTI_DIE0113  SOCKET4677_AZIFS054P001C01  I23
  U1     BJ66  PTI_DIE0112  SOCKET4677_AZIFS054P001C01  I23
  U1     BG66  PTI_DIE0111  SOCKET4677_AZIFS054P001C01  I23
  U1     BN68  PTI_DIE0110  SOCKET4677_AZIFS054P001C01  I23
  U1     BM69  PTI_DIE019  SOCKET4677_AZIFS054P001C01  I23
  U1     BK69  PTI_DIE018  SOCKET4677_AZIFS054P001C01  I23
  U1     BD67  PTI_DIE017  SOCKET4677_AZIFS054P001C01  I23
  U1     BG68  PTI_DIE016  SOCKET4677_AZIFS054P001C01  I23
  U1     BC68  PTI_DIE015  SOCKET4677_AZIFS054P001C01  I23
  U1     BH69  PTI_DIE014  SOCKET4677_AZIFS054P001C01  I23
  U1     CD28  PTI_DIE001  SOCKET4677_AZIFS054P001C01  I23
  U1     BF69  PTI_DIE013  SOCKET4677_AZIFS054P001C01  I23
  U1     BD69  PTI_DIE012  SOCKET4677_AZIFS054P001C01  I23
  U1     BE70  PTI_DIE011  SOCKET4677_AZIFS054P001C01  I23
  U1     BC70  PTI_DIE010  SOCKET4677_AZIFS054P001C01  I23
  U1     BP30  PTI_DIE0015  SOCKET4677_AZIFS054P001C01  I23
  U1     BN29  PTI_DIE0014  SOCKET4677_AZIFS054P001C01  I23
  U1     BP28  PTI_DIE0013  SOCKET4677_AZIFS054P001C01  I23
  U1     BN27  PTI_DIE0012  SOCKET4677_AZIFS054P001C01  I23
  U1     BT30  PTI_DIE0011  SOCKET4677_AZIFS054P001C01  I23
  U1     BU29  PTI_DIE0010  SOCKET4677_AZIFS054P001C01  I23
  U1     CC29  PTI_DIE000  SOCKET4677_AZIFS054P001C01  I23
  U1     BK67  PTI_DIE01_STB_1  SOCKET4677_AZIFS054P001C01  I23
  U1     BF67  PTI_DIE01_STB_0  SOCKET4677_AZIFS054P001C01  I23
  U1     BY28  PTI_DIE00_STB_1  SOCKET4677_AZIFS054P001C01  I23
  U1     CB30  PTI_DIE00_STB_0  SOCKET4677_AZIFS054P001C01  I23
  U2     CD28  PTI_DIE001  SOCKET4677_AZIFS054P001C01   I1
  U2     BT28  PTI_DIE009  SOCKET4677_AZIFS054P001C01   I1
  U2     BU27  PTI_DIE008  SOCKET4677_AZIFS054P001C01   I1
  U2     BV28  PTI_DIE007  SOCKET4677_AZIFS054P001C01   I1
  U2     CA27  PTI_DIE006  SOCKET4677_AZIFS054P001C01   I1
  U2     BV30  PTI_DIE005  SOCKET4677_AZIFS054P001C01   I1
  U2     CA29  PTI_DIE004  SOCKET4677_AZIFS054P001C01   I1
  U2     BY30  PTI_DIE003  SOCKET4677_AZIFS054P001C01   I1
  U2     BN66  PTI_DIE0115  SOCKET4677_AZIFS054P001C01   I1
  U2     BM67  PTI_DIE0114  SOCKET4677_AZIFS054P001C01   I1
  U2     CC27  PTI_DIE002  SOCKET4677_AZIFS054P001C01   I1
  U2     BL66  PTI_DIE0113  SOCKET4677_AZIFS054P001C01   I1
  U2     BJ66  PTI_DIE0112  SOCKET4677_AZIFS054P001C01   I1
  U2     BG66  PTI_DIE0111  SOCKET4677_AZIFS054P001C01   I1
  U2     BN68  PTI_DIE0110  SOCKET4677_AZIFS054P001C01   I1
  U2     BM69  PTI_DIE019  SOCKET4677_AZIFS054P001C01   I1
  U2     BK69  PTI_DIE018  SOCKET4677_AZIFS054P001C01   I1
  U2     BD67  PTI_DIE017  SOCKET4677_AZIFS054P001C01   I1
  U2     BG68  PTI_DIE016  SOCKET4677_AZIFS054P001C01   I1
  U2     BC68  PTI_DIE015  SOCKET4677_AZIFS054P001C01   I1
  U2     BH69  PTI_DIE014  SOCKET4677_AZIFS054P001C01   I1
  U2     BF69  PTI_DIE013  SOCKET4677_AZIFS054P001C01   I1
  U2     BD69  PTI_DIE012  SOCKET4677_AZIFS054P001C01   I1
  U2     BE70  PTI_DIE011  SOCKET4677_AZIFS054P001C01   I1
  U2     BC70  PTI_DIE010  SOCKET4677_AZIFS054P001C01   I1
  U2     BP30  PTI_DIE0015  SOCKET4677_AZIFS054P001C01   I1
  U2     BN29  PTI_DIE0014  SOCKET4677_AZIFS054P001C01   I1
  U2     BP28  PTI_DIE0013  SOCKET4677_AZIFS054P001C01   I1
  U2     BN27  PTI_DIE0012  SOCKET4677_AZIFS054P001C01   I1
  U2     BT30  PTI_DIE0011  SOCKET4677_AZIFS054P001C01   I1
  U2     BU29  PTI_DIE0010  SOCKET4677_AZIFS054P001C01   I1
  U2     BK67  PTI_DIE01_STB_1  SOCKET4677_AZIFS054P001C01   I1
  U2     BF67  PTI_DIE01_STB_0  SOCKET4677_AZIFS054P001C01   I1
  U2     BY28  PTI_DIE00_STB_1  SOCKET4677_AZIFS054P001C01   I1
  U2     CB30  PTI_DIE00_STB_0  SOCKET4677_AZIFS054P001C01   I1
  U2     CC29  PTI_DIE000  SOCKET4677_AZIFS054P001C01   I1
  J41    OCP_B13  GND_OCP_B13  SCONN168_623403212  I115
  J41    OCP_B14  RBT_CRS_DV  SCONN168_623403212  I115
  J41    OCP_B11  REFCLKN2  SCONN168_623403212  I115
  U2     BA68  SPI_OE_N  SOCKET4677_AZIFS054P001C01   I1
  U2     BD61  SPI_IO_3  SOCKET4677_AZIFS054P001C01   I1
  U2     BD65  SPI_IO_2  SOCKET4677_AZIFS054P001C01   I1
  U2     AW64  SPI_MISO_IO1  SOCKET4677_AZIFS054P001C01   I1
  U2     BA62  SPI_MOSI_IO0  SOCKET4677_AZIFS054P001C01   I1
  U2     AV63  SPI_CS1_N  SOCKET4677_AZIFS054P001C01   I1
  U2     BB61  SPI_CS0_N  SOCKET4677_AZIFS054P001C01   I1
  U2     BC64  SPI_CLK  SOCKET4677_AZIFS054P001C01   I1
  U2     BB67  SPI_TPM_OE_N  SOCKET4677_AZIFS054P001C01   I1
  U2     AY61  SPI_TPM_MISO_IO1  SOCKET4677_AZIFS054P001C01   I1
  U2     BA66  SPI_TPM_MOSI_IO0  SOCKET4677_AZIFS054P001C01   I1
  U2     AY67  SPI_TPM_CS0_N  SOCKET4677_AZIFS054P001C01   I1
  U2     AU62  SPI_TPM_CLK  SOCKET4677_AZIFS054P001C01   I1
  J41    B48  PETP9  SCONN168_623403212  I115
  J41    B47  PETN9  SCONN168_623403212  I115
  J41    B46  GND_B46  SCONN168_623403212  I115
  J41    B45  PETP8  SCONN168_623403212  I115
  J41    B44  PETN8  SCONN168_623403212  I115
  J41    B43  GND_B43  SCONN168_623403212  I115
  U31      5     EN  PCA9617ADP  I37
  U30      5     EN  PCA9617ADP  I28
  U29      5     EN  PCA9617ADP  I43
  U28      5     EN  PCA9617ADP  I39
  J34     B9  DUALPORTEN_N  SCONN84_123318136  I43
  J34    A10  LED_ACTIVITYA10  SCONN84_123318136  I43
  J33     B9  DUALPORTEN_N  SCONN84_123318136  I53
  J33    A10  LED_ACTIVITYA10  SCONN84_123318136  I53
  U4     AK8  SLP_LAN_N  EMMITSBURG_REV0P9  I36
  U1     CD65  GSXRESET_N  SOCKET4677_AZIFS054P001C01   I5
  U1     CF65  GSXDOUT  SOCKET4677_AZIFS054P001C01   I5
  U1     CJ66  GSXDLOAD  SOCKET4677_AZIFS054P001C01   I5
  U1     CH63  GSXDIN  SOCKET4677_AZIFS054P001C01   I5
  U1     CF63  GSXSCLK  SOCKET4677_AZIFS054P001C01   I5
  U2     CD65  GSXRESET_N  SOCKET4677_AZIFS054P001C01   I1
  U2     CF65  GSXDOUT  SOCKET4677_AZIFS054P001C01   I1
  U2     CJ66  GSXDLOAD  SOCKET4677_AZIFS054P001C01   I1
  U2     CH63  GSXDIN  SOCKET4677_AZIFS054P001C01   I1
  U2     CF63  GSXSCLK  SOCKET4677_AZIFS054P001C01   I1
  U4     BA36  GPP_E_17_ERR0_N  EMMITSBURG_REV0P9  I22
  U2     BG64  ESPI_RESET_N  SOCKET4677_AZIFS054P001C01   I1
  PR452    2      B  Q_RES       I263
  PR450    2      B  Q_RES       I82
  U4      M8  PLTRST_CPU_N  EMMITSBURG_REV0P9  I36
  J43      7      7  CONN10_G2100HT0038071  I42
  J43      6      6  CONN10_G2100HT0038071  I42
  J41    B68   RFU1  SCONN168_623403212  I115
  J41    B65  PETN15  SCONN168_623403212  I115
  J41    B62  PETN14  SCONN168_623403212  I115
  J41    B69   RFU2  SCONN168_623403212  I115
  J41    B66  PETP15  SCONN168_623403212  I115
  J41    B63  PETP14  SCONN168_623403212  I115
  J41    A68  USB_DATN  SCONN168_623403212  I115
  J41    A65  PERN15  SCONN168_623403212  I115
  J41    A62  PERN14  SCONN168_623403212  I115
  J41    A69  USB_DATP  SCONN168_623403212  I115
  J41    A66  PERP15  SCONN168_623403212  I115
  J41    A63  PERP14  SCONN168_623403212  I115
  U4     AJ13  SLP_S5_N  EMMITSBURG_REV0P9  I36
  U4     AM11  SLP_A_N  EMMITSBURG_REV0P9  I36
  U4     BB43  RSVD_BB43  EMMITSBURG_REV0P9   I4
  U4     P18  RSVD_P18  EMMITSBURG_REV0P9   I4
  U4      A4  RSVD_A4  EMMITSBURG_REV0P9   I4
  U4      F1  RSVD_F1  EMMITSBURG_REV0P9   I4
  U4     J23  RSVD_J23  EMMITSBURG_REV0P9  I78
  U4     H24  RSVD_H24  EMMITSBURG_REV0P9  I78
  U4     AF15  RSVD_AF15  EMMITSBURG_REV0P9  I11
  U4     AN26  RSVD_AN26  EMMITSBURG_REV0P9  I11
  U4     L13  RSVD_L13  EMMITSBURG_REV0P9   I4
  U4     N13  RSVD_N13  EMMITSBURG_REV0P9   I4
  U4      H1  RSVD_H1  EMMITSBURG_REV0P9   I4
  U4      J2  GPPC_H_15_FLEX_CLK_OUT_0  EMMITSBURG_REV0P9  I22
  U4     AJ7  LANPHYPC  EMMITSBURG_REV0P9  I36
  U4     V11  GPP_N_4  EMMITSBURG_REV0P9  I27
  U4     T11  GPP_N_1  EMMITSBURG_REV0P9  I27
  U4      V4  GPP_I_17_HDA_SDI_1  EMMITSBURG_REV0P9  I22
  U4      U1  GPP_I_16_HDA_SDI_0  EMMITSBURG_REV0P9  I22
  U4      R2  GPP_I_15_HDA_SDO  EMMITSBURG_REV0P9  I22
  U4     BA32  GPP_E_13_SATA1_SDATAOUT_SATA1_DEVSLP  EMMITSBURG_REV0P9  I22
  U4     BB28  GPP_E_12_SATA1_SLOAD_SATA1_GP  EMMITSBURG_REV0P9  I22
  U4     AV34  GPP_E_11_SATA1_SCLOCK_SATA1_LED_N  EMMITSBURG_REV0P9  I22
  U4     AG3  GPP_D_20_CATERR_N  EMMITSBURG_REV0P9  I93
  U4     AD2  GPP_D_2_HS_SMBALERT_N_DMA_SMBALERT_N  EMMITSBURG_REV0P9  I93
  U4     AT3  GPPC_C_5_ME_SML0BALERT_N  EMMITSBURG_REV0P9  I93
  U4     BE14  GPPC_A_15_SRCCLKREQ_N_5  EMMITSBURG_REV0P9  I93
  U4     BE12  GPPC_A_14_SRCCLKREQ_N_4  EMMITSBURG_REV0P9  I93
  U4     BF15  GPPC_A_13_SRCCLKREQ_N_3  EMMITSBURG_REV0P9  I93
  U4     BG18  GPPC_A_11_SRCCLKREQ_N_1  EMMITSBURG_REV0P9  I93
  U4     BD17  GPPC_A_10_SRCCLKREQ_N_0  EMMITSBURG_REV0P9  I93
  U4     BG14  GPPC_A_19_SRCCLKREQ_N_9  EMMITSBURG_REV0P9  I93
  U4     BF11  GPPC_A_18_SRCCLKREQ_N_8  EMMITSBURG_REV0P9  I93
  U4     F11  CPU_MSMI_N  EMMITSBURG_REV0P9  I36
  U4      E4  CPU_MEMTRIP_N  EMMITSBURG_REV0P9  I36
  U4     BG3  NC_CGC_DUT_DETECT_N  EMMITSBURG_REV0P9  I27
  U130     7    P03  PCA9555PW    I1
  U130     4    P00  PCA9555PW    I1
  U131    20    P17  PCA9555PW   I51
  U131    19    P16  PCA9555PW   I51
  U131    18    P15  PCA9555PW   I51
  U131    16    P13  PCA9555PW   I51
  U131    13    P10  PCA9555PW   I51
  U131    11    P07  PCA9555PW   I51
  U131    10    P06  PCA9555PW   I51
  U131     9    P05  PCA9555PW   I51
  U131     7    P03  PCA9555PW   I51
  U131     4    P00  PCA9555PW   I51
  U131     1   INT*  PCA9555PW   I51
  U130    20    P17  PCA9555PW    I1
  U130    19    P16  PCA9555PW    I1
  U130    18    P15  PCA9555PW    I1
  U130    16    P13  PCA9555PW    I1
  U130    13    P10  PCA9555PW    I1
  U130    11    P07  PCA9555PW    I1
  U130    10    P06  PCA9555PW    I1
  U130     9    P05  PCA9555PW    I1
  U130     1   INT*  PCA9555PW    I1
  U51     20    P17  PCA9555PW   I125
  U51     19    P16  PCA9555PW   I125
  U51     18    P15  PCA9555PW   I125
  U51     17    P14  PCA9555PW   I125
  U51     16    P13  PCA9555PW   I125
  U51     15    P12  PCA9555PW   I125
  U51     14    P11  PCA9555PW   I125
  U51     13    P10  PCA9555PW   I125
  U51     11    P07  PCA9555PW   I125
  U51     10    P06  PCA9555PW   I125
  U51      5    P01  PCA9555PW   I125
  U51      4    P00  PCA9555PW   I125
  U4     AG36  SATA_7_PCIE3_7_USB3_7_TXP  EMMITSBURG_REV0P9  I119
  U4     AH37  SATA_6_PCIE3_6_USB3_6_TXP  EMMITSBURG_REV0P9  I119
  U4     AJ32  SATA_5_PCIE3_5_USB3_5_TXP  EMMITSBURG_REV0P9  I119
  U4     AF34  SATA_7_PCIE3_7_USB3_7_TXN  EMMITSBURG_REV0P9  I119
  U4     AF37  SATA_6_PCIE3_6_USB3_6_TXN  EMMITSBURG_REV0P9  I119
  U4     AH34  SATA_5_PCIE3_5_USB3_5_TXN  EMMITSBURG_REV0P9  I119
  U4     V42  SATA_7_PCIE3_7_USB3_7_RXP  EMMITSBURG_REV0P9  I119
  U4     W43  SATA_6_PCIE3_6_USB3_6_RXP  EMMITSBURG_REV0P9  I119
  U4     Y42  SATA_5_PCIE3_5_USB3_5_RXP  EMMITSBURG_REV0P9  I119
  U4     V40  SATA_7_PCIE3_7_USB3_7_RXN  EMMITSBURG_REV0P9  I119
  U4     W41  SATA_6_PCIE3_6_USB3_6_RXN  EMMITSBURG_REV0P9  I119
  U4     Y40  SATA_5_PCIE3_5_USB3_5_RXN  EMMITSBURG_REV0P9  I119
  U4     N36  SATA_15_PCIE3_15_TXP  EMMITSBURG_REV0P9  I119
  U4     P34  SATA_15_PCIE3_15_TXN  EMMITSBURG_REV0P9  I119
  U4     G42  SATA_15_PCIE3_15_RXP  EMMITSBURG_REV0P9  I119
  U4     G40  SATA_15_PCIE3_15_RXN  EMMITSBURG_REV0P9  I119
  U4     T34  SATA_14_PCIE3_14_GBE_2_TXP  EMMITSBURG_REV0P9  I119
  U4     R32  SATA_14_PCIE3_14_GBE_2_TXN  EMMITSBURG_REV0P9  I119
  U4     H43  SATA_14_PCIE3_14_GBE_2_RXP  EMMITSBURG_REV0P9  I119
  U4     H41  SATA_14_PCIE3_14_GBE_2_RXN  EMMITSBURG_REV0P9  I119
  U4     W32  SATA_13_PCIE3_13_TXP  EMMITSBURG_REV0P9  I119
  U4     U32  SATA_13_PCIE3_13_TXN  EMMITSBURG_REV0P9  I119
  U4     J42  SATA_13_PCIE3_13_RXP  EMMITSBURG_REV0P9  I119
  U4     J40  SATA_13_PCIE3_13_RXN  EMMITSBURG_REV0P9  I119
  U4     U36  SATA_12_PCIE3_12_GBE_1_TXP  EMMITSBURG_REV0P9  I119
  U4     V34  SATA_12_PCIE3_12_GBE_1_TXN  EMMITSBURG_REV0P9  I119
  U4     K43  SATA_12_PCIE3_12_GBE_1_RXP  EMMITSBURG_REV0P9  I119
  U4     K41  SATA_12_PCIE3_12_GBE_1_RXN  EMMITSBURG_REV0P9  I119
  J37    B69   RFU2  SCONN168_623403212  I86
  J37    B68   RFU1  SCONN168_623403212  I86
  U77     13    4OE  74CBTLV3126PW  I105
  U77     11     4B  74CBTLV3126PW  I105
  U77     12     4A  74CBTLV3126PW  I105
  U81     18  VTEMP  MP5981GLUZ  I66
  U107    18  VTEMP  MP5981GLUZ  I113
  U122    V9  DIFFIO_TX_RX_B12N  10M04SAU324I7G  I155
  U122   V12  DIFFIO_RX_B17N  10M04SAU324I7G  I93
  U122   V11  DIFFIO_RX_B15P  10M04SAU324I7G  I93
  U122   V10  DIFFIO_RX_B15N  10M04SAU324I7G  I93
  U122    U9  DIFFIO_TX_RX_B12P  10M04SAU324I7G  I155
  U122    U8  DIFFIO_RX_B13N  10M04SAU324I7G  I93
  U122   C18  DIFFIO_RX_R32P  10M04SAU324I7G  I93
  U1     CV22  CPLD_TMS  SOCKET4677_AZIFS054P001C01   I5
  U1     CP22  CPLD_TDO  SOCKET4677_AZIFS054P001C01   I5
  U1     CT22  CPLD_TDI  SOCKET4677_AZIFS054P001C01   I5
  U83     10     A2  GTL2014PW   I45
  U83     13     A0  GTL2014PW   I45
  U86     11     4B  74CBTLV3126PW  I84
  U86      3     1B  74CBTLV3126PW  I84
  U65      3  ALERT  TMP75AIDR   I84
  U63      3  ALERT  TMP75AIDR    I1
  JP8      3      3  CONN3_HFK1030G000LAF  I86
  U2     CW21  PLT_SLP_S5_N  SOCKET4677_AZIFS054P001C01   I1
  U2     CN21  PLT_SLP_S4_N  SOCKET4677_AZIFS054P001C01   I1
  U2     CR21  PLT_SLP_S3_N  SOCKET4677_AZIFS054P001C01   I1
  U2     CL21  PLT_PLTRST_SYNC_N  SOCKET4677_AZIFS054P001C01   I1
  U2     CJ21  PLT_GLB_RST_WARN_N  SOCKET4677_AZIFS054P001C01   I1
  U1     BC25  I3C_MNG_SDA  SOCKET4677_AZIFS054P001C01   I5
  U1     BE25  I3C_MNG_SCL  SOCKET4677_AZIFS054P001C01   I5
  U2     BC25  I3C_MNG_SDA  SOCKET4677_AZIFS054P001C01   I1
  U2     BE25  I3C_MNG_SCL  SOCKET4677_AZIFS054P001C01   I1
  U1     CJ23  I2C_RTC_SDA  SOCKET4677_AZIFS054P001C01   I5
  U1     CL23  I2C_RTC_SCL  SOCKET4677_AZIFS054P001C01   I5
  U1     CJ25  I2C_RTC_ALERT_N  SOCKET4677_AZIFS054P001C01   I5
  U2     CJ23  I2C_RTC_SDA  SOCKET4677_AZIFS054P001C01   I1
  U2     CL23  I2C_RTC_SCL  SOCKET4677_AZIFS054P001C01   I1
  U2     CJ25  I2C_RTC_ALERT_N  SOCKET4677_AZIFS054P001C01   I1
  U1     CF24  PMSYNC6  SOCKET4677_AZIFS054P001C01  I29
  U1     CC25  PMDOWN6  SOCKET4677_AZIFS054P001C01  I29
  U2     CF24  PMSYNC6  SOCKET4677_AZIFS054P001C01   I1
  U2     CC25  PMDOWN6  SOCKET4677_AZIFS054P001C01   I1
  U1     CH24  PMSYNC5  SOCKET4677_AZIFS054P001C01  I29
  U1     CE23  PMDOWN5  SOCKET4677_AZIFS054P001C01  I29
  U2     CH24  PMSYNC5  SOCKET4677_AZIFS054P001C01   I1
  U2     CE23  PMDOWN5  SOCKET4677_AZIFS054P001C01   I1
  U1     CR19  PMSYNC4  SOCKET4677_AZIFS054P001C01  I29
  U1     CV18  PMDOWN4  SOCKET4677_AZIFS054P001C01  I29
  U2     CR19  PMSYNC4  SOCKET4677_AZIFS054P001C01   I1
  U2     CV18  PMDOWN4  SOCKET4677_AZIFS054P001C01   I1
  U1     CE25  PMSYNC3  SOCKET4677_AZIFS054P001C01  I29
  U1     CD24  PMDOWN3  SOCKET4677_AZIFS054P001C01  I29
  U2     CE25  PMSYNC3  SOCKET4677_AZIFS054P001C01   I1
  U2     CD24  PMDOWN3  SOCKET4677_AZIFS054P001C01   I1
  U1     CH26  PMSYNC2  SOCKET4677_AZIFS054P001C01  I29
  U1     CM26  PMDOWN2  SOCKET4677_AZIFS054P001C01  I29
  U2     CH26  PMSYNC2  SOCKET4677_AZIFS054P001C01   I1
  U2     CM26  PMDOWN2  SOCKET4677_AZIFS054P001C01   I1
  U1     CL25  PMSYNC1  SOCKET4677_AZIFS054P001C01  I29
  U1     CP26  PMDOWN1  SOCKET4677_AZIFS054P001C01  I29
  U2     CL25  PMSYNC1  SOCKET4677_AZIFS054P001C01   I1
  U2     CP26  PMDOWN1  SOCKET4677_AZIFS054P001C01   I1
  U1     DA39  PMSYNC_PCH  SOCKET4677_AZIFS054P001C01  I29
  U1     CY40  PMDOWN_PCH  SOCKET4677_AZIFS054P001C01  I29
  J41    OCP_B8  RBT_RXD1  SCONN168_623403212  I115
  J41    OCP_B9  RBT_RXD0  SCONN168_623403212  I115
  U4     AB11  GPP_M_7  EMMITSBURG_REV0P9  I22
  U4     R10  GPP_M_6  EMMITSBURG_REV0P9  I22
  U4     AA13  GPP_M_1  EMMITSBURG_REV0P9  I22
  U4      N7  GPP_M_0  EMMITSBURG_REV0P9  I22
  U4     BB34  GPP_E_14_SATA2_SCLOCK_SATA2_LED_N  EMMITSBURG_REV0P9  I22
  U1     AW19  PLT_WAKE_N  SOCKET4677_AZIFS054P001C01   I5
  U1     CK22  PLT_SYS_RESET_N  SOCKET4677_AZIFS054P001C01   I5
  U2     AW19  PLT_WAKE_N  SOCKET4677_AZIFS054P001C01   I1
  U2     CK22  PLT_SYS_RESET_N  SOCKET4677_AZIFS054P001C01   I1
  U1     CW21  PLT_SLP_S5_N  SOCKET4677_AZIFS054P001C01   I5
  U1     CN21  PLT_SLP_S4_N  SOCKET4677_AZIFS054P001C01   I5
  U1     CR21  PLT_SLP_S3_N  SOCKET4677_AZIFS054P001C01   I5
  U1     CK24  PLT_PWRBUTTON_N  SOCKET4677_AZIFS054P001C01   I5
  U2     CT24  ADR_TRIGGER  SOCKET4677_AZIFS054P001C01   I1
  U2     CP24  ADR_COMPLETE  SOCKET4677_AZIFS054P001C01   I1
  U2     CN23  ADR_ACK  SOCKET4677_AZIFS054P001C01   I1
  U1     AV59  MAS_EXT_BGREF  SOCKET4677_AZIFS054P001C01  I29
  U2     AV59  MAS_EXT_BGREF  SOCKET4677_AZIFS054P001C01   I1
  U2     BH63  ESPI_OE_N  SOCKET4677_AZIFS054P001C01   I1
  U2     BM63  ESPI_IO_3  SOCKET4677_AZIFS054P001C01   I1
  U2     AU64  ESPI_IO_2  SOCKET4677_AZIFS054P001C01   I1
  U2     BJ64  ESPI_IO_1  SOCKET4677_AZIFS054P001C01   I1
  U2     BK63  ESPI_IO_0  SOCKET4677_AZIFS054P001C01   I1
  U2     BH65  ESPI_CS1_N  SOCKET4677_AZIFS054P001C01   I1
  U2     BF65  ESPI_CS0_N  SOCKET4677_AZIFS054P001C01   I1
  U2     BD63  ESPI_ALERT1_N  SOCKET4677_AZIFS054P001C01   I1
  U2     BE62  ESPI_ALERT0_N  SOCKET4677_AZIFS054P001C01   I1
  J35    A18  SIGNAL_A18  SCONN140_G64V3431BHR  I64
  J93     B8    RFU  CONN56_ME2005602311011  I123
  J93     B7    MFG  CONN56_ME2005602311011  I123
  J92     B8    RFU  CONN56_ME2005602311011  I105
  J92     B7    MFG  CONN56_ME2005602311011  I105
  J91     B8    RFU  CONN56_ME2005602311011  I123
  J91     B7    MFG  CONN56_ME2005602311011  I123
  J90     B8    RFU  CONN56_ME2005602311011  I105
  J90     B7    MFG  CONN56_ME2005602311011  I105
  U1     CM18  DMI_TX_DP7  SOCKET4677_AZIFS054P001C01  I20
  U1     CL19  DMI_TX_DP6  SOCKET4677_AZIFS054P001C01  I20
  U1     CH18  DMI_TX_DP5  SOCKET4677_AZIFS054P001C01  I20
  U1     CG19  DMI_TX_DP4  SOCKET4677_AZIFS054P001C01  I20
  U1     CD18  DMI_TX_DP3  SOCKET4677_AZIFS054P001C01  I20
  U1     CC19  DMI_TX_DP2  SOCKET4677_AZIFS054P001C01  I20
  U1     BY18  DMI_TX_DP1  SOCKET4677_AZIFS054P001C01  I20
  U1     CA19  DMI_TX_DP0  SOCKET4677_AZIFS054P001C01  I20
  U1     CN17  DMI_TX_DN7  SOCKET4677_AZIFS054P001C01  I20
  U1     CK18  DMI_TX_DN6  SOCKET4677_AZIFS054P001C01  I20
  U1     CJ17  DMI_TX_DN5  SOCKET4677_AZIFS054P001C01  I20
  U1     CF18  DMI_TX_DN4  SOCKET4677_AZIFS054P001C01  I20
  U1     CE17  DMI_TX_DN3  SOCKET4677_AZIFS054P001C01  I20
  U1     CB18  DMI_TX_DN2  SOCKET4677_AZIFS054P001C01  I20
  U1     CA17  DMI_TX_DN1  SOCKET4677_AZIFS054P001C01  I20
  U1     BW19  DMI_TX_DN0  SOCKET4677_AZIFS054P001C01  I20
  U1     BT18  DMI_RX_DP7  SOCKET4677_AZIFS054P001C01  I20
  U1     BR19  DMI_RX_DP6  SOCKET4677_AZIFS054P001C01  I20
  U1     BM18  DMI_RX_DP5  SOCKET4677_AZIFS054P001C01  I20
  U1     BL19  DMI_RX_DP4  SOCKET4677_AZIFS054P001C01  I20
  U1     BH18  DMI_RX_DP3  SOCKET4677_AZIFS054P001C01  I20
  U1     BG19  DMI_RX_DP2  SOCKET4677_AZIFS054P001C01  I20
  U1     BD18  DMI_RX_DP1  SOCKET4677_AZIFS054P001C01  I20
  U1     BC19  DMI_RX_DP0  SOCKET4677_AZIFS054P001C01  I20
  U1     BU17  DMI_RX_DN7  SOCKET4677_AZIFS054P001C01  I20
  U1     BP18  DMI_RX_DN6  SOCKET4677_AZIFS054P001C01  I20
  U1     BN17  DMI_RX_DN5  SOCKET4677_AZIFS054P001C01  I20
  U1     BK18  DMI_RX_DN4  SOCKET4677_AZIFS054P001C01  I20
  U1     BJ17  DMI_RX_DN3  SOCKET4677_AZIFS054P001C01  I20
  U1     BF18  DMI_RX_DN2  SOCKET4677_AZIFS054P001C01  I20
  U1     BE17  DMI_RX_DN1  SOCKET4677_AZIFS054P001C01  I20
  U1     BB18  DMI_RX_DN0  SOCKET4677_AZIFS054P001C01  I20
  U1     CL66  SSC_SYNC  SOCKET4677_AZIFS054P001C01   I5
  U1     CH61  OVERCLK_BCLK0_DP  SOCKET4677_AZIFS054P001C01   I2
  U1     CK61  OVERCLK_BCLK1_DN  SOCKET4677_AZIFS054P001C01   I2
  U1     CL60  OVERCLK_BCLK1_DP  SOCKET4677_AZIFS054P001C01   I2
  U1     CW43  SPARE_3  SOCKET4677_AZIFS054P001C01   I2
  U1     AU52  SPARE_1  SOCKET4677_AZIFS054P001C01   I2
  U1     DA70  SPARE_0  SOCKET4677_AZIFS054P001C01   I2
  U1     BD77  SPARE_10  SOCKET4677_AZIFS054P001C01   I2
  U1     CL70  SPARE_5  SOCKET4677_AZIFS054P001C01   I2
  U1     CD69  OVERCLK_ENABLE  SOCKET4677_AZIFS054P001C01   I2
  U1     CG60  OVERCLK_BCLK0_DN  SOCKET4677_AZIFS054P001C01   I2
  U1     J13  SMBALERT_N  SOCKET4677_AZIFS054P001C01   I2
  U1     BF24  IFST_TRIG  SOCKET4677_AZIFS054P001C01  I16
  U1     BE23  IFST_KOT  SOCKET4677_AZIFS054P001C01  I16
  U1     BC23  IFST_DONE  SOCKET4677_AZIFS054P001C01  I16
  U1     CJ21  PLT_GLB_RST_WARN_N  SOCKET4677_AZIFS054P001C01   I5
  U1     BE21  DIE_HVM  SOCKET4677_AZIFS054P001C01   I1
  U1     H12  A0_DEBUG  SOCKET4677_AZIFS054P001C01  I16
  U2     CL66  SSC_SYNC  SOCKET4677_AZIFS054P001C01   I1
  U2     CH61  OVERCLK_BCLK0_DP  SOCKET4677_AZIFS054P001C01   I1
  U2     CK61  OVERCLK_BCLK1_DN  SOCKET4677_AZIFS054P001C01   I1
  U2     CL60  OVERCLK_BCLK1_DP  SOCKET4677_AZIFS054P001C01   I1
  U2     CW43  SPARE_3  SOCKET4677_AZIFS054P001C01   I1
  U2     AU52  SPARE_1  SOCKET4677_AZIFS054P001C01   I1
  U2     DA70  SPARE_0  SOCKET4677_AZIFS054P001C01   I1
  U2     BD77  SPARE_10  SOCKET4677_AZIFS054P001C01   I1
  U2     CL70  SPARE_5  SOCKET4677_AZIFS054P001C01   I1
  U2     CD69  OVERCLK_ENABLE  SOCKET4677_AZIFS054P001C01   I1
  U2     CG60  OVERCLK_BCLK0_DN  SOCKET4677_AZIFS054P001C01   I1
  U2     CK24  PLT_PWRBUTTON_N  SOCKET4677_AZIFS054P001C01   I1
  U2     DA52  PROCDIS_N  SOCKET4677_AZIFS054P001C01  I57
  U2     J13  SMBALERT_N  SOCKET4677_AZIFS054P001C01   I1
  U2     BF24  IFST_TRIG  SOCKET4677_AZIFS054P001C01   I1
  U2     BE23  IFST_KOT  SOCKET4677_AZIFS054P001C01   I1
  U2     BC23  IFST_DONE  SOCKET4677_AZIFS054P001C01   I1
  U2     BE21  DIE_HVM  SOCKET4677_AZIFS054P001C01   I1
  U2     H12  A0_DEBUG  SOCKET4677_AZIFS054P001C01   I1
  U13     A8  PFT_IN  9SQ440NQQI8  I180
  U13     A9  PFT_IN#  9SQ440NQQI8  I180
  U13     A6  PFT_OUT  9SQ440NQQI8  I180
  U13     A7  PFT_OUT#  9SQ440NQQI8  I180
  U2     BG62  ESPI_CLK  SOCKET4677_AZIFS054P001C01   I1
  U90      8     Y3  PI6CV304LE  I46
  U90      7     Y2  PI6CV304LE  I46
  U4     D15  CLKOUT_SRC_P_9  EMMITSBURG_REV0P9  I78
  U4     B15  CLKOUT_SRC_N_9  EMMITSBURG_REV0P9  I78
  U4     H18  CLKOUT_SRC_P_8  EMMITSBURG_REV0P9  I78
  U4     F18  CLKOUT_SRC_N_8  EMMITSBURG_REV0P9  I78
  U4     C14  CLKOUT_SRC_P_7  EMMITSBURG_REV0P9  I78
  U4     A14  CLKOUT_SRC_N_7  EMMITSBURG_REV0P9  I78
  U4     C12  CLKOUT_SRC_P_5  EMMITSBURG_REV0P9  I78
  U4     A12  CLKOUT_SRC_N_5  EMMITSBURG_REV0P9  I78
  U4     D19  CLKOUT_SRC_P_4  EMMITSBURG_REV0P9  I78
  U4     B19  CLKOUT_SRC_N_4  EMMITSBURG_REV0P9  I78
  U4     D17  CLKOUT_SRC_P_3  EMMITSBURG_REV0P9  I78
  U4     B17  CLKOUT_SRC_N_3  EMMITSBURG_REV0P9  I78
  U4     F21  CLKOUT_SRC_P_1  EMMITSBURG_REV0P9  I78
  U4     G23  CLKOUT_SRC_N_1  EMMITSBURG_REV0P9  I78
  U4     C18  CLKOUT_SRC_P_16  EMMITSBURG_REV0P9  I78
  U4     A18  CLKOUT_SRC_N_16  EMMITSBURG_REV0P9  I78
  U4      C6  CLKOUT_SRC_P_15  EMMITSBURG_REV0P9  I78
  U4      B5  CLKOUT_SRC_N_15  EMMITSBURG_REV0P9  I78
  U4      D7  CLKOUT_SRC_P_14  EMMITSBURG_REV0P9  I78
  U4      B7  CLKOUT_SRC_N_14  EMMITSBURG_REV0P9  I78
  U4      C8  CLKOUT_SRC_P_13  EMMITSBURG_REV0P9  I78
  U4      A8  CLKOUT_SRC_N_13  EMMITSBURG_REV0P9  I78
  U4     C10  CLKOUT_SRC_P_12  EMMITSBURG_REV0P9  I78
  U4     A10  CLKOUT_SRC_N_12  EMMITSBURG_REV0P9  I78
  U4     H15  CLKOUT_SRC_P_11  EMMITSBURG_REV0P9  I78
  U4     G16  CLKOUT_SRC_N_11  EMMITSBURG_REV0P9  I78
  U4     K18  CLKOUT_SRC_P_10  EMMITSBURG_REV0P9  I78
  U4     J16  CLKOUT_SRC_N_10  EMMITSBURG_REV0P9  I78
  U4     C16  CLKOUT_SRC_P_0  EMMITSBURG_REV0P9  I78
  U4     A16  CLKOUT_SRC_N_0  EMMITSBURG_REV0P9  I78
  J88    A15  REFCLKP1  SCONN84_123318136  I16
  J88    A14  REFCLKN1  SCONN84_123318136  I16
  J34    A15  REFCLKP1  SCONN84_123318136  I43
  J34    A14  REFCLKN1  SCONN84_123318136  I43
  J33    A15  REFCLKP1  SCONN84_123318136  I53
  J33    A14  REFCLKN1  SCONN84_123318136  I53
  J93    A15  REFCLKP1  CONN56_ME2005602311011  I123
  J93    A14  REFCLKN1  CONN56_ME2005602311011  I123
  J92    A15  REFCLKP1  CONN56_ME2005602311011  I105
  J92    A14  REFCLKN1  CONN56_ME2005602311011  I105
  J91    A15  REFCLKP1  CONN56_ME2005602311011  I123
  J91    A14  REFCLKN1  CONN56_ME2005602311011  I123
  J90    A15  REFCLKP1  CONN56_ME2005602311011  I105
  J90    A14  REFCLKN1  CONN56_ME2005602311011  I105
  U13    A53  SBI_OUT  9SQ440NQQI8  I180
  J32    232   RFU6  SCONN288_ADR50001P003C01  I179
  J32    231   RFU5  SCONN288_ADR50001P003C01  I179
  J32    220   RFU4  SCONN288_ADR50001P003C01  I179
  J32    150   RFU3  SCONN288_ADR50001P003C01  I179
  J32    149   RFU2  SCONN288_ADR50001P003C01  I179
  J32    144   RFU1  SCONN288_ADR50001P003C01  I179
  J32      2   RFU0  SCONN288_ADR50001P003C01  I179
  J31    232   RFU6  SCONN288_ADR50001P013C01  I180
  J31    231   RFU5  SCONN288_ADR50001P013C01  I180
  J31    220   RFU4  SCONN288_ADR50001P013C01  I180
  J31    150   RFU3  SCONN288_ADR50001P013C01  I180
  J31    149   RFU2  SCONN288_ADR50001P013C01  I180
  J31    144   RFU1  SCONN288_ADR50001P013C01  I180
  J31      2   RFU0  SCONN288_ADR50001P013C01  I180
  J16    232   RFU6  SCONN288_ADR50001P003C01   I6
  J16    231   RFU5  SCONN288_ADR50001P003C01   I6
  J16    220   RFU4  SCONN288_ADR50001P003C01   I6
  J16    150   RFU3  SCONN288_ADR50001P003C01   I6
  J16    149   RFU2  SCONN288_ADR50001P003C01   I6
  J16    144   RFU1  SCONN288_ADR50001P003C01   I6
  J16      2   RFU0  SCONN288_ADR50001P003C01   I6
  J15    232   RFU6  SCONN288_ADR50001P013C01  I48
  J15    231   RFU5  SCONN288_ADR50001P013C01  I48
  J15    220   RFU4  SCONN288_ADR50001P013C01  I48
  J15    150   RFU3  SCONN288_ADR50001P013C01  I48
  J15    149   RFU2  SCONN288_ADR50001P013C01  I48
  J15    144   RFU1  SCONN288_ADR50001P013C01  I48
  J15      2   RFU0  SCONN288_ADR50001P013C01  I48
  J30    232   RFU6  SCONN288_ADR50001P003C01  I179
  J30    231   RFU5  SCONN288_ADR50001P003C01  I179
  J30    220   RFU4  SCONN288_ADR50001P003C01  I179
  J30    150   RFU3  SCONN288_ADR50001P003C01  I179
  J30    149   RFU2  SCONN288_ADR50001P003C01  I179
  J30    144   RFU1  SCONN288_ADR50001P003C01  I179
  J30      2   RFU0  SCONN288_ADR50001P003C01  I179
  J29    232   RFU6  SCONN288_ADR50001P013C01  I179
  J29    231   RFU5  SCONN288_ADR50001P013C01  I179
  J29    220   RFU4  SCONN288_ADR50001P013C01  I179
  J29    150   RFU3  SCONN288_ADR50001P013C01  I179
  J29    149   RFU2  SCONN288_ADR50001P013C01  I179
  J29    144   RFU1  SCONN288_ADR50001P013C01  I179
  J29      2   RFU0  SCONN288_ADR50001P013C01  I179
  J14    232   RFU6  SCONN288_ADR50001P003C01  I47
  J14    231   RFU5  SCONN288_ADR50001P003C01  I47
  J14    220   RFU4  SCONN288_ADR50001P003C01  I47
  J14    150   RFU3  SCONN288_ADR50001P003C01  I47
  J14    149   RFU2  SCONN288_ADR50001P003C01  I47
  J14    144   RFU1  SCONN288_ADR50001P003C01  I47
  J14      2   RFU0  SCONN288_ADR50001P003C01  I47
  J13    232   RFU6  SCONN288_ADR50001P013C01  I11
  J13    231   RFU5  SCONN288_ADR50001P013C01  I11
  J13    220   RFU4  SCONN288_ADR50001P013C01  I11
  J13    150   RFU3  SCONN288_ADR50001P013C01  I11
  J13    149   RFU2  SCONN288_ADR50001P013C01  I11
  J13    144   RFU1  SCONN288_ADR50001P013C01  I11
  J13      2   RFU0  SCONN288_ADR50001P013C01  I11
  J28    232   RFU6  SCONN288_ADR50001P003C01  I47
  J28    231   RFU5  SCONN288_ADR50001P003C01  I47
  J28    220   RFU4  SCONN288_ADR50001P003C01  I47
  J28    150   RFU3  SCONN288_ADR50001P003C01  I47
  J28    149   RFU2  SCONN288_ADR50001P003C01  I47
  J28    144   RFU1  SCONN288_ADR50001P003C01  I47
  J28      2   RFU0  SCONN288_ADR50001P003C01  I47
  J27    232   RFU6  SCONN288_ADR50001P013C01  I179
  J27    231   RFU5  SCONN288_ADR50001P013C01  I179
  J27    220   RFU4  SCONN288_ADR50001P013C01  I179
  J27    150   RFU3  SCONN288_ADR50001P013C01  I179
  J27    149   RFU2  SCONN288_ADR50001P013C01  I179
  J27    144   RFU1  SCONN288_ADR50001P013C01  I179
  J27      2   RFU0  SCONN288_ADR50001P013C01  I179
  J12    232   RFU6  SCONN288_ADR50001P003C01  I24
  J12    231   RFU5  SCONN288_ADR50001P003C01  I24
  J12    220   RFU4  SCONN288_ADR50001P003C01  I24
  J12    150   RFU3  SCONN288_ADR50001P003C01  I24
  J12    149   RFU2  SCONN288_ADR50001P003C01  I24
  J12    144   RFU1  SCONN288_ADR50001P003C01  I24
  J12      2   RFU0  SCONN288_ADR50001P003C01  I24
  J11    232   RFU6  SCONN288_ADR50001P013C01  I25
  J11    231   RFU5  SCONN288_ADR50001P013C01  I25
  J11    220   RFU4  SCONN288_ADR50001P013C01  I25
  J11    150   RFU3  SCONN288_ADR50001P013C01  I25
  J11    149   RFU2  SCONN288_ADR50001P013C01  I25
  J11    144   RFU1  SCONN288_ADR50001P013C01  I25
  J11      2   RFU0  SCONN288_ADR50001P013C01  I25
  J26    232   RFU6  SCONN288_ADR50001P003C01  I180
  J26    231   RFU5  SCONN288_ADR50001P003C01  I180
  J26    220   RFU4  SCONN288_ADR50001P003C01  I180
  J26    150   RFU3  SCONN288_ADR50001P003C01  I180
  J26    149   RFU2  SCONN288_ADR50001P003C01  I180
  J26    144   RFU1  SCONN288_ADR50001P003C01  I180
  J26      2   RFU0  SCONN288_ADR50001P003C01  I180
  J25    232   RFU6  SCONN288_ADR50001P013C01  I180
  J25    231   RFU5  SCONN288_ADR50001P013C01  I180
  J25    220   RFU4  SCONN288_ADR50001P013C01  I180
  J25    150   RFU3  SCONN288_ADR50001P013C01  I180
  J25    149   RFU2  SCONN288_ADR50001P013C01  I180
  J25    144   RFU1  SCONN288_ADR50001P013C01  I180
  J25      2   RFU0  SCONN288_ADR50001P013C01  I180
  J10    232   RFU6  SCONN288_ADR50001P003C01  I13
  J10    231   RFU5  SCONN288_ADR50001P003C01  I13
  J10    220   RFU4  SCONN288_ADR50001P003C01  I13
  J10    150   RFU3  SCONN288_ADR50001P003C01  I13
  J10    149   RFU2  SCONN288_ADR50001P003C01  I13
  J10    144   RFU1  SCONN288_ADR50001P003C01  I13
  J10      2   RFU0  SCONN288_ADR50001P003C01  I13
  J9     232   RFU6  SCONN288_ADR50001P013C01  I12
  J9     231   RFU5  SCONN288_ADR50001P013C01  I12
  J9     220   RFU4  SCONN288_ADR50001P013C01  I12
  J9     150   RFU3  SCONN288_ADR50001P013C01  I12
  J9     149   RFU2  SCONN288_ADR50001P013C01  I12
  J9     144   RFU1  SCONN288_ADR50001P013C01  I12
  J9       2   RFU0  SCONN288_ADR50001P013C01  I12
  J24    232   RFU6  SCONN288_ADR50001P003C01  I178
  J24    231   RFU5  SCONN288_ADR50001P003C01  I178
  J24    220   RFU4  SCONN288_ADR50001P003C01  I178
  J24    150   RFU3  SCONN288_ADR50001P003C01  I178
  J24    149   RFU2  SCONN288_ADR50001P003C01  I178
  J24    144   RFU1  SCONN288_ADR50001P003C01  I178
  J24      2   RFU0  SCONN288_ADR50001P003C01  I178
  J23    232   RFU6  SCONN288_ADR50001P013C01  I25
  J23    231   RFU5  SCONN288_ADR50001P013C01  I25
  J23    220   RFU4  SCONN288_ADR50001P013C01  I25
  J23    150   RFU3  SCONN288_ADR50001P013C01  I25
  J23    149   RFU2  SCONN288_ADR50001P013C01  I25
  J23    144   RFU1  SCONN288_ADR50001P013C01  I25
  J23      2   RFU0  SCONN288_ADR50001P013C01  I25
  J8     232   RFU6  SCONN288_ADR50001P003C01  I50
  J8     231   RFU5  SCONN288_ADR50001P003C01  I50
  J8     220   RFU4  SCONN288_ADR50001P003C01  I50
  J8     150   RFU3  SCONN288_ADR50001P003C01  I50
  J8     149   RFU2  SCONN288_ADR50001P003C01  I50
  J8     144   RFU1  SCONN288_ADR50001P003C01  I50
  J8       2   RFU0  SCONN288_ADR50001P003C01  I50
  J7     232   RFU6  SCONN288_ADR50001P013C01  I12
  J7     231   RFU5  SCONN288_ADR50001P013C01  I12
  J7     220   RFU4  SCONN288_ADR50001P013C01  I12
  J7     150   RFU3  SCONN288_ADR50001P013C01  I12
  J7     149   RFU2  SCONN288_ADR50001P013C01  I12
  J7     144   RFU1  SCONN288_ADR50001P013C01  I12
  J7       2   RFU0  SCONN288_ADR50001P013C01  I12
  J22    232   RFU6  SCONN288_ADR50001P003C01  I51
  J22    231   RFU5  SCONN288_ADR50001P003C01  I51
  J22    220   RFU4  SCONN288_ADR50001P003C01  I51
  J22    150   RFU3  SCONN288_ADR50001P003C01  I51
  J22    149   RFU2  SCONN288_ADR50001P003C01  I51
  J22    144   RFU1  SCONN288_ADR50001P003C01  I51
  J22      2   RFU0  SCONN288_ADR50001P003C01  I51
  J21    232   RFU6  SCONN288_ADR50001P013C01  I13
  J21    231   RFU5  SCONN288_ADR50001P013C01  I13
  J21    220   RFU4  SCONN288_ADR50001P013C01  I13
  J21    150   RFU3  SCONN288_ADR50001P013C01  I13
  J21    149   RFU2  SCONN288_ADR50001P013C01  I13
  J21    144   RFU1  SCONN288_ADR50001P013C01  I13
  J21      2   RFU0  SCONN288_ADR50001P013C01  I13
  J6     232   RFU6  SCONN288_ADR50001P003C01  I46
  J6     231   RFU5  SCONN288_ADR50001P003C01  I46
  J6     220   RFU4  SCONN288_ADR50001P003C01  I46
  J6     150   RFU3  SCONN288_ADR50001P003C01  I46
  J6     149   RFU2  SCONN288_ADR50001P003C01  I46
  J6     144   RFU1  SCONN288_ADR50001P003C01  I46
  J6       2   RFU0  SCONN288_ADR50001P003C01  I46
  J5     232   RFU6  SCONN288_ADR50001P013C01  I24
  J5     231   RFU5  SCONN288_ADR50001P013C01  I24
  J5     220   RFU4  SCONN288_ADR50001P013C01  I24
  J5     150   RFU3  SCONN288_ADR50001P013C01  I24
  J5     149   RFU2  SCONN288_ADR50001P013C01  I24
  J5     144   RFU1  SCONN288_ADR50001P013C01  I24
  J5       2   RFU0  SCONN288_ADR50001P013C01  I24
  J20    232   RFU6  SCONN288_ADR50001P003C01  I47
  J20    231   RFU5  SCONN288_ADR50001P003C01  I47
  J20    220   RFU4  SCONN288_ADR50001P003C01  I47
  J20    150   RFU3  SCONN288_ADR50001P003C01  I47
  J20    149   RFU2  SCONN288_ADR50001P003C01  I47
  J20    144   RFU1  SCONN288_ADR50001P003C01  I47
  J20      2   RFU0  SCONN288_ADR50001P003C01  I47
  J19    232   RFU6  SCONN288_ADR50001P013C01  I25
  J19    231   RFU5  SCONN288_ADR50001P013C01  I25
  J19    220   RFU4  SCONN288_ADR50001P013C01  I25
  J19    150   RFU3  SCONN288_ADR50001P013C01  I25
  J19    149   RFU2  SCONN288_ADR50001P013C01  I25
  J19    144   RFU1  SCONN288_ADR50001P013C01  I25
  J19      2   RFU0  SCONN288_ADR50001P013C01  I25
  J4     232   RFU6  SCONN288_ADR50001P003C01  I23
  J4     231   RFU5  SCONN288_ADR50001P003C01  I23
  J4     220   RFU4  SCONN288_ADR50001P003C01  I23
  J4     150   RFU3  SCONN288_ADR50001P003C01  I23
  J4     149   RFU2  SCONN288_ADR50001P003C01  I23
  J4     144   RFU1  SCONN288_ADR50001P003C01  I23
  J4       2   RFU0  SCONN288_ADR50001P003C01  I23
  J3     232   RFU6  SCONN288_ADR50001P013C01  I11
  J3     231   RFU5  SCONN288_ADR50001P013C01  I11
  J3     220   RFU4  SCONN288_ADR50001P013C01  I11
  J3     150   RFU3  SCONN288_ADR50001P013C01  I11
  J3     149   RFU2  SCONN288_ADR50001P013C01  I11
  J3     144   RFU1  SCONN288_ADR50001P013C01  I11
  J3       2   RFU0  SCONN288_ADR50001P013C01  I11
  J18    232   RFU6  SCONN288_ADR50001P003C01  I24
  J18    231   RFU5  SCONN288_ADR50001P003C01  I24
  J18    220   RFU4  SCONN288_ADR50001P003C01  I24
  J18    150   RFU3  SCONN288_ADR50001P003C01  I24
  J18    149   RFU2  SCONN288_ADR50001P003C01  I24
  J18    144   RFU1  SCONN288_ADR50001P003C01  I24
  J18      2   RFU0  SCONN288_ADR50001P003C01  I24
  J17    232   RFU6  SCONN288_ADR50001P013C01  I12
  J17    231   RFU5  SCONN288_ADR50001P013C01  I12
  J17    220   RFU4  SCONN288_ADR50001P013C01  I12
  J17    150   RFU3  SCONN288_ADR50001P013C01  I12
  J17    149   RFU2  SCONN288_ADR50001P013C01  I12
  J17    144   RFU1  SCONN288_ADR50001P013C01  I12
  J17      2   RFU0  SCONN288_ADR50001P013C01  I12
  J2     232   RFU6  SCONN288_ADR50001P003C01  I177
  J2     231   RFU5  SCONN288_ADR50001P003C01  I177
  J2     220   RFU4  SCONN288_ADR50001P003C01  I177
  J2     150   RFU3  SCONN288_ADR50001P003C01  I177
  J2     149   RFU2  SCONN288_ADR50001P003C01  I177
  J2     144   RFU1  SCONN288_ADR50001P003C01  I177
  J2       2   RFU0  SCONN288_ADR50001P003C01  I177
  J1     232   RFU6  SCONN288_ADR50001P013C01  I198
  J1     231   RFU5  SCONN288_ADR50001P013C01  I198
  J1     220   RFU4  SCONN288_ADR50001P013C01  I198
  J1     150   RFU3  SCONN288_ADR50001P013C01  I198
  J1     149   RFU2  SCONN288_ADR50001P013C01  I198
  J1     144   RFU1  SCONN288_ADR50001P013C01  I198
  J1       2   RFU0  SCONN288_ADR50001P013C01  I198
  U17      8     3B  74CBTLV3126PW  I80
  U4     AP3  GPPC_C_10_ME_SML2DATA  EMMITSBURG_REV0P9  I93
  U4     AR2  GPPC_C_9_ME_SML2CLK  EMMITSBURG_REV0P9  I93
  U122    K1  DIFFIO_RX_L15P  10M04SAU324I7G  I93
  U122    K2  DIFFIO_RX_L15N  10M04SAU324I7G  I93
  R1792    1      A  Q_RES       I20
  R1793    1      A  Q_RES       I19
  R632     1      A  Q_RES       I214
  R633     1      A  Q_RES       I215
  R1617    1      A  Q_RES       I203
  J55    A10  GND_A10  SCONN140_G64V3431BHR  I150
  U122    A6  DIFFIO_RX_T19P  10M04SAU324I7G  I155
  U122    F1  DIFFIO_RX_L8N||ADC1IN15  10M04SAU324I7G  I93
  PR412    1      A  Q_RES       I15
  U122    U1  DIFFIO_RX_L28N  10M04SAU324I7G  I93
  PU72_P0_4   34    PWM  ISL99390FRZTR5935  I24
  PU71_P0_3   34    PWM  ISL99390FRZTR5935  I40
  PU72_P0_4   38   IOUT  ISL99390FRZTR5935  I24
  PU71_P0_3   38   IOUT  ISL99390FRZTR5935  I40
  PR410    2      B  Q_RES       I260
  U103     3    OUT  MAX9634FEUKT  I12
  PR409    2      B  Q_RES       I59
  U102     3    OUT  MAX9634FEUKT  I17
  R404     1      A  Q_RES       I206
  J93    B12  PWRDIS  CONN56_ME2005602311011  I123
  J92    B12  PWRDIS  CONN56_ME2005602311011  I105
  J91    B12  PWRDIS  CONN56_ME2005602311011  I123
  J90    B12  PWRDIS  CONN56_ME2005602311011  I105
  U13    A29   OE2#  9SQ440NQQI8  I180
  U4     AA10  GPP_M_3  EMMITSBURG_REV0P9  I22
  U2      D4  XTAL_OUT  SOCKET4677_AZIFS054P001C01  I57
  U2      G5  XTAL_IN  SOCKET4677_AZIFS054P001C01  I57
  U1     CV69  UART_RXD  SOCKET4677_AZIFS054P001C01   I5
  U1     CY69  UART_TXD  SOCKET4677_AZIFS054P001C01   I5
  U1     CY71  UART_RTS  SOCKET4677_AZIFS054P001C01   I5
  U1     CV71  UART_CTS  SOCKET4677_AZIFS054P001C01   I5
  U2     CV69  UART_RXD  SOCKET4677_AZIFS054P001C01   I1
  U2     CY69  UART_TXD  SOCKET4677_AZIFS054P001C01   I1
  U2     CY71  UART_RTS  SOCKET4677_AZIFS054P001C01   I1
  U2     CV71  UART_CTS  SOCKET4677_AZIFS054P001C01   I1
  U1     BA68  SPI_OE_N  SOCKET4677_AZIFS054P001C01   I5
  U1     BD61  SPI_IO_3  SOCKET4677_AZIFS054P001C01   I5
  U1     BD65  SPI_IO_2  SOCKET4677_AZIFS054P001C01   I5
  U1     AW64  SPI_MISO_IO1  SOCKET4677_AZIFS054P001C01   I5
  U1     BA62  SPI_MOSI_IO0  SOCKET4677_AZIFS054P001C01   I5
  U1     AV63  SPI_CS1_N  SOCKET4677_AZIFS054P001C01   I5
  U1     BB61  SPI_CS0_N  SOCKET4677_AZIFS054P001C01   I5
  U1     BC64  SPI_CLK  SOCKET4677_AZIFS054P001C01   I5
  U1     BB67  SPI_TPM_OE_N  SOCKET4677_AZIFS054P001C01   I5
  U1     AY61  SPI_TPM_MISO_IO1  SOCKET4677_AZIFS054P001C01   I5
  U1     BA66  SPI_TPM_MOSI_IO0  SOCKET4677_AZIFS054P001C01   I5
  U1     AY67  SPI_TPM_CS0_N  SOCKET4677_AZIFS054P001C01   I5
  U1     AU62  SPI_TPM_CLK  SOCKET4677_AZIFS054P001C01   I5
  J57    A12  SIGNAL_A12  SCONN140_G64V3431BHR  I242
  J57     B9  SIGNAL_B9  SCONN140_G64V3431BHR  I242
  J57     A7  GND_A7  SCONN140_G64V3431BHR  I242
  J57    B10  GND_B10  SCONN140_G64V3431BHR  I242
  J55    A12  SIGNAL_A12  SCONN140_G64V3431BHR  I150
  J55     B9  SIGNAL_B9  SCONN140_G64V3431BHR  I150
  J55     A7  GND_A7  SCONN140_G64V3431BHR  I150
  J55    B10  GND_B10  SCONN140_G64V3431BHR  I150
  PU29    15  NPMALERT  RAA229126GNPHA0  I211
  PU14    15  NPMALERT  RAA229126GNPHA0  I48
  PU22    11  NPMALERT  ISL69260IRAZT  I61
  PU22     2   PWM1  ISL69260IRAZT  I61
  PU22     3   PWM2  ISL69260IRAZT  I61
  PU22     4   PWM3  ISL69260IRAZT  I61
  PU22     5   PWM4  ISL69260IRAZT  I61
  PU22     6   PWM5  ISL69260IRAZT  I61
  PU22    29    CS1  ISL69260IRAZT  I61
  PU22    28    CS2  ISL69260IRAZT  I61
  PU22    27    CS3  ISL69260IRAZT  I61
  PU22    26    CS4  ISL69260IRAZT  I61
  PU22    25    CS5  ISL69260IRAZT  I61
  PU5     11  NPMALERT  ISL69260IRAZT  I51
  PU5      2   PWM1  ISL69260IRAZT  I51
  PU5      3   PWM2  ISL69260IRAZT  I51
  PU5      4   PWM3  ISL69260IRAZT  I51
  PU5      5   PWM4  ISL69260IRAZT  I51
  PU5      6   PWM5  ISL69260IRAZT  I51
  PU5     29    CS1  ISL69260IRAZT  I51
  PU5     28    CS2  ISL69260IRAZT  I51
  PU5     27    CS3  ISL69260IRAZT  I51
  PU5     26    CS4  ISL69260IRAZT  I51
  PU5     25    CS5  ISL69260IRAZT  I51
  PU14     4   PWM3  RAA229126GNPHA0  I48
  PU14     3   PWM2  RAA229126GNPHA0  I48
  PU14    35    CS3  RAA229126GNPHA0  I48
  PU14    36    CS2  RAA229126GNPHA0  I48
  PU18    11  NPMALERT  ISL69260IRAZT  I243
  PU18    16    PG1  ISL69260IRAZT  I243
  PU18     1   PWM0  ISL69260IRAZT  I243
  PU18     2   PWM1  ISL69260IRAZT  I243
  PU18     3   PWM2  ISL69260IRAZT  I243
  PU18     4   PWM3  ISL69260IRAZT  I243
  PU18     5   PWM4  ISL69260IRAZT  I243
  PU18     6   PWM5  ISL69260IRAZT  I243
  PU18     7   PWM6  ISL69260IRAZT  I243
  PU18    30    CS0  ISL69260IRAZT  I243
  PU18    29    CS1  ISL69260IRAZT  I243
  PU18    28    CS2  ISL69260IRAZT  I243
  PU18    27    CS3  ISL69260IRAZT  I243
  PU18    26    CS4  ISL69260IRAZT  I243
  PU18    25    CS5  ISL69260IRAZT  I243
  PU18    24    CS6  ISL69260IRAZT  I243
  PU35    11  NPMALERT  ISL69260IRAZT  I51
  PU35    16    PG1  ISL69260IRAZT  I51
  PU35     1   PWM0  ISL69260IRAZT  I51
  PU35     2   PWM1  ISL69260IRAZT  I51
  PU35     3   PWM2  ISL69260IRAZT  I51
  PU35     4   PWM3  ISL69260IRAZT  I51
  PU35     5   PWM4  ISL69260IRAZT  I51
  PU35     6   PWM5  ISL69260IRAZT  I51
  PU35     7   PWM6  ISL69260IRAZT  I51
  PU35    30    CS0  ISL69260IRAZT  I51
  PU35    29    CS1  ISL69260IRAZT  I51
  PU35    28    CS2  ISL69260IRAZT  I51
  PU35    27    CS3  ISL69260IRAZT  I51
  PU35    26    CS4  ISL69260IRAZT  I51
  PU35    25    CS5  ISL69260IRAZT  I51
  PU35    24    CS6  ISL69260IRAZT  I51
  PU9     37    GL2  NCP3284MNTXG  I23
  PU9      6    GL1  NCP3284MNTXG  I23
  PU9     34    NC2  NCP3284MNTXG  I23
  PU9     33    NC1  NCP3284MNTXG  I23
  U4     D39  RSVD_D39  EMMITSBURG_REV0P9  I119
  U4     C40  RSVD_C40  EMMITSBURG_REV0P9  I119
  U4     BF39  RSVD_BF39  EMMITSBURG_REV0P9  I36
  U4     AV21  RSVD_AV21  EMMITSBURG_REV0P9  I36
  U4     AW26  RSVD_AW23  EMMITSBURG_REV0P9  I36
  U4     BG36  RSVD_BG36  EMMITSBURG_REV0P9  I36
  U4     BC40  RSVD_BC40  EMMITSBURG_REV0P9  I11
  U4     N42  RSVD_N42  EMMITSBURG_REV0P9  I119
  U4     N40  RSVD_N40  EMMITSBURG_REV0P9  I119
  U101     1     NC  SN74LVC1G17DCKR  I205
  J42      9      9  SCONN60_QSH03001LDAKTR  I44
  U54      1    NC1  74LVC1G07GV  I165
  J59     68  SUSCLK  SCONN75K_APCI0155P004A  I178
  J59     54  PEWAKE#  SCONN75K_APCI0155P004A  I178
  J59     32    NC9  SCONN75K_APCI0155P004A  I178
  J59     30    NC8  SCONN75K_APCI0155P004A  I178
  J59     28    NC7  SCONN75K_APCI0155P004A  I178
  J59     26    NC6  SCONN75K_APCI0155P004A  I178
  J59     24    NC5  SCONN75K_APCI0155P004A  I178
  J59     22    NC4  SCONN75K_APCI0155P004A  I178
  J59     20    NC3  SCONN75K_APCI0155P004A  I178
  J59      8    NC2  SCONN75K_APCI0155P004A  I178
  J59     67   NC19  SCONN75K_APCI0155P004A  I178
  J59     58   NC18  SCONN75K_APCI0155P004A  I178
  J59     56   NC17  SCONN75K_APCI0155P004A  I178
  J59     48   NC16  SCONN75K_APCI0155P004A  I178
  J59     46   NC15  SCONN75K_APCI0155P004A  I178
  J59     44   NC14  SCONN75K_APCI0155P004A  I178
  J59     36   NC11  SCONN75K_APCI0155P004A  I178
  J59     34   NC10  SCONN75K_APCI0155P004A  I178
  J59      6    NC1  SCONN75K_APCI0155P004A  I178
  PU9     35  HICCUP#  NCP3284MNTXG  I23
  U1     CT24  ADR_TRIGGER  SOCKET4677_AZIFS054P001C01   I5
  U1     CP24  ADR_COMPLETE  SOCKET4677_AZIFS054P001C01   I5
  U1     CN23  ADR_ACK  SOCKET4677_AZIFS054P001C01   I5
  J44      7      7  CONN24_52SH90245BRD  I125
  J44     24     24  CONN24_52SH90245BRD  I125
  J44     22     22  CONN24_52SH90245BRD  I125
  J44     21     21  CONN24_52SH90245BRD  I125
  U1     BG64  ESPI_RESET_N  SOCKET4677_AZIFS054P001C01   I5
  U1     BH63  ESPI_OE_N  SOCKET4677_AZIFS054P001C01   I5
  U1     BM63  ESPI_IO_3  SOCKET4677_AZIFS054P001C01   I5
  U1     AU64  ESPI_IO_2  SOCKET4677_AZIFS054P001C01   I5
  U1     BJ64  ESPI_IO_1  SOCKET4677_AZIFS054P001C01   I5
  U1     BK63  ESPI_IO_0  SOCKET4677_AZIFS054P001C01   I5
  U1     BH65  ESPI_CS1_N  SOCKET4677_AZIFS054P001C01   I5
  U1     BF65  ESPI_CS0_N  SOCKET4677_AZIFS054P001C01   I5
  U1     BG62  ESPI_CLK  SOCKET4677_AZIFS054P001C01   I5
  U1     BD63  ESPI_ALERT1_N  SOCKET4677_AZIFS054P001C01   I5
  U1     BE62  ESPI_ALERT0_N  SOCKET4677_AZIFS054P001C01   I5
  J42     56     56  SCONN60_QSH03001LDAKTR  I44
  J42     54     54  SCONN60_QSH03001LDAKTR  I44
  J42     46     46  SCONN60_QSH03001LDAKTR  I44
  J42     44     44  SCONN60_QSH03001LDAKTR  I44
  J42     34     34  SCONN60_QSH03001LDAKTR  I44
  J42     32     32  SCONN60_QSH03001LDAKTR  I44
  J42     30     30  SCONN60_QSH03001LDAKTR  I44
  J42     28     28  SCONN60_QSH03001LDAKTR  I44
  J42     26     26  SCONN60_QSH03001LDAKTR  I44
  J42     24     24  SCONN60_QSH03001LDAKTR  I44
  J42     22     22  SCONN60_QSH03001LDAKTR  I44
  J42     20     20  SCONN60_QSH03001LDAKTR  I44
  J42     18     18  SCONN60_QSH03001LDAKTR  I44
  U1     CY57  SOC_SPARE1_DIE11  SOCKET4677_AZIFS054P001C01   I1
  U1     CR25  SOC_SPARE1_DIE10  SOCKET4677_AZIFS054P001C01   I1
  U1     CW58  SOC_SPARE0_DIE11  SOCKET4677_AZIFS054P001C01   I1
  U1     CT26  SOC_SPARE0_DIE10  SOCKET4677_AZIFS054P001C01   I1
  U1     CR68  UPI3_APROBE_1  SOCKET4677_AZIFS054P001C01  I23
  U1     CP69  UPI3_APROBE_0  SOCKET4677_AZIFS054P001C01  I23
  U1     AT67  UPI2_APROBE_1  SOCKET4677_AZIFS054P001C01  I23
  U1     AU68  UPI2_APROBE_0  SOCKET4677_AZIFS054P001C01  I23
  U1     CA23  UPI1_APROBE_1  SOCKET4677_AZIFS054P001C01  I23
  U1     BV22  UPI1_APROBE_0  SOCKET4677_AZIFS054P001C01  I23
  U1     AR17  UPI0_APROBE_1  SOCKET4677_AZIFS054P001C01  I23
  U1     AN17  UPI0_APROBE_0  SOCKET4677_AZIFS054P001C01  I23
  U1     AV38  MAS_THERMADC  SOCKET4677_AZIFS054P001C01  I16
  U1     AV40  MAS_THERMADA  SOCKET4677_AZIFS054P001C01  I16
  U1     BP65  SOC_SPARE1_DIE01  SOCKET4677_AZIFS054P001C01   I1
  U1     BA25  SOC_SPARE1_DIE00  SOCKET4677_AZIFS054P001C01   I1
  U1     BM65  SOC_SPARE0_DIE01  SOCKET4677_AZIFS054P001C01   I1
  U1     AY24  SOC_SPARE0_DIE00  SOCKET4677_AZIFS054P001C01   I1
  U1     AU66  PE4_APROBE_1  SOCKET4677_AZIFS054P001C01  I23
  U1     AV67  PE4_APROBE_0  SOCKET4677_AZIFS054P001C01  I23
  U1     CM69  PE3_APROBE_1  SOCKET4677_AZIFS054P001C01  I23
  U1     CL68  PE3_APROBE_0  SOCKET4677_AZIFS054P001C01  I23
  U1     BW23  PE2_APROBE_1  SOCKET4677_AZIFS054P001C01  I23
  U1     CC23  PE2_APROBE_0  SOCKET4677_AZIFS054P001C01  I23
  U1     CC21  PE1_APROBE_1  SOCKET4677_AZIFS054P001C01  I23
  U1     CE21  PE1_APROBE_0  SOCKET4677_AZIFS054P001C01  I23
  U1     BL21  PE0_APROBE_1  SOCKET4677_AZIFS054P001C01  I23
  U1     BN21  PE0_APROBE_0  SOCKET4677_AZIFS054P001C01  I23
  U1     CK67  MDFI_VIEW_DIE11_NS_1  SOCKET4677_AZIFS054P001C01   I1
  U1     CJ68  MDFI_VIEW_DIE11_NS_0  SOCKET4677_AZIFS054P001C01   I1
  U1     CH69  MDFI_VIEW_DIE11_EW_1  SOCKET4677_AZIFS054P001C01   I1
  U1     CJ70  MDFI_VIEW_DIE11_EW_0  SOCKET4677_AZIFS054P001C01   I1
  U1     CD22  MDFI_VIEW_DIE10_NS_1  SOCKET4677_AZIFS054P001C01   I1
  U1     CF22  MDFI_VIEW_DIE10_NS_0  SOCKET4677_AZIFS054P001C01   I1
  U1     CD30  MDFI_VIEW_DIE10_EW_1  SOCKET4677_AZIFS054P001C01   I1
  U1     CD26  MDFI_VIEW_DIE10_EW_0  SOCKET4677_AZIFS054P001C01   I1
  U1     BD71  MDFI_VIEW_DIE01_NS_1  SOCKET4677_AZIFS054P001C01   I1
  U1     BF71  MDFI_VIEW_DIE01_NS_0  SOCKET4677_AZIFS054P001C01   I1
  U1     CC66  MDFI_VIEW_DIE01_EW_1  SOCKET4677_AZIFS054P001C01   I1
  U1     AV65  MDFI_VIEW_DIE01_EW_0  SOCKET4677_AZIFS054P001C01   I1
  U1     BJ21  MDFI_VIEW_DIE00_NS_1  SOCKET4677_AZIFS054P001C01   I1
  U1     BK22  MDFI_VIEW_DIE00_NS_0  SOCKET4677_AZIFS054P001C01   I1
  U1     BR21  MDFI_VIEW_DIE00_EW_1  SOCKET4677_AZIFS054P001C01   I1
  U1     BP22  MDFI_VIEW_DIE00_EW_0  SOCKET4677_AZIFS054P001C01   I1
  U1     CP61  LGSPARE_5  SOCKET4677_AZIFS054P001C01  I16
  U1     CC64  LGSPARE_4  SOCKET4677_AZIFS054P001C01  I16
  U1     CE62  LGSPARE_3  SOCKET4677_AZIFS054P001C01  I16
  U1     CU62  LGSPARE_2  SOCKET4677_AZIFS054P001C01  I16
  U1     CN60  LGSPARE_1  SOCKET4677_AZIFS054P001C01  I16
  U1     CR60  LGSPARE_0  SOCKET4677_AZIFS054P001C01  I16
  U1     BL60  HBM3_VIEWPIN_1  SOCKET4677_AZIFS054P001C01   I1
  U1     BG78  HBM3_VIEWPIN_0  SOCKET4677_AZIFS054P001C01   I1
  U1     AD77  HBM2_VIEWPIN_1  SOCKET4677_AZIFS054P001C01   I1
  U1     AC78  HBM2_VIEWPIN_0  SOCKET4677_AZIFS054P001C01   I1
  U1     CW41  HBM1_VIEWPIN_1  SOCKET4677_AZIFS054P001C01   I1
  U1     W17  HBM1_VIEWPIN_0  SOCKET4677_AZIFS054P001C01   I1
  U1     EG17  HBM0_VIEWPIN_1  SOCKET4677_AZIFS054P001C01   I1
  U1     U17  HBM0_VIEWPIN_0  SOCKET4677_AZIFS054P001C01   I1
  U1     BW21  DMI_APROBE_1  SOCKET4677_AZIFS054P001C01  I23
  U1     CA21  DMI_APROBE_0  SOCKET4677_AZIFS054P001C01  I23
  U1     CY49  DDR67_VIEWDIG_1  SOCKET4677_AZIFS054P001C01  I16
  U1     DA45  DDR67_VIEWDIG_0  SOCKET4677_AZIFS054P001C01  I16
  U1     CY38  DDR45_VIEWDIG_1  SOCKET4677_AZIFS054P001C01  I16
  U1     CY24  DDR45_VIEWDIG_0  SOCKET4677_AZIFS054P001C01  I16
  U1     AU33  DDR23_VIEWDIG_1  SOCKET4677_AZIFS054P001C01  I16
  U1     AV32  DDR23_VIEWDIG_0  SOCKET4677_AZIFS054P001C01  I16
  U1     AU56  DDR01_VIEWDIG_1  SOCKET4677_AZIFS054P001C01  I16
  U1     AU58  DDR01_VIEWDIG_0  SOCKET4677_AZIFS054P001C01  I16
  U2     CY57  SOC_SPARE1_DIE11  SOCKET4677_AZIFS054P001C01   I1
  U2     CR25  SOC_SPARE1_DIE10  SOCKET4677_AZIFS054P001C01   I1
  U2     CW58  SOC_SPARE0_DIE11  SOCKET4677_AZIFS054P001C01   I1
  U2     CT26  SOC_SPARE0_DIE10  SOCKET4677_AZIFS054P001C01   I1
  U2     CL64  VIEWPIN_DIE11_3  SOCKET4677_AZIFS054P001C01   I1
  U2     CM63  VIEWPIN_DIE11_2  SOCKET4677_AZIFS054P001C01   I1
  U2     CN62  VIEWPIN_DIE11_1  SOCKET4677_AZIFS054P001C01   I1
  U2     CJ62  VIEWPIN_DIE11_0  SOCKET4677_AZIFS054P001C01   I1
  U2     CW23  VIEWPIN_DIE10_3  SOCKET4677_AZIFS054P001C01   I1
  U2     CV24  VIEWPIN_DIE10_2  SOCKET4677_AZIFS054P001C01   I1
  U2     CW25  VIEWPIN_DIE10_1  SOCKET4677_AZIFS054P001C01   I1
  U2     CR23  VIEWPIN_DIE10_0  SOCKET4677_AZIFS054P001C01   I1
  U2     BJ70  VIEWPIN_DIE01_3  SOCKET4677_AZIFS054P001C01   I1
  U2     AY65  VIEWPIN_DIE01_2  SOCKET4677_AZIFS054P001C01   I1
  U2     BP67  VIEWPIN_DIE01_1  SOCKET4677_AZIFS054P001C01   I1
  U2     BP69  VIEWPIN_DIE01_0  SOCKET4677_AZIFS054P001C01   I1
  U2     AV26  VIEWPIN_DIE00_3  SOCKET4677_AZIFS054P001C01   I1
  U2     AU25  VIEWPIN_DIE00_2  SOCKET4677_AZIFS054P001C01   I1
  U2     AT24  VIEWPIN_DIE00_1  SOCKET4677_AZIFS054P001C01   I1
  U2     AY26  VIEWPIN_DIE00_0  SOCKET4677_AZIFS054P001C01   I1
  U2     CR68  UPI3_APROBE_1  SOCKET4677_AZIFS054P001C01   I1
  U2     CP69  UPI3_APROBE_0  SOCKET4677_AZIFS054P001C01   I1
  U2     AT67  UPI2_APROBE_1  SOCKET4677_AZIFS054P001C01   I1
  U2     AU68  UPI2_APROBE_0  SOCKET4677_AZIFS054P001C01   I1
  U2     CA23  UPI1_APROBE_1  SOCKET4677_AZIFS054P001C01   I1
  U2     BV22  UPI1_APROBE_0  SOCKET4677_AZIFS054P001C01   I1
  U2     AR17  UPI0_APROBE_1  SOCKET4677_AZIFS054P001C01   I1
  U2     AN17  UPI0_APROBE_0  SOCKET4677_AZIFS054P001C01   I1
  U2     AV38  MAS_THERMADC  SOCKET4677_AZIFS054P001C01   I1
  U2     AV40  MAS_THERMADA  SOCKET4677_AZIFS054P001C01   I1
  U2     BP65  SOC_SPARE1_DIE01  SOCKET4677_AZIFS054P001C01   I1
  U2     BA25  SOC_SPARE1_DIE00  SOCKET4677_AZIFS054P001C01   I1
  U2     BM65  SOC_SPARE0_DIE01  SOCKET4677_AZIFS054P001C01   I1
  U2     AY24  SOC_SPARE0_DIE00  SOCKET4677_AZIFS054P001C01   I1
  U2     CW68  FIVR_CLKREF  SOCKET4677_AZIFS054P001C01   I1
  U2     AU66  PE4_APROBE_1  SOCKET4677_AZIFS054P001C01   I1
  U2     AV67  PE4_APROBE_0  SOCKET4677_AZIFS054P001C01   I1
  U2     CM69  PE3_APROBE_1  SOCKET4677_AZIFS054P001C01   I1
  U2     CL68  PE3_APROBE_0  SOCKET4677_AZIFS054P001C01   I1
  U2     BW23  PE2_APROBE_1  SOCKET4677_AZIFS054P001C01   I1
  U2     CC23  PE2_APROBE_0  SOCKET4677_AZIFS054P001C01   I1
  U2     CC21  PE1_APROBE_1  SOCKET4677_AZIFS054P001C01   I1
  U2     CE21  PE1_APROBE_0  SOCKET4677_AZIFS054P001C01   I1
  U2     BL21  PE0_APROBE_1  SOCKET4677_AZIFS054P001C01   I1
  U2     BN21  PE0_APROBE_0  SOCKET4677_AZIFS054P001C01   I1
  U2     CK67  MDFI_VIEW_DIE11_NS_1  SOCKET4677_AZIFS054P001C01   I1
  U2     CJ68  MDFI_VIEW_DIE11_NS_0  SOCKET4677_AZIFS054P001C01   I1
  U2     CH69  MDFI_VIEW_DIE11_EW_1  SOCKET4677_AZIFS054P001C01   I1
  U2     CJ70  MDFI_VIEW_DIE11_EW_0  SOCKET4677_AZIFS054P001C01   I1
  U2     CD22  MDFI_VIEW_DIE10_NS_1  SOCKET4677_AZIFS054P001C01   I1
  U2     CF22  MDFI_VIEW_DIE10_NS_0  SOCKET4677_AZIFS054P001C01   I1
  U2     CD30  MDFI_VIEW_DIE10_EW_1  SOCKET4677_AZIFS054P001C01   I1
  U2     CD26  MDFI_VIEW_DIE10_EW_0  SOCKET4677_AZIFS054P001C01   I1
  U2     BD71  MDFI_VIEW_DIE01_NS_1  SOCKET4677_AZIFS054P001C01   I1
  U2     BF71  MDFI_VIEW_DIE01_NS_0  SOCKET4677_AZIFS054P001C01   I1
  U2     CC66  MDFI_VIEW_DIE01_EW_1  SOCKET4677_AZIFS054P001C01   I1
  U2     AV65  MDFI_VIEW_DIE01_EW_0  SOCKET4677_AZIFS054P001C01   I1
  U2     BJ21  MDFI_VIEW_DIE00_NS_1  SOCKET4677_AZIFS054P001C01   I1
  U2     BK22  MDFI_VIEW_DIE00_NS_0  SOCKET4677_AZIFS054P001C01   I1
  U2     BR21  MDFI_VIEW_DIE00_EW_1  SOCKET4677_AZIFS054P001C01   I1
  U2     BP22  MDFI_VIEW_DIE00_EW_0  SOCKET4677_AZIFS054P001C01   I1
  U2     CP61  LGSPARE_5  SOCKET4677_AZIFS054P001C01   I1
  U2     CC64  LGSPARE_4  SOCKET4677_AZIFS054P001C01   I1
  U2     CE62  LGSPARE_3  SOCKET4677_AZIFS054P001C01   I1
  U2     CU62  LGSPARE_2  SOCKET4677_AZIFS054P001C01   I1
  U2     CN60  LGSPARE_1  SOCKET4677_AZIFS054P001C01   I1
  U2     CR60  LGSPARE_0  SOCKET4677_AZIFS054P001C01   I1
  U2     BL60  HBM3_VIEWPIN_1  SOCKET4677_AZIFS054P001C01   I1
  U2     BG78  HBM3_VIEWPIN_0  SOCKET4677_AZIFS054P001C01   I1
  U2     AD77  HBM2_VIEWPIN_1  SOCKET4677_AZIFS054P001C01   I1
  U2     AC78  HBM2_VIEWPIN_0  SOCKET4677_AZIFS054P001C01   I1
  U2     CW41  HBM1_VIEWPIN_1  SOCKET4677_AZIFS054P001C01   I1
  U2     W17  HBM1_VIEWPIN_0  SOCKET4677_AZIFS054P001C01   I1
  U2     EG17  HBM0_VIEWPIN_1  SOCKET4677_AZIFS054P001C01   I1
  U2     U17  HBM0_VIEWPIN_0  SOCKET4677_AZIFS054P001C01   I1
  U2     BW21  DMI_APROBE_1  SOCKET4677_AZIFS054P001C01   I1
  U2     CA21  DMI_APROBE_0  SOCKET4677_AZIFS054P001C01   I1
  U2     CY49  DDR67_VIEWDIG_1  SOCKET4677_AZIFS054P001C01   I1
  U2     DA45  DDR67_VIEWDIG_0  SOCKET4677_AZIFS054P001C01   I1
  U2     CY38  DDR45_VIEWDIG_1  SOCKET4677_AZIFS054P001C01   I1
  U2     CY24  DDR45_VIEWDIG_0  SOCKET4677_AZIFS054P001C01   I1
  U2     AU33  DDR23_VIEWDIG_1  SOCKET4677_AZIFS054P001C01   I1
  U2     AV32  DDR23_VIEWDIG_0  SOCKET4677_AZIFS054P001C01   I1
  U2     AU56  DDR01_VIEWDIG_1  SOCKET4677_AZIFS054P001C01   I1
  U2     AU58  DDR01_VIEWDIG_0  SOCKET4677_AZIFS054P001C01   I1
  U2     CD71  PFT_OUT_DP  SOCKET4677_AZIFS054P001C01  I57
  U2     CE70  PFT_OUT_DN  SOCKET4677_AZIFS054P001C01  I57
  U13    A36  MXCK8  9SQ440NQQI8  I180
  U13    A35  MXCK8#  9SQ440NQQI8  I180
  U13    A40  MXCK6  9SQ440NQQI8  I180
  U13    A39  MXCK6#  9SQ440NQQI8  I180
  U13    A46  MXCK3  9SQ440NQQI8  I180
  U13    A45  MXCK3#  9SQ440NQQI8  I180
  U38    F11    NC9  9QXL2001BNHGI8  I119
  U38     F2    NC8  9QXL2001BNHGI8  I119
  U38    D11    NC7  9QXL2001BNHGI8  I119
  U38     D2    NC6  9QXL2001BNHGI8  I119
  U38     C2    NC5  9QXL2001BNHGI8  I119
  U38     B9    NC4  9QXL2001BNHGI8  I119
  U38     B7    NC3  9QXL2001BNHGI8  I119
  U38     B5    NC2  9QXL2001BNHGI8  I119
  U38     L9   NC18  9QXL2001BNHGI8  I119
  U38     L3   NC17  9QXL2001BNHGI8  I119
  U38     L7   NC16  9QXL2001BNHGI8  I119
  U38     L6   NC15  9QXL2001BNHGI8  I119
  U38     K2   NC14  9QXL2001BNHGI8  I119
  U38    J11   NC13  9QXL2001BNHGI8  I119
  U38     J2   NC12  9QXL2001BNHGI8  I119
  U38    G11   NC11  9QXL2001BNHGI8  I119
  U38     G2   NC10  9QXL2001BNHGI8  I119
  U38     B3    NC1  9QXL2001BNHGI8  I119
  U13     B7  NC_B7  9SQ440NQQI8  I288
  U13     B5  NC_B5  9SQ440NQQI8  I288
  U13    B44  NC_B44  9SQ440NQQI8  I288
  U13    B41  NC_B41  9SQ440NQQI8  I288
  U13    B39  NC_B39  9SQ440NQQI8  I288
  U13    B37  NC_B37  9SQ440NQQI8  I288
  U13    B36  NC_B36  9SQ440NQQI8  I288
  U13    B34  NC_B34  9SQ440NQQI8  I288
  U13    B33  NC_B33  9SQ440NQQI8  I288
  U13    B31  NC_B31  9SQ440NQQI8  I288
  U13    B30  NC_B30  9SQ440NQQI8  I288
  U13     B3  NC_B3  9SQ440NQQI8  I288
  U13    B28  NC_B28  9SQ440NQQI8  I288
  U13    B26  NC_B26  9SQ440NQQI8  I288
  U13    B25  NC_B25  9SQ440NQQI8  I288
  U13    B24  NC_B24  9SQ440NQQI8  I288
  U13    B22  NC_B22  9SQ440NQQI8  I288
  U13    B20  NC_B20  9SQ440NQQI8  I288
  U13     B2  NC_B2  9SQ440NQQI8  I288
  U13    B18  NC_B18  9SQ440NQQI8  I288
  U13    B16  NC_B16  9SQ440NQQI8  I288
  U13    B13  NC_B13  9SQ440NQQI8  I288
  U13    A15  NC_A15  9SQ440NQQI8  I288
  U122    B4  DIFFIO_RX_T23N  10M04SAU324I7G  I155
  L11      2      2  Q_INDUCTOR  I56
  U122    B3  DIFFIO_RX_T25N  10M04SAU324I7G  I155
  PR1388    1      A  Q_RES       I26
  J41    A45  PERP8  SCONN168_623403212  I115
  U122    B5  DIFFIO_RX_T20N  10M04SAU324I7G  I155
  U122    H1  DIFFIO_RX_L10P  10M04SAU324I7G  I93
  U122    B7  IO_8||VREFB8N0  10M04SAU324I7G  I139
  J93    A11  PERST1#||CLKREQ#  CONN56_ME2005602311011  I123
  J92    A11  PERST1#||CLKREQ#  CONN56_ME2005602311011  I105
  J91    A11  PERST1#||CLKREQ#  CONN56_ME2005602311011  I123
  J90    A11  PERST1#||CLKREQ#  CONN56_ME2005602311011  I105
  U1     CJ62  VIEWPIN_DIE11_0  SOCKET4677_AZIFS054P001C01  I29
  U1     CE70  PFT_OUT_DN  SOCKET4677_AZIFS054P001C01  I51
  U1     CD71  PFT_OUT_DP  SOCKET4677_AZIFS054P001C01  I51
  U1     AU25  VIEWPIN_DIE00_2  SOCKET4677_AZIFS054P001C01  I29
  U1     BP69  VIEWPIN_DIE01_0  SOCKET4677_AZIFS054P001C01  I29
  U1     BP67  VIEWPIN_DIE01_1  SOCKET4677_AZIFS054P001C01  I29
  U1     BJ70  VIEWPIN_DIE01_3  SOCKET4677_AZIFS054P001C01  I29
  U1     AT24  VIEWPIN_DIE00_1  SOCKET4677_AZIFS054P001C01  I29
  U1     AY65  VIEWPIN_DIE01_2  SOCKET4677_AZIFS054P001C01  I29
  U1     AY26  VIEWPIN_DIE00_0  SOCKET4677_AZIFS054P001C01  I29
  U1     AV26  VIEWPIN_DIE00_3  SOCKET4677_AZIFS054P001C01  I29
  U1      G5  XTAL_IN  SOCKET4677_AZIFS054P001C01  I51
  U1      D4  XTAL_OUT  SOCKET4677_AZIFS054P001C01  I51
  U1     CW68  FIVR_CLKREF  SOCKET4677_AZIFS054P001C01  I29
  U1     CW25  VIEWPIN_DIE10_1  SOCKET4677_AZIFS054P001C01  I29
  U1     CW23  VIEWPIN_DIE10_3  SOCKET4677_AZIFS054P001C01  I29
  U1     CV24  VIEWPIN_DIE10_2  SOCKET4677_AZIFS054P001C01  I29
  U1     CR23  VIEWPIN_DIE10_0  SOCKET4677_AZIFS054P001C01  I29
  U1     CN62  VIEWPIN_DIE11_1  SOCKET4677_AZIFS054P001C01  I29
  U1     CM63  VIEWPIN_DIE11_2  SOCKET4677_AZIFS054P001C01  I29
  U1     CL64  VIEWPIN_DIE11_3  SOCKET4677_AZIFS054P001C01  I29
  U1     CL21  PLT_PLTRST_SYNC_N  SOCKET4677_AZIFS054P001C01  I29
  U141    11    SD3  PCA9546APWR  I91
  U141     9    SD2  PCA9546APWR  I91
  U141    12    SC3  PCA9546APWR  I91
  U141    10    SC2  PCA9546APWR  I91
  R1833    2      B  Q_RES       I611
  PU17    27    GL2  RAA2213404GNPHB0  I38
  PU49    27    GL2  RAA2213404GNPHB0  I14
  PU50_P1_1   27    GL2  RAA2213404GNPHB0  I17
  PU51_P1_2   27    GL2  RAA2213404GNPHB0  I12
  PU77_P1_3   41    GL2  ISL99390FRZTR5935  I27
  PU77_P1_3    6    GL1  ISL99390FRZTR5935  I27
  PU77_P1_3   31    DNC  ISL99390FRZTR5935  I27
  PU78_P1_4   41    GL2  ISL99390FRZTR5935  I24
  PU78_P1_4    6    GL1  ISL99390FRZTR5935  I24
  PU78_P1_4   31    DNC  ISL99390FRZTR5935  I24
  PU75_P1_1   41    GL2  ISL99390FRZTR5935  I278
  PU75_P1_1    6    GL1  ISL99390FRZTR5935  I278
  PU75_P1_1   31    DNC  ISL99390FRZTR5935  I278
  PU76_P1_2   41    GL2  ISL99390FRZTR5935  I221
  PU76_P1_2    6    GL1  ISL99390FRZTR5935  I221
  PU76_P1_2   31    DNC  ISL99390FRZTR5935  I221
  PU24_P1_7   41    GL2  ISL99390FRZTR5935  I37
  PU24_P1_7    6    GL1  ISL99390FRZTR5935  I37
  PU24_P1_7   31    DNC  ISL99390FRZTR5935  I37
  PU23_P1_8   41    GL2  ISL99390FRZTR5935   I9
  PU23_P1_8    6    GL1  ISL99390FRZTR5935   I9
  PU23_P1_8   31    DNC  ISL99390FRZTR5935   I9
  PU26_P1_5   41    GL2  ISL99390FRZTR5935  I32
  PU26_P1_5    6    GL1  ISL99390FRZTR5935  I32
  PU26_P1_5   31    DNC  ISL99390FRZTR5935  I32
  PU25_P1_6   41    GL2  ISL99390FRZTR5935  I23
  PU25_P1_6    6    GL1  ISL99390FRZTR5935  I23
  PU25_P1_6   31    DNC  ISL99390FRZTR5935  I23
  PU28_P1_3   41    GL2  ISL99390FRZTR5935  I18
  PU28_P1_3    6    GL1  ISL99390FRZTR5935  I18
  PU28_P1_3   31    DNC  ISL99390FRZTR5935  I18
  PU27_P1_4   41    GL2  ISL99390FRZTR5935   I9
  PU27_P1_4    6    GL1  ISL99390FRZTR5935   I9
  PU27_P1_4   31    DNC  ISL99390FRZTR5935   I9
  PU31_P1_1   41    GL2  ISL99390FRZTR5935  I20
  PU31_P1_1    6    GL1  ISL99390FRZTR5935  I20
  PU31_P1_1   31    DNC  ISL99390FRZTR5935  I20
  PU30_P1_2   41    GL2  ISL99390FRZTR5935  I18
  PU30_P1_2    6    GL1  ISL99390FRZTR5935  I18
  PU30_P1_2   31    DNC  ISL99390FRZTR5935  I18
  PU36    27    GL2  RAA2213404GNPHB0  I333
  PU42    27    GL2  RAA2213404GNPHB0  I11
  PU43_P0_1   27    GL2  RAA2213404GNPHB0  I166
  PU44_P0_2   27    GL2  RAA2213404GNPHB0  I164
  PU71_P0_3   41    GL2  ISL99390FRZTR5935  I40
  PU71_P0_3    6    GL1  ISL99390FRZTR5935  I40
  PU71_P0_3   31    DNC  ISL99390FRZTR5935  I40
  PU72_P0_4   41    GL2  ISL99390FRZTR5935  I24
  PU72_P0_4    6    GL1  ISL99390FRZTR5935  I24
  PU72_P0_4   31    DNC  ISL99390FRZTR5935  I24
  PU69_P0_1   41    GL2  ISL99390FRZTR5935  I35
  PU69_P0_1    6    GL1  ISL99390FRZTR5935  I35
  PU69_P0_1   31    DNC  ISL99390FRZTR5935  I35
  PU70_P0_2   41    GL2  ISL99390FRZTR5935  I30
  PU70_P0_2    6    GL1  ISL99390FRZTR5935  I30
  PU70_P0_2   31    DNC  ISL99390FRZTR5935  I30
  PU6_P0_8   41    GL2  ISL99390FRZTR5935  I64
  PU6_P0_8    6    GL1  ISL99390FRZTR5935  I64
  PU6_P0_8   31    DNC  ISL99390FRZTR5935  I64
  PU7_P0_7   41    GL2  ISL99390FRZTR5935  I20
  PU7_P0_7    6    GL1  ISL99390FRZTR5935  I20
  PU7_P0_7   31    DNC  ISL99390FRZTR5935  I20
  PU8_P0_6   41    GL2  ISL99390FRZTR5935  I62
  PU8_P0_6    6    GL1  ISL99390FRZTR5935  I62
  PU8_P0_6   31    DNC  ISL99390FRZTR5935  I62
  PU9_P0_5   41    GL2  ISL99390FRZTR5935  I31
  PU9_P0_5    6    GL1  ISL99390FRZTR5935  I31
  PU9_P0_5   31    DNC  ISL99390FRZTR5935  I31
  PU11_P0_3   41    GL2  ISL99390FRZTR5935  I30
  PU11_P0_3    6    GL1  ISL99390FRZTR5935  I30
  PU11_P0_3   31    DNC  ISL99390FRZTR5935  I30
  PU10_P0_4   41    GL2  ISL99390FRZTR5935  I14
  PU10_P0_4    6    GL1  ISL99390FRZTR5935  I14
  PU10_P0_4   31    DNC  ISL99390FRZTR5935  I14
  PU12_P0_2   41    GL2  ISL99390FRZTR5935  I87
  PU12_P0_2    6    GL1  ISL99390FRZTR5935  I87
  PU12_P0_2   31    DNC  ISL99390FRZTR5935  I87
  PU13_P0_1   41    GL2  ISL99390FRZTR5935  I21
  PU13_P0_1    6    GL1  ISL99390FRZTR5935  I21
  PU13_P0_1   31    DNC  ISL99390FRZTR5935  I21
  J93_S2    1     TP  TP          I35
  J92_S2    1     TP  TP          I34
  J93_S1    1     TP  TP          I33
  J92_S1    1     TP  TP          I32
  J91_S2    1     TP  TP          I31
  J91_S1    1     TP  TP          I30
  J90_S2    1     TP  TP          I29
  J90_S1    1     TP  TP          I28
  ME8      1      1  DUMMY_SYMBOL  I19
  DM8      1      1  DUMMY_SYMBOL  I18
  DM9      1      1  DUMMY_SYMBOL  I17
  DM4      1      1  DUMMY_SYMBOL  I15
  DM7      1      1  DUMMY_SYMBOL  I14
  DM13     1      1  DUMMY_SYMBOL  I13
  DM10     1      1  DUMMY_SYMBOL   I8
  DM14     1      1  DUMMY_SYMBOL   I6
  DM15     1      1  DUMMY_SYMBOL   I5
  DM16     1      1  DUMMY_SYMBOL   I1
  H43      1      1  HOLE        I47
  H42      1      1  HOLE        I46
  H41      1      1  HOLE        I45
  H38      1      1  HOLE        I38
  H36      1      1  HOLE        I37
  H34      1      1  HOLE        I34
  H33      1      1  HOLE        I33
  H29      1      1  HOLE        I30
  H30      1      1  HOLE        I29
  H28      1      1  HOLE        I28
  H27      1      1  HOLE        I27
  H20      1      1  HOLE        I26
  H22      1      1  HOLE        I25
  H24      1      1  HOLE        I24
  H26      1      1  HOLE        I23
  H18      1      1  HOLE        I22
  H16      1      1  HOLE        I21
  H25      1      1  HOLE        I20
  H23      1      1  HOLE        I19
  H19      1      1  HOLE        I18
  H21      1      1  HOLE        I17
  H17      1      1  HOLE        I16
  H15      1      1  HOLE        I15
  U95      1    NC1  SN74LVC1G07DCKR  I41
  J93     B9  DUALPORTEN#  CONN56_ME2005602311011  I123
  J92     B9  DUALPORTEN#  CONN56_ME2005602311011  I105
  J91     B9  DUALPORTEN#  CONN56_ME2005602311011  I123
  J90     B9  DUALPORTEN#  CONN56_ME2005602311011  I105
  U104     1    NC1  74LVC1G07GV  I63
  U75      1     NC  SN74LVC1G17DCKR   I1
  J87    A42    RFU  SCONN84_123318136  I43
  J62    A42    RFU  SCONN84_123318136  I33

NCSI_BMC_CRS_DV_R   @S9S_MB_2U_LIB.S9S_MB_2U(SCH_1):NCSI_BMC_CRS_DV_R
  R1291    1      A  Q_RES       I99
  U67      9     3A  74CBTLV3126PW   I1

NCSI_BMC_RXD0_R   @S9S_MB_2U_LIB.S9S_MB_2U(SCH_1):NCSI_BMC_RXD0_R
  R1292    1      A  Q_RES       I100
  U67      5     2A  74CBTLV3126PW   I1

NCSI_BMC_RXD1_R   @S9S_MB_2U_LIB.S9S_MB_2U(SCH_1):NCSI_BMC_RXD1_R
  R1293    1      A  Q_RES       I101
  U67      2     1A  74CBTLV3126PW   I1

NCSI_BMC_TXD0_R   @S9S_MB_2U_LIB.S9S_MB_2U(SCH_1):NCSI_BMC_TXD0_R
  R1295    1      A  Q_RES       I103
  U68      5     2A  74CBTLV3126PW   I2

NCSI_BMC_TXD1_R   @S9S_MB_2U_LIB.S9S_MB_2U(SCH_1):NCSI_BMC_TXD1_R
  R1296    1      A  Q_RES       I104
  U68      2     1A  74CBTLV3126PW   I2

NCSI_BMC_TX_EN_R   @S9S_MB_2U_LIB.S9S_MB_2U(SCH_1):NCSI_BMC_TX_EN_R
  R1294    1      A  Q_RES       I102
  U68      9     3A  74CBTLV3126PW   I2

NCSI_OCP_SFF_CRS_DV   @S9S_MB_2U_LIB.S9S_MB_2U(SCH_1):NCSI_OCP_SFF_CRS_DV
  J37    OCP_B14  RBT_CRS_DV  SCONN168_623403212  I86
  U67      8     3B  74CBTLV3126PW   I1

NCSI_OCP_SFF_RXD0   @S9S_MB_2U_LIB.S9S_MB_2U(SCH_1):NCSI_OCP_SFF_RXD0
  J37    OCP_B9  RBT_RXD0  SCONN168_623403212  I86
  U67      6     2B  74CBTLV3126PW   I1

NCSI_OCP_SFF_RXD1   @S9S_MB_2U_LIB.S9S_MB_2U(SCH_1):NCSI_OCP_SFF_RXD1
  J37    OCP_B8  RBT_RXD1  SCONN168_623403212  I86
  U67      3     1B  74CBTLV3126PW   I1

NCSI_OCP_SFF_TXD0   @S9S_MB_2U_LIB.S9S_MB_2U(SCH_1):NCSI_OCP_SFF_TXD0
  J37    OCP_A9  RBT_TXD0  SCONN168_623403212  I86
  U68      6     2B  74CBTLV3126PW   I2

NCSI_OCP_SFF_TXD1   @S9S_MB_2U_LIB.S9S_MB_2U(SCH_1):NCSI_OCP_SFF_TXD1
  J37    OCP_A8  RBT_TXD1  SCONN168_623403212  I86
  U68      3     1B  74CBTLV3126PW   I2

NCSI_OCP_SFF_TX_EN   @S9S_MB_2U_LIB.S9S_MB_2U(SCH_1):NCSI_OCP_SFF_TX_EN
  J37    OCP_A7  RBT_TX_EN  SCONN168_623403212  I86
  U68      8     3B  74CBTLV3126PW   I2

OCP_SFF_AUX_PWR_EN   @S9S_MB_2U_LIB.S9S_MB_2U(SCH_1):OCP_SFF_AUX_PWR_EN
  R923     1      A  Q_RES       I118
  R1671    1      A  Q_RES       I340
  R1719    1      A  Q_RES       I119
  R1929    2      B  Q_RES       I360
  U122    K7  DIFFIO_RX_L14P  10M04SAU324I7G  I93

OCP_SFF_AUX_PWR_EN_R   @S9S_MB_2U_LIB.S9S_MB_2U(SCH_1):OCP_SFF_AUX_PWR_EN_R
  J37    B12  AUX_PWR_EN  SCONN168_623403212  I86
  R1671    2      B  Q_RES       I340

OCP_SFF_AUX_PWR_EN_R1   @S9S_MB_2U_LIB.S9S_MB_2U(SCH_1):OCP_SFF_AUX_PWR_EN_R1
  R1719    2      B  Q_RES       I119
  U66      1      1  74HC1G126GW  I53

OCP_SFF_AUX_PWR_EN_R2   @S9S_MB_2U_LIB.S9S_MB_2U(SCH_1):OCP_SFF_AUX_PWR_EN_R2
  R923     2      B  Q_RES       I118
  U77      1    1OE  74CBTLV3126PW  I105
  U77      4    2OE  74CBTLV3126PW  I105
  U77     10    3OE  74CBTLV3126PW  I105

OCP_SFF_BIF0_N   @S9S_MB_2U_LIB.S9S_MB_2U(SCH_1):OCP_SFF_BIF0_N
  U4      U3  GPP_I_12_HDA_BCLK  EMMITSBURG_REV0P9  I22
  U77      9     3A  74CBTLV3126PW  I105

OCP_SFF_BIF0_R_N   @S9S_MB_2U_LIB.S9S_MB_2U(SCH_1):OCP_SFF_BIF0_R_N
  J37     B7  BIF0#  SCONN168_623403212  I86
  R416     2      B  Q_RES       I253

OCP_SFF_BIF1_N   @S9S_MB_2U_LIB.S9S_MB_2U(SCH_1):OCP_SFF_BIF1_N
  U4      N2  GPP_I_13_HDA_RST_N  EMMITSBURG_REV0P9  I22
  U77      5     2A  74CBTLV3126PW  I105

OCP_SFF_BIF1_R_N   @S9S_MB_2U_LIB.S9S_MB_2U(SCH_1):OCP_SFF_BIF1_R_N
  J37     B8  BIF1#  SCONN168_623403212  I86
  R417     2      B  Q_RES       I255

OCP_SFF_BIF2_N   @S9S_MB_2U_LIB.S9S_MB_2U(SCH_1):OCP_SFF_BIF2_N
  U4      P1  GPP_I_14_HDA_SYNC  EMMITSBURG_REV0P9  I22
  U77      2     1A  74CBTLV3126PW  I105

OCP_SFF_BIF2_R_N   @S9S_MB_2U_LIB.S9S_MB_2U(SCH_1):OCP_SFF_BIF2_R_N
  J37     B9  BIF2#  SCONN168_623403212  I86
  R418     2      B  Q_RES       I258

OCP_SFF_ID0     @S9S_MB_2U_LIB.S9S_MB_2U(SCH_1):OCP_SFF_ID0
  J37    OCP_B7  SLOT_ID0  SCONN168_623403212  I86
  R409     2      B  Q_RES       I147
  R410     1      A  Q_RES       I148

OCP_SFF_ID1     @S9S_MB_2U_LIB.S9S_MB_2U(SCH_1):OCP_SFF_ID1
  J37    OCP_A6  SLOT_ID1  SCONN168_623403212  I86
  R414     2      B  Q_RES       I144
  R415     1      A  Q_RES       I145

OCP_SFF_ISO_BIF0_EN   @S9S_MB_2U_LIB.S9S_MB_2U(SCH_1):OCP_SFF_ISO_BIF0_EN
  R416     1      A  Q_RES       I253
  R1896    1      A  Q_RES       I123
  U77      8     3B  74CBTLV3126PW  I105

OCP_SFF_ISO_BIF1_EN   @S9S_MB_2U_LIB.S9S_MB_2U(SCH_1):OCP_SFF_ISO_BIF1_EN
  R417     1      A  Q_RES       I255
  R1897    1      A  Q_RES       I124
  U77      6     2B  74CBTLV3126PW  I105

OCP_SFF_ISO_BIF2_EN   @S9S_MB_2U_LIB.S9S_MB_2U(SCH_1):OCP_SFF_ISO_BIF2_EN
  R418     1      A  Q_RES       I258
  R1898    1      A  Q_RES       I122
  U77      3     1B  74CBTLV3126PW  I105

OCP_SFF_MAIN_PWR_EN   @S9S_MB_2U_LIB.S9S_MB_2U(SCH_1):OCP_SFF_MAIN_PWR_EN
  J37    OCP_B2  MAIN_PWR_EN  SCONN168_623403212  I86
  R429     2      B  Q_RES       I344
  R1930    2      B  Q_RES       I359

OCP_SFF_PRSNT0_R_N   @S9S_MB_2U_LIB.S9S_MB_2U(SCH_1):OCP_SFF_PRSNT0_R_N
  J37    B42  PRSNTB0#  SCONN168_623403212  I86
  R1905    2      B  Q_RES       I404
  U58      1     1A  SN74LVC2G07DCKR  I397

OCP_SFF_PRSNT1_R_N   @S9S_MB_2U_LIB.S9S_MB_2U(SCH_1):OCP_SFF_PRSNT1_R_N
  J37    A42  PRSNTB1#  SCONN168_623403212  I86
  R1907    2      B  Q_RES       I399
  U58      3     2A  SN74LVC2G07DCKR  I397

OCP_SFF_PRSNT2_R_N   @S9S_MB_2U_LIB.S9S_MB_2U(SCH_1):OCP_SFF_PRSNT2_R_N
  J37    A12  PRSNTB2#  SCONN168_623403212  I86
  R1906    2      B  Q_RES       I408
  U59      1     1A  SN74LVC2G07DCKR  I400

OCP_SFF_PRSNT3_R_N   @S9S_MB_2U_LIB.S9S_MB_2U(SCH_1):OCP_SFF_PRSNT3_R_N
  J37    B70  PRSNTB3#  SCONN168_623403212  I86
  R1908    2      B  Q_RES       I402
  U59      3     2A  SN74LVC2G07DCKR  I400

OCP_SFF_PRSNTA_R_N   @S9S_MB_2U_LIB.S9S_MB_2U(SCH_1):OCP_SFF_PRSNTA_R_N
  J37    A10  PRSNTA#  SCONN168_623403212  I86
  R1895    1      A  Q_RES       I353

OCP_SFF_PWRBRK_BUFF_N   @S9S_MB_2U_LIB.S9S_MB_2U(SCH_1):OCP_SFF_PWRBRK_BUFF_N
  R1593    2      B  Q_RES       I42
  R1595    1      A  Q_RES       I40
  U104     4      Y  74LVC1G07GV  I63

OCP_SFF_PWRBRK_N   @S9S_MB_2U_LIB.S9S_MB_2U(SCH_1):OCP_SFF_PWRBRK_N
  J37    A70  PWRBRK#  SCONN168_623403212  I86
  R1595    2      B  Q_RES       I40

OCP_SFF_RBT_ARB_IN   @S9S_MB_2U_LIB.S9S_MB_2U(SCH_1):OCP_SFF_RBT_ARB_IN
  J37    OCP_A4  RBT_ARB_IN  SCONN168_623403212  I86
  R1290    1      A  Q_RES       I98
  U67     11     4B  74CBTLV3126PW   I1
  U67     12     4A  74CBTLV3126PW   I1

OCP_SFF_RBT_ARB_OUT   @S9S_MB_2U_LIB.S9S_MB_2U(SCH_1):OCP_SFF_RBT_ARB_OUT
  J37    OCP_A5  RBT_ARB_OUT  SCONN168_623403212  I86
  R1290    2      B  Q_RES       I98
  U68     11     4B  74CBTLV3126PW   I2
  U68     12     4A  74CBTLV3126PW   I2

OCP_SFF_USB2_3_DN   @S9S_MB_2U_LIB.S9S_MB_2U(SCH_1):OCP_SFF_USB2_3_DN
  J37    A68  USB_DATN  SCONN168_623403212  I86
  R444     1      A  Q_RES       I350

OCP_SFF_USB2_3_DP   @S9S_MB_2U_LIB.S9S_MB_2U(SCH_1):OCP_SFF_USB2_3_DP
  J37    A69  USB_DATP  SCONN168_623403212  I86
  R445     1      A  Q_RES       I349

OCP_SFF_WAKE_BUFF_N   @S9S_MB_2U_LIB.S9S_MB_2U(SCH_1):OCP_SFF_WAKE_BUFF_N
  R1594    1      A  Q_RES       I26
  U82      4      Y  74LVC1G126GW  I35

P12V_AUX        @S9S_MB_2U_LIB.S9S_MB_2U(SCH_1):P12V_AUX
  C583     1      A  Q_CAP       I382
  C586     1      A  Q_CAP       I381
  C1358    1      A  Q_CAP       I148
  C1359    1      A  Q_CAP       I147
  C1430    1      A  Q_CAP       I101
  C1431    1      A  Q_CAP       I100
  C1597    1      A  Q_CAP       I47
  D12      C      C  DIODE_TVS   I45
  J49      6      6  CONN10_10142708102011LF   I2
  J49      7      7  CONN10_10142708102011LF   I2
  J49      8      8  CONN10_10142708102011LF   I2
  J49      9      9  CONN10_10142708102011LF   I2
  J49     10     10  CONN10_10142708102011LF   I2
  J50      6      6  CONN10_10142708102011LF   I4
  J50      7      7  CONN10_10142708102011LF   I4
  J50      8      8  CONN10_10142708102011LF   I4
  J50      9      9  CONN10_10142708102011LF   I4
  J50     10     10  CONN10_10142708102011LF   I4
  PL6      1      1  Q_INDUCTOR  I211
  PL14     1      1  Q_INDUCTOR  I69
  PL15     1      1  Q_INDUCTOR  I75
  PL16     1      1  Q_INDUCTOR  I26
  PL23     1      1  Q_INDUCTOR  I65
  PL32     1      1  Q_INDUCTOR  I71
  PL43     1      1  Q_INDUCTOR  I266
  PL44     1      1  Q_INDUCTOR  I74
  PL45     1      1  Q_INDUCTOR   I3
  PL64     1      1  Q_INDUCTOR   I5
  PL101    1      1  Q_INDUCTOR  I69
  PL110    1      1  Q_INDUCTOR   I2
  PR107    1      A  Q_RES       I28
  PR108    1      A  Q_RES       I27
  PR156    1      A  Q_RES        I6
  PR157    1      A  Q_RES        I9
  PR260    1      A  Q_RES       I12
  PR261    1      A  Q_RES       I11
  PR303    1      A  Q_RES       I166
  PR304    1      A  Q_RES       I167
  PR1945    1      A  Q_RES        I3
  R1642    1      A  Q_RES       I87
  R1643    1      A  Q_RES       I86
  R1688    1      A  Q_RES        I4
  R1799    1      A  Q_RES       I44
  R1837    2      2  Q_RES_4P_12   I1
  R1838    2      2  Q_RES_4P_12   I5
  U57      1   IN_1  TPS259824ONRGER  I377
  U57      2   IN_2  TPS259824ONRGER  I377
  U57      3   IN_3  TPS259824ONRGER  I377
  U57     16   IN_4  TPS259824ONRGER  I377
  U57     25  IN_TH1  TPS259824ONRGER  I377
  U81      9  VIN_9  MP5981GLUZ  I66
  U81     10  VIN_10  MP5981GLUZ  I66
  U81     11  VIN_11  MP5981GLUZ  I66
  U81     12  VIN_12  MP5981GLUZ  I66
  U81     13  VIN_13  MP5981GLUZ  I66
  U81     14  VIN_14  MP5981GLUZ  I66
  U81     15  VIN_15  MP5981GLUZ  I66
  U81     16  VIN_16  MP5981GLUZ  I66
  U107     9  VIN_9  MP5981GLUZ  I113
  U107    10  VIN_10  MP5981GLUZ  I113
  U107    11  VIN_11  MP5981GLUZ  I113
  U107    12  VIN_12  MP5981GLUZ  I113
  U107    13  VIN_13  MP5981GLUZ  I113
  U107    14  VIN_14  MP5981GLUZ  I113
  U107    15  VIN_15  MP5981GLUZ  I113
  U107    16  VIN_16  MP5981GLUZ  I113
  U138     3    IN1  TPS259540DSGR  I52
  U138     4    IN2  TPS259540DSGR  I52

P12V_AUX_SENSE   @S9S_MB_2U_LIB.S9S_MB_2U(SCH_1):P12V_AUX_SENSE
  C1351    1      A  Q_CAP       I45
  R1799    2      B  Q_RES       I44
  R1800    1      A  Q_RES       I46
  U105     7   AIN3  ADS1015IDGSR   I1
  U121     4  AIN3||REF  MAX11607EUAT  I48

P12V_E1S_0      @S9S_MB_2U_LIB.S9S_MB_2U(SCH_1):P12V_E1S_0
  C1276    1      A  Q_CAP       I45
  C1277    1      A  Q_CAP       I44
  C1278    1      A  Q_CAP       I15
  C1279    1      A  Q_CAP       I14
  C1506    1      A  Q_CAP       I164
  J90     B1  12V_B1  CONN56_ME2005602311011  I105
  J90     B2  12V_B2  CONN56_ME2005602311011  I105
  J90     B3  12V_B3  CONN56_ME2005602311011  I105
  J90     B4  12V_B4  CONN56_ME2005602311011  I105
  J90     B5  12V_B5  CONN56_ME2005602311011  I105
  J90     B6  12V_B6  CONN56_ME2005602311011  I105
  U126     5    OUT  TPS259540DSGR  I156

P12V_E1S_0_DVDT   @S9S_MB_2U_LIB.S9S_MB_2U(SCH_1):P12V_E1S_0_DVDT
  C1503    1      A  Q_CAP       I160
  U126     1   DVDT  TPS259540DSGR  I156

P12V_E1S_0_FLT_N   @S9S_MB_2U_LIB.S9S_MB_2U(SCH_1):P12V_E1S_0_FLT_N
  R2040    2      B  Q_RES       I166
  U126     6   FLT#  TPS259540DSGR  I156

P12V_E1S_0_ILM   @S9S_MB_2U_LIB.S9S_MB_2U(SCH_1):P12V_E1S_0_ILM
  R2038    1      A  Q_RES       I165
  U126     7    ILM  TPS259540DSGR  I156

P12V_E1S_1      @S9S_MB_2U_LIB.S9S_MB_2U(SCH_1):P12V_E1S_1
  C1280    1      A  Q_CAP       I32
  C1281    1      A  Q_CAP       I30
  C1489    1      A  Q_CAP       I77
  C1490    1      A  Q_CAP       I76
  C1514    1      A  Q_CAP       I114
  J91     B1  12V_B1  CONN56_ME2005602311011  I123
  J91     B2  12V_B2  CONN56_ME2005602311011  I123
  J91     B3  12V_B3  CONN56_ME2005602311011  I123
  J91     B4  12V_B4  CONN56_ME2005602311011  I123
  J91     B5  12V_B5  CONN56_ME2005602311011  I123
  J91     B6  12V_B6  CONN56_ME2005602311011  I123
  U128     5    OUT  TPS259540DSGR  I157

P12V_E1S_1_DVDT   @S9S_MB_2U_LIB.S9S_MB_2U(SCH_1):P12V_E1S_1_DVDT
  C1510    1      A  Q_CAP       I162
  U128     1   DVDT  TPS259540DSGR  I157

P12V_E1S_1_FLT_N   @S9S_MB_2U_LIB.S9S_MB_2U(SCH_1):P12V_E1S_1_FLT_N
  R2046    2      B  Q_RES       I116
  U128     6   FLT#  TPS259540DSGR  I157

P12V_E1S_1_ILM   @S9S_MB_2U_LIB.S9S_MB_2U(SCH_1):P12V_E1S_1_ILM
  R2044    1      A  Q_RES       I167
  U128     7    ILM  TPS259540DSGR  I157

P12V_E1S_2      @S9S_MB_2U_LIB.S9S_MB_2U(SCH_1):P12V_E1S_2
  C1491    1      A  Q_CAP       I47
  C1493    1      A  Q_CAP       I46
  C1495    1      A  Q_CAP       I45
  C1497    1      A  Q_CAP       I13
  C1509    1      A  Q_CAP       I123
  J92     B1  12V_B1  CONN56_ME2005602311011  I105
  J92     B2  12V_B2  CONN56_ME2005602311011  I105
  J92     B3  12V_B3  CONN56_ME2005602311011  I105
  J92     B4  12V_B4  CONN56_ME2005602311011  I105
  J92     B5  12V_B5  CONN56_ME2005602311011  I105
  J92     B6  12V_B6  CONN56_ME2005602311011  I105
  U127     5    OUT  TPS259540DSGR  I159

P12V_E1S_2_DVDT   @S9S_MB_2U_LIB.S9S_MB_2U(SCH_1):P12V_E1S_2_DVDT
  C1504    1      A  Q_CAP       I161
  U127     1   DVDT  TPS259540DSGR  I159

P12V_E1S_2_FLT_N   @S9S_MB_2U_LIB.S9S_MB_2U(SCH_1):P12V_E1S_2_FLT_N
  R2041    2      B  Q_RES       I119
  U127     6   FLT#  TPS259540DSGR  I159

P12V_E1S_2_ILM   @S9S_MB_2U_LIB.S9S_MB_2U(SCH_1):P12V_E1S_2_ILM
  R2039    1      A  Q_RES       I169
  U127     7    ILM  TPS259540DSGR  I159

P12V_E1S_3      @S9S_MB_2U_LIB.S9S_MB_2U(SCH_1):P12V_E1S_3
  C1492    1      A  Q_CAP       I88
  C1494    1      A  Q_CAP       I86
  C1496    1      A  Q_CAP       I85
  C1498    1      A  Q_CAP       I27
  C1515    1      A  Q_CAP       I140
  J93     B1  12V_B1  CONN56_ME2005602311011  I123
  J93     B2  12V_B2  CONN56_ME2005602311011  I123
  J93     B3  12V_B3  CONN56_ME2005602311011  I123
  J93     B4  12V_B4  CONN56_ME2005602311011  I123
  J93     B5  12V_B5  CONN56_ME2005602311011  I123
  J93     B6  12V_B6  CONN56_ME2005602311011  I123
  U129     5    OUT  TPS259540DSGR  I158

P12V_E1S_3_DVDT   @S9S_MB_2U_LIB.S9S_MB_2U(SCH_1):P12V_E1S_3_DVDT
  C1511    1      A  Q_CAP       I163
  U129     1   DVDT  TPS259540DSGR  I158

P12V_E1S_3_FLT_N   @S9S_MB_2U_LIB.S9S_MB_2U(SCH_1):P12V_E1S_3_FLT_N
  R2047    2      B  Q_RES       I136
  U129     6   FLT#  TPS259540DSGR  I158

P12V_E1S_3_ILM   @S9S_MB_2U_LIB.S9S_MB_2U(SCH_1):P12V_E1S_3_ILM
  R2045    1      A  Q_RES       I168
  U129     7    ILM  TPS259540DSGR  I158

P12V_FRONT_CPU   @S9S_MB_2U_LIB.S9S_MB_2U(SCH_1):P12V_FRONT_CPU
  C133     1      A  Q_CAPP      I18
  C134     1      A  Q_CAP       I20
  C180     1      A  Q_CAP       I77
  C632     1      A  Q_CAP       I59
  C1432    1      A  Q_CAP       I97
  C1433    1      A  Q_CAP       I98
  C1505    1      A  Q_CAP       I127
  C1512    1      A  Q_CAP       I108
  C1513    1      A  Q_CAP       I144
  C1601    1      A  Q_CAPP      I138
  C1602    1      A  Q_CAP       I139
  D8       C      C  DIODE_TVS   I174
  D9       C      C  DIODE_TVS   I177
  D10      C      C  DIODE_TVS   I181
  D11      C      C  DIODE_TVS   I179
  J89     B1     B1  SCONN280_ME1028040102011  I239
  J89     B2     B2  SCONN280_ME1028040102011  I239
  J89     B3     B3  SCONN280_ME1028040102011  I239
  J89     B4     B4  SCONN280_ME1028040102011  I239
  J89     B5     B5  SCONN280_ME1028040102011  I239
  J89     B6     B6  SCONN280_ME1028040102011  I239
  J89     B7     B7  SCONN280_ME1028040102011  I239
  J89    B13    B13  SCONN280_ME1028040102011  I239
  J89    B14    B14  SCONN280_ME1028040102011  I239
  J89    B15    B15  SCONN280_ME1028040102011  I239
  J89    B16    B16  SCONN280_ME1028040102011  I239
  J89    B17    B17  SCONN280_ME1028040102011  I239
  J89    B18    B18  SCONN280_ME1028040102011  I239
  JP5      1      1  CONN3_HFK1030G000LAF  I58
  U81      1  VOUT_1  MP5981GLUZ  I66
  U81      2  VOUT_2  MP5981GLUZ  I66
  U81     25  VOUT_25  MP5981GLUZ  I66
  U81     26  VOUT_26  MP5981GLUZ  I66
  U81     27  VOUT_27  MP5981GLUZ  I66
  U81     28  VOUT_28  MP5981GLUZ  I66
  U81     29  VOUT_29  MP5981GLUZ  I66
  U81     30  VOUT_30  MP5981GLUZ  I66
  U81     31  VOUT_31  MP5981GLUZ  I66
  U81     32  VOUT_32  MP5981GLUZ  I66
  U126     3    IN1  TPS259540DSGR  I156
  U126     4    IN2  TPS259540DSGR  I156
  U127     3    IN1  TPS259540DSGR  I159
  U127     4    IN2  TPS259540DSGR  I159
  U128     3    IN1  TPS259540DSGR  I157
  U128     4    IN2  TPS259540DSGR  I157
  U129     3    IN1  TPS259540DSGR  I158
  U129     4    IN2  TPS259540DSGR  I158

P12V_FRONT_CPU0   @S9S_MB_2U_LIB.S9S_MB_2U(SCH_1):P12V_FRONT_CPU0
  C127     1      A  Q_CAPP      I50
  C128     1      A  Q_CAP       I52
  J89     A2     A2  SCONN280_ME1028040102011  I239
  J89     A3     A3  SCONN280_ME1028040102011  I239
  J89     A4     A4  SCONN280_ME1028040102011  I239
  J89     A5     A5  SCONN280_ME1028040102011  I239
  J89     A6     A6  SCONN280_ME1028040102011  I239
  J89     A7     A7  SCONN280_ME1028040102011  I239

P12V_FRONT_CPU1   @S9S_MB_2U_LIB.S9S_MB_2U(SCH_1):P12V_FRONT_CPU1
  J55     A1  GND_A1  SCONN140_G64V3431BHR  I150
  J55     A2  SIGNAL_A2  SCONN140_G64V3431BHR  I150
  J55     A3  SIGNAL_A3  SCONN140_G64V3431BHR  I150
  J55     A4  GND_A4  SCONN140_G64V3431BHR  I150
  J55     A5  SIGNAL_A5  SCONN140_G64V3431BHR  I150
  J55     A6  SIGNAL_A6  SCONN140_G64V3431BHR  I150
  J57     A1  GND_A1  SCONN140_G64V3431BHR  I242
  J57     A2  SIGNAL_A2  SCONN140_G64V3431BHR  I242
  J57     A3  SIGNAL_A3  SCONN140_G64V3431BHR  I242
  J57     A4  GND_A4  SCONN140_G64V3431BHR  I242
  J57     A5  SIGNAL_A5  SCONN140_G64V3431BHR  I242
  J57     A6  SIGNAL_A6  SCONN140_G64V3431BHR  I242

P12V_OCP_DVDT_1   @S9S_MB_2U_LIB.S9S_MB_2U(SCH_1):P12V_OCP_DVDT_1
  C591     1      A  Q_CAP       I371
  U57     15   DVDT  TPS259824ONRGER  I377

P12V_OCP_ILIM1   @S9S_MB_2U_LIB.S9S_MB_2U(SCH_1):P12V_OCP_ILIM1
  R1137    1      A  Q_RES       I379
  U57      8   ILIM  TPS259824ONRGER  I377

P12V_OCP_IMON_1   @S9S_MB_2U_LIB.S9S_MB_2U(SCH_1):P12V_OCP_IMON_1
  R1144    1      A  Q_RES       I362
  U57      9   IMON  TPS259824ONRGER  I377

P12V_OCP_ITIMER_1   @S9S_MB_2U_LIB.S9S_MB_2U(SCH_1):P12V_OCP_ITIMER_1
  C588     1      A  Q_CAP       I373
  U57      7  ITIMER  TPS259824ONRGER  I377

P12V_OCP_LDSTRT11   @S9S_MB_2U_LIB.S9S_MB_2U(SCH_1):P12V_OCP_LDSTRT11
  R1134    1      A  Q_RES       I389
  U57     12  LDSTRT  TPS259824ONRGER  I377

P12V_OCP_NRETRY1   @S9S_MB_2U_LIB.S9S_MB_2U(SCH_1):P12V_OCP_NRETRY1
  R1135    1      A  Q_RES       I386
  U57     11  NRETRY  TPS259824ONRGER  I377

P12V_OCP_RETRY1   @S9S_MB_2U_LIB.S9S_MB_2U(SCH_1):P12V_OCP_RETRY1
  R1136    1      A  Q_RES       I385
  U57     10  RETRY_DLY  TPS259824ONRGER  I377

P12V_OCP_SFF    @S9S_MB_2U_LIB.S9S_MB_2U(SCH_1):P12V_OCP_SFF
  C319     1      A  Q_CAP       I361
  C331     1      A  Q_CAP       I360
  C589     1      A  Q_CAP       I369
  C1213    1      A  Q_CAP       I316
  C1232    1      A  Q_CAP       I331
  C1233    1      A  Q_CAP       I319
  C1234    1      A  Q_CAP       I332
  C1235    1      A  Q_CAP       I333
  C1236    1      A  Q_CAP       I322
  D4       C      C  SCHOTTKY_AC  I370
  J37     B1  +12V_EDGE_B1  SCONN168_623403212  I86
  J37     B2  +12V_EDGE_B2  SCONN168_623403212  I86
  J37     B3  +12V_EDGE_B3  SCONN168_623403212  I86
  J37     B4  +12V_EDGE_B4  SCONN168_623403212  I86
  J37     B5  +12V_EDGE_B5  SCONN168_623403212  I86
  J37     B6  +12V_EDGE_B6  SCONN168_623403212  I86
  U57     17  OUT_1  TPS259824ONRGER  I377
  U57     18  OUT_2  TPS259824ONRGER  I377
  U57     19  OUT_3  TPS259824ONRGER  I377
  U57     20  OUT_4  TPS259824ONRGER  I377
  U57     21  OUT_5  TPS259824ONRGER  I377
  U57     22  OUT_6  TPS259824ONRGER  I377
  U57     23  OUT_7  TPS259824ONRGER  I377
  U57     24  OUT_8  TPS259824ONRGER  I377

P12V_REAR_CPU   @S9S_MB_2U_LIB.S9S_MB_2U(SCH_1):P12V_REAR_CPU
  C1047    1      A  Q_CAP       I37
  C1048    1      A  Q_CAP       I36
  C1049    1      A  Q_CAP       I35
  C1050    1      A  Q_CAP       I34
  C1051    1      A  Q_CAP       I33
  C1052    1      A  Q_CAP       I31
  C1055    1      A  Q_CAP       I60
  C1056    1      A  Q_CAP       I59
  C1057    1      A  Q_CAP       I58
  C1058    1      A  Q_CAP       I57
  C1059    1      A  Q_CAP       I56
  C1060    1      A  Q_CAP       I54
  C1063    1      A  Q_CAP       I200
  C1064    1      A  Q_CAP       I198
  C1065    1      A  Q_CAP       I197
  C1066    1      A  Q_CAP       I196
  C1067    1      A  Q_CAP       I195
  C1068    1      A  Q_CAP       I193
  C1360    1      A  Q_CAP       I144
  C1361    1      A  Q_CAP       I145
  C1439    1      A  Q_CAP       I46
  C1440    1      A  Q_CAP       I45
  C1441    1      A  Q_CAP       I44
  C1442    1      A  Q_CAP       I43
  C1443    1      A  Q_CAP       I42
  C1444    1      A  Q_CAP       I40
  C1449    1      A  Q_CAP       I66
  C1450    1      A  Q_CAP       I65
  C1451    1      A  Q_CAP       I64
  C1452    1      A  Q_CAP       I63
  C1453    1      A  Q_CAP       I62
  C1454    1      A  Q_CAP       I60
  C1459    1      A  Q_CAP       I50
  C1460    1      A  Q_CAP       I52
  C1461    1      A  Q_CAP       I53
  C1462    1      A  Q_CAP       I63
  C1463    1      A  Q_CAP       I64
  C1464    1      A  Q_CAP       I66
  C1469    1      A  Q_CAP       I50
  C1470    1      A  Q_CAP       I52
  C1471    1      A  Q_CAP       I54
  C1472    1      A  Q_CAP       I55
  C1473    1      A  Q_CAP       I57
  C1474    1      A  Q_CAP       I58
  J33     B1  12VB1  SCONN84_123318136  I53
  J33     B2  12VB2  SCONN84_123318136  I53
  J33     B3  12VB3  SCONN84_123318136  I53
  J33     B4  12VB4  SCONN84_123318136  I53
  J33     B5  12VB5  SCONN84_123318136  I53
  J33     B6  12VB6  SCONN84_123318136  I53
  J34     B1  12VB1  SCONN84_123318136  I43
  J34     B2  12VB2  SCONN84_123318136  I43
  J34     B3  12VB3  SCONN84_123318136  I43
  J34     B4  12VB4  SCONN84_123318136  I43
  J34     B5  12VB5  SCONN84_123318136  I43
  J34     B6  12VB6  SCONN84_123318136  I43
  J35     B1  GND_B1  SCONN140_G64V3431BHR  I64
  J35     B2  SIGNAL_B2  SCONN140_G64V3431BHR  I64
  J35     B3  SIGNAL_B3  SCONN140_G64V3431BHR  I64
  J35     B4  GND_B4  SCONN140_G64V3431BHR  I64
  J35     B5  SIGNAL_B5  SCONN140_G64V3431BHR  I64
  J35     B8  SIGNAL_B8  SCONN140_G64V3431BHR  I64
  J35     B9  SIGNAL_B9  SCONN140_G64V3431BHR  I64
  J35    B10  GND_B10  SCONN140_G64V3431BHR  I64
  J35    B11  SIGNAL_B11  SCONN140_G64V3431BHR  I64
  J35    B12  SIGNAL_B12  SCONN140_G64V3431BHR  I64
  J61     B1  12VB1  SCONN84_123318136  I49
  J61     B2  12VB2  SCONN84_123318136  I49
  J61     B3  12VB3  SCONN84_123318136  I49
  J61     B4  12VB4  SCONN84_123318136  I49
  J61     B5  12VB5  SCONN84_123318136  I49
  J61     B6  12VB6  SCONN84_123318136  I49
  J62     B1  12VB1  SCONN84_123318136  I33
  J62     B2  12VB2  SCONN84_123318136  I33
  J62     B3  12VB3  SCONN84_123318136  I33
  J62     B4  12VB4  SCONN84_123318136  I33
  J62     B5  12VB5  SCONN84_123318136  I33
  J62     B6  12VB6  SCONN84_123318136  I33
  J87     B1  12VB1  SCONN84_123318136  I43
  J87     B2  12VB2  SCONN84_123318136  I43
  J87     B3  12VB3  SCONN84_123318136  I43
  J87     B4  12VB4  SCONN84_123318136  I43
  J87     B5  12VB5  SCONN84_123318136  I43
  J87     B6  12VB6  SCONN84_123318136  I43
  J88     B1  12VB1  SCONN84_123318136  I16
  J88     B2  12VB2  SCONN84_123318136  I16
  J88     B3  12VB3  SCONN84_123318136  I16
  J88     B4  12VB4  SCONN84_123318136  I16
  J88     B5  12VB5  SCONN84_123318136  I16
  J88     B6  12VB6  SCONN84_123318136  I16
  U107     1  VOUT_1  MP5981GLUZ  I113
  U107     2  VOUT_2  MP5981GLUZ  I113
  U107    25  VOUT_25  MP5981GLUZ  I113
  U107    26  VOUT_26  MP5981GLUZ  I113
  U107    27  VOUT_27  MP5981GLUZ  I113
  U107    28  VOUT_28  MP5981GLUZ  I113
  U107    29  VOUT_29  MP5981GLUZ  I113
  U107    30  VOUT_30  MP5981GLUZ  I113
  U107    31  VOUT_31  MP5981GLUZ  I113
  U107    32  VOUT_32  MP5981GLUZ  I113

P12V_S3_AUX_CPU0_NVDIMM   @S9S_MB_2U_LIB.S9S_MB_2U(SCH_1):P12V_S3_AUX_CPU0_NVDIMM
  C3       1      A  Q_CAP       I188
  C4       1      A  Q_CAP       I190
  C6       1      A  Q_CAP       I122
  C7       1      A  Q_CAP       I144
  C9       1      A  Q_CAP       I122
  C10      1      A  Q_CAP       I144
  C12      1      A  Q_CAP       I125
  C13      1      A  Q_CAP       I127
  C15      1      A  Q_CAP       I121
  C16      1      A  Q_CAP       I123
  C18      1      A  Q_CAP       I124
  C19      1      A  Q_CAP       I127
  C21      1      A  Q_CAP       I126
  C22      1      A  Q_CAP       I166
  C24      1      A  Q_CAP       I125
  C25      1      A  Q_CAP       I127
  C27      1      A  Q_CAP       I123
  C28      1      A  Q_CAP       I145
  C30      1      A  Q_CAP       I124
  C31      1      A  Q_CAP       I146
  C33      1      A  Q_CAP       I127
  C34      1      A  Q_CAP       I130
  C36      1      A  Q_CAP       I126
  C37      1      A  Q_CAP       I128
  C39      1      A  Q_CAP       I125
  C40      1      A  Q_CAP       I162
  C42      1      A  Q_CAP       I125
  C43      1      A  Q_CAP       I128
  C45      1      A  Q_CAP       I125
  C46      1      A  Q_CAP       I127
  C48      1      A  Q_CAP       I59
  C49      1      A  Q_CAP       I62
  J1       1  VIN_BULK0  SCONN288_ADR50001P013C01  I200
  J1     145  VIN_BULK1  SCONN288_ADR50001P013C01  I200
  J1     146  VIN_BULK2  SCONN288_ADR50001P013C01  I200
  J2       1  VIN_BULK0  SCONN288_ADR50001P003C01  I179
  J2     145  VIN_BULK1  SCONN288_ADR50001P003C01  I179
  J2     146  VIN_BULK2  SCONN288_ADR50001P003C01  I179
  J3       1  VIN_BULK0  SCONN288_ADR50001P013C01  I146
  J3     145  VIN_BULK1  SCONN288_ADR50001P013C01  I146
  J3     146  VIN_BULK2  SCONN288_ADR50001P013C01  I146
  J4       1  VIN_BULK0  SCONN288_ADR50001P003C01  I174
  J4     145  VIN_BULK1  SCONN288_ADR50001P003C01  I174
  J4     146  VIN_BULK2  SCONN288_ADR50001P003C01  I174
  J5       1  VIN_BULK0  SCONN288_ADR50001P013C01  I174
  J5     145  VIN_BULK1  SCONN288_ADR50001P013C01  I174
  J5     146  VIN_BULK2  SCONN288_ADR50001P013C01  I174
  J6       1  VIN_BULK0  SCONN288_ADR50001P003C01  I175
  J6     145  VIN_BULK1  SCONN288_ADR50001P003C01  I175
  J6     146  VIN_BULK2  SCONN288_ADR50001P003C01  I175
  J7       1  VIN_BULK0  SCONN288_ADR50001P013C01  I168
  J7     145  VIN_BULK1  SCONN288_ADR50001P013C01  I168
  J7     146  VIN_BULK2  SCONN288_ADR50001P013C01  I168
  J8       1  VIN_BULK0  SCONN288_ADR50001P003C01  I175
  J8     145  VIN_BULK1  SCONN288_ADR50001P003C01  I175
  J8     146  VIN_BULK2  SCONN288_ADR50001P003C01  I175
  J9       1  VIN_BULK0  SCONN288_ADR50001P013C01  I147
  J9     145  VIN_BULK1  SCONN288_ADR50001P013C01  I147
  J9     146  VIN_BULK2  SCONN288_ADR50001P013C01  I147
  J10      1  VIN_BULK0  SCONN288_ADR50001P003C01  I148
  J10    145  VIN_BULK1  SCONN288_ADR50001P003C01  I148
  J10    146  VIN_BULK2  SCONN288_ADR50001P003C01  I148
  J11      1  VIN_BULK0  SCONN288_ADR50001P013C01  I175
  J11    145  VIN_BULK1  SCONN288_ADR50001P013C01  I175
  J11    146  VIN_BULK2  SCONN288_ADR50001P013C01  I175
  J12      1  VIN_BULK0  SCONN288_ADR50001P003C01  I175
  J12    145  VIN_BULK1  SCONN288_ADR50001P003C01  I175
  J12    146  VIN_BULK2  SCONN288_ADR50001P003C01  I175
  J13      1  VIN_BULK0  SCONN288_ADR50001P013C01  I164
  J13    145  VIN_BULK1  SCONN288_ADR50001P013C01  I164
  J13    146  VIN_BULK2  SCONN288_ADR50001P013C01  I164
  J14      1  VIN_BULK0  SCONN288_ADR50001P003C01  I176
  J14    145  VIN_BULK1  SCONN288_ADR50001P003C01  I176
  J14    146  VIN_BULK2  SCONN288_ADR50001P003C01  I176
  J15      1  VIN_BULK0  SCONN288_ADR50001P013C01  I176
  J15    145  VIN_BULK1  SCONN288_ADR50001P013C01  I176
  J15    146  VIN_BULK2  SCONN288_ADR50001P013C01  I176
  J16      1  VIN_BULK0  SCONN288_ADR50001P003C01  I64
  J16    145  VIN_BULK1  SCONN288_ADR50001P003C01  I64
  J16    146  VIN_BULK2  SCONN288_ADR50001P003C01  I64
  R1838    1      1  Q_RES_4P_12   I5

P12V_S3_AUX_CPU0_NVDIMM_ISENSE_   @S9S_MB_2U_LIB.S9S_MB_2U(SCH_1):P12V_S3_AUX_CPU0_NVDIMM_ISENSE_N
  PR1390    1      A  Q_RES        I9
  R1838    3      3  Q_RES_4P_12   I5
  U102     4    RS-  MAX9634FEUKT  I17

P12V_S3_AUX_CPU0_NVDIMM_ISENS_1   @S9S_MB_2U_LIB.S9S_MB_2U(SCH_1):P12V_S3_AUX_CPU0_NVDIMM_ISENSE_P
  PR1380    1      A  Q_RES       I10
  R1838    4      4  Q_RES_4P_12   I5
  U102     5    RS+  MAX9634FEUKT  I17

P12V_S3_AUX_CPU1_NVDIMM   @S9S_MB_2U_LIB.S9S_MB_2U(SCH_1):P12V_S3_AUX_CPU1_NVDIMM
  C51      1      A  Q_CAP       I123
  C52      1      A  Q_CAP       I145
  C54      1      A  Q_CAP       I126
  C55      1      A  Q_CAP       I128
  C57      1      A  Q_CAP       I122
  C58      1      A  Q_CAP       I124
  C60      1      A  Q_CAP       I125
  C61      1      A  Q_CAP       I127
  C63      1      A  Q_CAP       I127
  C64      1      A  Q_CAP       I167
  C66      1      A  Q_CAP       I126
  C67      1      A  Q_CAP       I128
  C69      1      A  Q_CAP       I127
  C70      1      A  Q_CAP       I129
  C73      1      A  Q_CAP       I120
  C74      1      A  Q_CAP       I122
  C76      1      A  Q_CAP       I125
  C77      1      A  Q_CAP       I126
  C79      1      A  Q_CAP       I56
  C80      1      A  Q_CAP       I59
  C82      1      A  Q_CAP       I124
  C83      1      A  Q_CAP       I126
  C85      1      A  Q_CAP       I125
  C86      1      A  Q_CAP       I128
  C88      1      A  Q_CAP       I123
  C89      1      A  Q_CAP       I160
  C91      1      A  Q_CAP       I126
  C92      1      A  Q_CAP       I128
  C94      1      A  Q_CAP       I127
  C95      1      A  Q_CAP       I130
  C97      1      A  Q_CAP       I124
  C98      1      A  Q_CAP       I146
  J17      1  VIN_BULK0  SCONN288_ADR50001P013C01  I147
  J17    145  VIN_BULK1  SCONN288_ADR50001P013C01  I147
  J17    146  VIN_BULK2  SCONN288_ADR50001P013C01  I147
  J18      1  VIN_BULK0  SCONN288_ADR50001P003C01  I175
  J18    145  VIN_BULK1  SCONN288_ADR50001P003C01  I175
  J18    146  VIN_BULK2  SCONN288_ADR50001P003C01  I175
  J19      1  VIN_BULK0  SCONN288_ADR50001P013C01  I175
  J19    145  VIN_BULK1  SCONN288_ADR50001P013C01  I175
  J19    146  VIN_BULK2  SCONN288_ADR50001P013C01  I175
  J20      1  VIN_BULK0  SCONN288_ADR50001P003C01  I176
  J20    145  VIN_BULK1  SCONN288_ADR50001P003C01  I176
  J20    146  VIN_BULK2  SCONN288_ADR50001P003C01  I176
  J21      1  VIN_BULK0  SCONN288_ADR50001P013C01  I169
  J21    145  VIN_BULK1  SCONN288_ADR50001P013C01  I169
  J21    146  VIN_BULK2  SCONN288_ADR50001P013C01  I169
  J22      1  VIN_BULK0  SCONN288_ADR50001P003C01  I176
  J22    145  VIN_BULK1  SCONN288_ADR50001P003C01  I176
  J22    146  VIN_BULK2  SCONN288_ADR50001P003C01  I176
  J23      1  VIN_BULK0  SCONN288_ADR50001P013C01  I175
  J23    145  VIN_BULK1  SCONN288_ADR50001P013C01  I175
  J23    146  VIN_BULK2  SCONN288_ADR50001P013C01  I175
  J24      1  VIN_BULK0  SCONN288_ADR50001P003C01  I180
  J24    145  VIN_BULK1  SCONN288_ADR50001P003C01  I180
  J24    146  VIN_BULK2  SCONN288_ADR50001P003C01  I180
  J25      1  VIN_BULK0  SCONN288_ADR50001P013C01  I178
  J25    145  VIN_BULK1  SCONN288_ADR50001P013C01  I178
  J25    146  VIN_BULK2  SCONN288_ADR50001P013C01  I178
  J26      1  VIN_BULK0  SCONN288_ADR50001P003C01  I179
  J26    145  VIN_BULK1  SCONN288_ADR50001P003C01  I179
  J26    146  VIN_BULK2  SCONN288_ADR50001P003C01  I179
  J27      1  VIN_BULK0  SCONN288_ADR50001P013C01  I178
  J27    145  VIN_BULK1  SCONN288_ADR50001P013C01  I178
  J27    146  VIN_BULK2  SCONN288_ADR50001P013C01  I178
  J28      1  VIN_BULK0  SCONN288_ADR50001P003C01  I176
  J28    145  VIN_BULK1  SCONN288_ADR50001P003C01  I176
  J28    146  VIN_BULK2  SCONN288_ADR50001P003C01  I176
  J29      1  VIN_BULK0  SCONN288_ADR50001P013C01  I178
  J29    145  VIN_BULK1  SCONN288_ADR50001P013C01  I178
  J29    146  VIN_BULK2  SCONN288_ADR50001P013C01  I178
  J30      1  VIN_BULK0  SCONN288_ADR50001P003C01  I178
  J30    145  VIN_BULK1  SCONN288_ADR50001P003C01  I178
  J30    146  VIN_BULK2  SCONN288_ADR50001P003C01  I178
  J31      1  VIN_BULK0  SCONN288_ADR50001P013C01  I178
  J31    145  VIN_BULK1  SCONN288_ADR50001P013C01  I178
  J31    146  VIN_BULK2  SCONN288_ADR50001P013C01  I178
  J32      1  VIN_BULK0  SCONN288_ADR50001P003C01  I177
  J32    145  VIN_BULK1  SCONN288_ADR50001P003C01  I177
  J32    146  VIN_BULK2  SCONN288_ADR50001P003C01  I177
  R1837    1      1  Q_RES_4P_12   I1

P12V_S3_AUX_CPU1_NVDIMM_ISENSE_   @S9S_MB_2U_LIB.S9S_MB_2U(SCH_1):P12V_S3_AUX_CPU1_NVDIMM_ISENSE_N
  PR1410    1      A  Q_RES       I202
  R1837    3      3  Q_RES_4P_12   I1
  U103     4    RS-  MAX9634FEUKT  I12

P12V_S3_AUX_CPU1_NVDIMM_ISENS_1   @S9S_MB_2U_LIB.S9S_MB_2U(SCH_1):P12V_S3_AUX_CPU1_NVDIMM_ISENSE_P
  PR1400    1      A  Q_RES       I203
  R1837    4      4  Q_RES_4P_12   I1
  U103     5    RS+  MAX9634FEUKT  I12

P12V_SCM        @S9S_MB_2U_LIB.S9S_MB_2U(SCH_1):P12V_SCM
  C1598    1      A  Q_CAP       I48
  J41    OCP_A1  PERST2#  SCONN168_623403212  I115
  J41    OCP_A2  PERST3#  SCONN168_623403212  I115
  J41    OCP_B1  NIC_PWR_GOOD  SCONN168_623403212  I115
  J41    OCP_B2  MAIN_PWR_EN  SCONN168_623403212  I115
  U138     5    OUT  TPS259540DSGR  I52

P12V_SCM_DVDT   @S9S_MB_2U_LIB.S9S_MB_2U(SCH_1):P12V_SCM_DVDT
  C1596    1      A  Q_CAP       I46
  U138     1   DVDT  TPS259540DSGR  I52

P12V_SCM_EN_N   @S9S_MB_2U_LIB.S9S_MB_2U(SCH_1):P12V_SCM_EN_N
  Q39      3     D2  MOSFET_NCH_DUAL  I20
  R1857    2      B  Q_RES       I29
  R2135    2      B  Q_RES       I53
  U138     2  EN||UVLO  TPS259540DSGR  I52

P12V_SCM_FLT_N   @S9S_MB_2U_LIB.S9S_MB_2U(SCH_1):P12V_SCM_FLT_N
  R2138    2      B  Q_RES       I50
  U138     6   FLT#  TPS259540DSGR  I52

P12V_SCM_ILM    @S9S_MB_2U_LIB.S9S_MB_2U(SCH_1):P12V_SCM_ILM
  R2137    1      A  Q_RES       I49
  U138     7    ILM  TPS259540DSGR  I52

P1V05_PCH_AUX   @S9S_MB_2U_LIB.S9S_MB_2U(SCH_1):P1V05_PCH_AUX
  C547     1      A  Q_CAP       I100
  C1178    1      A  Q_CAP        I6
  C1182    1      A  Q_CAP       I42
  C1183    1      A  Q_CAP       I51
  C1185    1      A  Q_CAP        I7
  C1187    1      A  Q_CAP       I40
  C1189    1      A  Q_CAP       I58
  C1192    1      A  Q_CAP        I8
  C1198    1      A  Q_CAP       I43
  C1200    1      A  Q_CAP       I59
  C1203    1      A  Q_CAP       I48
  C1204    1      A  Q_CAP       I60
  C1205    1      A  Q_CAP       I12
  C1210    1      A  Q_CAP       I45
  C1214    1      A  Q_CAP       I61
  C1228    1      A  Q_CAP       I13
  C1231    1      A  Q_CAP       I49
  C1242    1      A  Q_CAP       I63
  C1244    1      A  Q_CAP       I15
  C1246    1      A  Q_CAP       I21
  C1247    1      A  Q_CAP       I65
  C1248    1      A  Q_CAP       I22
  C1249    1      A  Q_CAP       I66
  C1250    1      A  Q_CAP       I137
  J42      1      1  SCONN60_QSH03001LDAKTR  I44
  L2       1      1  Q_INDUCTOR  I135
  PC117    1      A  Q_CAPP      I14
  PC1224    1      A  Q_CAP       I45
  PC1225    1      A  Q_CAP       I47
  PC1226    1      A  Q_CAP       I48
  PC1227    1      A  Q_CAPP      I16
  PC1229    1      A  Q_CAPP      I52
  PC1230    1      A  Q_CAPP      I18
  PJ62     2      2  Q_SHORT     I46
  PL150    2      2  Q_INDUCTOR  I43
  R382     1      A  Q_RES       I32
  R747     1      A  Q_RES       I176
  R748     1      A  Q_RES       I180
  R749     1      A  Q_RES       I179
  R750     1      A  Q_RES       I178
  R751     1      A  Q_RES       I177
  R1026    2      B  Q_RES       I37
  R1260    1      A  Q_RES       I17
  R1261    1      A  Q_RES       I18
  R1262    1      A  Q_RES       I11
  R1266    1      A  Q_RES       I36
  R1298    1      A  Q_RES       I22
  R1315    1      A  Q_RES       I35
  R1317    1      A  Q_RES       I28
  R1342    1      A  Q_RES       I45
  R1343    1      A  Q_RES       I44
  R1463    1      A  Q_RES       I129
  U4     AB19  VCCP_1P05_AB19  EMMITSBURG_REV0P9  I11
  U4     AB20  VCCP_1P05_AB20  EMMITSBURG_REV0P9  I11
  U4     AB22  VCCP_1P05_AB22  EMMITSBURG_REV0P9  I11
  U4     AB24  VCCP_1P05_AB24  EMMITSBURG_REV0P9  I11
  U4     AD25  VCCP_1P05_AD25  EMMITSBURG_REV0P9  I11
  U4     AD27  VCCP_1P05_AD27  EMMITSBURG_REV0P9  I11
  U4     AF20  VCCP_VNN_AF20  EMMITSBURG_REV0P9  I11
  U4     AF22  VCCP_VNN_AF22  EMMITSBURG_REV0P9  I11
  U4     AF25  VCCP_1P05_AF25  EMMITSBURG_REV0P9  I11
  U4     AF27  VCCP_1P05_AF27  EMMITSBURG_REV0P9  I11
  U4     AG20  VCCP_VNN_AG20  EMMITSBURG_REV0P9  I11
  U4     AG22  VCCP_VNN_AG22  EMMITSBURG_REV0P9  I11
  U4     AG25  VCCP_1P05_AG25  EMMITSBURG_REV0P9  I11
  U4     AG27  VCCP_1P05_AG27  EMMITSBURG_REV0P9  I11
  U4     AJ20  VCCP_VNN_AJ20  EMMITSBURG_REV0P9  I11
  U4     AJ22  VCCP_VNN_AJ22  EMMITSBURG_REV0P9  I11
  U4     AJ25  VCCP_1P05_AJ25  EMMITSBURG_REV0P9  I11
  U4     AJ27  VCCP_1P05_AJ27  EMMITSBURG_REV0P9  I11
  U4     AL20  VCCP_VNN_AL20  EMMITSBURG_REV0P9  I11
  U4     AL22  VCCP_VNN_AL22  EMMITSBURG_REV0P9  I11
  U4     AN23  VCCP_VNN_AN23  EMMITSBURG_REV0P9  I11
  U4     AP21  VCCP_VNN_AP21  EMMITSBURG_REV0P9  I11
  U4     AR23  VCCP_VNN_AR23  EMMITSBURG_REV0P9  I11
  U4     AR26  VCCP_1P05_AR26  EMMITSBURG_REV0P9  I11
  U4     M24  VCCP_1P05_M24  EMMITSBURG_REV0P9  I11
  U4     N23  VCCP_1P05_N23  EMMITSBURG_REV0P9  I11
  U4     N26  VCCP_1P05_N26  EMMITSBURG_REV0P9  I11
  U4     P15  VCCP_1P05_P15  EMMITSBURG_REV0P9  I11
  U4     W17  VCCP_1P05_W17  EMMITSBURG_REV0P9  I11
  U4     W19  VCCP_1P05_W19  EMMITSBURG_REV0P9  I11
  U4     W20  VCCP_1P05_W20  EMMITSBURG_REV0P9  I11
  U4     W22  VCCP_1P05_W22  EMMITSBURG_REV0P9  I11
  U4     W24  VCCP_1P05_W24  EMMITSBURG_REV0P9  I11
  U87      D  DRAIN  MOSFET_N    I96

P1V05_PCH_AUX_CS   @S9S_MB_2U_LIB.S9S_MB_2U(SCH_1):P1V05_PCH_AUX_CS
  PR1327    1      A  Q_RES       I10
  PU73     3     CS  MPQ8633BGLEC838Z  I34

P1V05_PCH_AUX_FB   @S9S_MB_2U_LIB.S9S_MB_2U(SCH_1):P1V05_PCH_AUX_FB
  PC1223    1      A  Q_CAP       I42
  PR187    1      A  Q_RES       I13
  PR1328    1      A  Q_RES       I41
  PU73     7     FB  MPQ8633BGLEC838Z  I34

P1V05_PCH_AUX_REF   @S9S_MB_2U_LIB.S9S_MB_2U(SCH_1):P1V05_PCH_AUX_REF
  PC1221    1      A  Q_CAP       I36
  PC2000    1      A  Q_CAP       I35
  PU73     5  TRK_REF  MPQ8633BGLEC838Z  I34

P1V05_PCH_AUX_VCC   @S9S_MB_2U_LIB.S9S_MB_2U(SCH_1):P1V05_PCH_AUX_VCC
  PC113    1      A  Q_CAP        I8
  PR1326    2      B  Q_RES       I21
  PU73     4   MODE  MPQ8633BGLEC838Z  I34
  PU73    19    VCC  MPQ8633BGLEC838Z  I34

P1V05_PCH_PLL_AUX   @S9S_MB_2U_LIB.S9S_MB_2U(SCH_1):P1V05_PCH_PLL_AUX
  C1251    1      A  Q_CAP       I110
  C1254    1      A  Q_CAP       I111
  C1256    1      A  Q_CAP       I136
  C1258    1      A  Q_CAP       I112
  C1260    1      A  Q_CAP       I131
  C1262    1      A  Q_CAP       I104
  C1264    1      A  Q_CAP       I133
  C1272    1      A  Q_CAP       I100
  L2       2      2  Q_INDUCTOR  I135
  R1463    2      B  Q_RES       I129
  U4     AA29  VCCP_1P05_FILTERED_AA29  EMMITSBURG_REV0P9  I11
  U4     AB27  VCCP_1P05_FILTERED_AB27  EMMITSBURG_REV0P9  I11
  U4     AE29  VCCP_1P05_FILTERED_AE29  EMMITSBURG_REV0P9  I11
  U4     AG29  VCCP_1P05_FILTERED_AG29  EMMITSBURG_REV0P9  I11
  U4     AL25  VCCP_1P05_FILTERED_AL25  EMMITSBURG_REV0P9  I11
  U4     R23  VCCP_1P05_FILTERED_R23  EMMITSBURG_REV0P9  I11
  U4     R26  VCCP_1P05_FILTERED_R26  EMMITSBURG_REV0P9  I11
  U4     R29  VCCP_1P05_FILTERED_R29  EMMITSBURG_REV0P9  I11
  U4     U27  VCCP_1P05_FILTERED_U27  EMMITSBURG_REV0P9  I11

P1V8_PCH_AUX    @S9S_MB_2U_LIB.S9S_MB_2U(SCH_1):P1V8_PCH_AUX
  C550     1      A  Q_CAP       I99
  C1181    1      A  Q_CAP       I27
  C1186    1      A  Q_CAP       I25
  C1197    1      A  Q_CAP       I30
  C1202    1      A  Q_CAP       I29
  C1207    1      A  Q_CAP       I32
  C1253    1      A  Q_CAP       I147
  C1323    1      A  Q_CAP       I28
  J42     12     12  SCONN60_QSH03001LDAKTR  I44
  L10      1      1  Q_INDUCTOR  I145
  PC1236    1      A  Q_CAP       I23
  PC1237    1      A  Q_CAP       I25
  PC1238    1      A  Q_CAP       I37
  PC1239    1      A  Q_CAP       I38
  PC1240    1      A  Q_CAP       I39
  PC1241    1      A  Q_CAP       I41
  PL170    2      2  Q_INDUCTOR  I22
  PU74    12   VOUT  NB695GDZ    I20
  R401     1      A  Q_RES       I69
  R623     1      A  Q_RES       I13
  R1464    1      A  Q_RES       I144
  R1700    1      A  Q_RES       I48
  R1702    1      A  Q_RES       I43
  R1703    1      A  Q_RES       I45
  R1747    1      A  Q_RES        I2
  U4     N20  VCCP_1P8_N20  EMMITSBURG_REV0P9  I11
  U4     U17  VCCP_1P8_U17  EMMITSBURG_REV0P9  I11
  U4     U19  VCCP_1P8_U19  EMMITSBURG_REV0P9  I11
  U4     U20  VCCP_1P8_U20  EMMITSBURG_REV0P9  I11
  U4     U22  VCCP_1P8_U22  EMMITSBURG_REV0P9  I11
  U4     U24  VCCP_1P8_U24  EMMITSBURG_REV0P9  I11
  U98      2  VREF1  PCA9306DCTR  I27

P1V8_PCH_AUX_MODE   @S9S_MB_2U_LIB.S9S_MB_2U(SCH_1):P1V8_PCH_AUX_MODE
  PR1330    1      A  Q_RES       I12
  PU74     7   MODE  NB695GDZ    I20

P1V8_PCH_AUX_VCC   @S9S_MB_2U_LIB.S9S_MB_2U(SCH_1):P1V8_PCH_AUX_VCC
  PC1642    1      A  Q_CAP        I4
  PR1329    2      B  Q_RES        I7
  PU74     3     C1  NB695GDZ    I20
  PU74     6    LP#  NB695GDZ    I20
  PU74    10    3V3  NB695GDZ    I20

P1V8_PCH_PLL_AUX   @S9S_MB_2U_LIB.S9S_MB_2U(SCH_1):P1V8_PCH_PLL_AUX
  C1252    1      A  Q_CAP       I125
  C1255    1      A  Q_CAP       I123
  C1257    1      A  Q_CAP       I146
  C1259    1      A  Q_CAP       I121
  C1261    1      A  Q_CAP       I142
  C1263    1      A  Q_CAP       I119
  C1265    1      A  Q_CAP       I140
  C1266    1      A  Q_CAP       I127
  C1273    1      A  Q_CAP       I116
  L10      2      2  Q_INDUCTOR  I145
  R1464    2      B  Q_RES       I144
  U4     AB31  VCCP_1P8_FILTERED_AB31  EMMITSBURG_REV0P9  I11
  U4     AB34  VCCP_1P8_FILTERED_AB34  EMMITSBURG_REV0P9  I11
  U4     U29  VCCP_1P8_FILTERED_U29  EMMITSBURG_REV0P9  I11
  U4     W27  VCCP_1P8_FILTERED_W27  EMMITSBURG_REV0P9  I11
  U4     W29  VCCP_1P8_FILTERED_W29  EMMITSBURG_REV0P9  I11

P3E_PCH_BMC_RX_DN   @S9S_MB_2U_LIB.S9S_MB_2U(SCH_1):P3E_PCH_BMC_RX_DN
  J41    A19  GND_A19  SCONN168_623403212  I115
  U4     M41  SATA_10_PCIE3_10_GBE_0_RXN  EMMITSBURG_REV0P9  I119

P3E_PCH_BMC_RX_DP   @S9S_MB_2U_LIB.S9S_MB_2U(SCH_1):P3E_PCH_BMC_RX_DP
  J41    A18  PERP0  SCONN168_623403212  I115
  U4     M43  SATA_10_PCIE3_10_GBE_0_RXP  EMMITSBURG_REV0P9  I119

P3E_PCH_BMC_TX_C_DN   @S9S_MB_2U_LIB.S9S_MB_2U(SCH_1):P3E_PCH_BMC_TX_C_DN
  C644     2      2  Q_CAP_DIFFBUS  I194
  J41    A16  GND_A16  SCONN168_623403212  I115

P3E_PCH_BMC_TX_C_DP   @S9S_MB_2U_LIB.S9S_MB_2U(SCH_1):P3E_PCH_BMC_TX_C_DP
  C643     2      2  Q_CAP_DIFFBUS  I195
  J41    A15  REFCLKP1  SCONN168_623403212  I115

P3E_PCH_BMC_TX_DN   @S9S_MB_2U_LIB.S9S_MB_2U(SCH_1):P3E_PCH_BMC_TX_DN
  C644     1      1  Q_CAP_DIFFBUS  I194
  U4     W36  SATA_10_PCIE3_10_GBE_0_TXN  EMMITSBURG_REV0P9  I119

P3E_PCH_BMC_TX_DP   @S9S_MB_2U_LIB.S9S_MB_2U(SCH_1):P3E_PCH_BMC_TX_DP
  C643     1      1  Q_CAP_DIFFBUS  I195
  U4     Y37  SATA_10_PCIE3_10_GBE_0_TXP  EMMITSBURG_REV0P9  I119

P3E_PCH_M2_RX_C_DN<3>   @S9S_MB_2U_LIB.S9S_MB_2U(SCH_1):P3E_PCH_M2_RX_C_DN<3>
  C1420    1      1  Q_CAP_DIFFBUS  I243
  J59     43  PERP0||SATA-B-  SCONN75K_APCI0155P004A  I178

P3E_PCH_M2_RX_C_DP<3>   @S9S_MB_2U_LIB.S9S_MB_2U(SCH_1):P3E_PCH_M2_RX_C_DP<3>
  C1421    1      1  Q_CAP_DIFFBUS  I246
  J59     41  PERN0||SATA-B+  SCONN75K_APCI0155P004A  I178

P3E_PCH_M2_RX_DN<0>   @S9S_MB_2U_LIB.S9S_MB_2U(SCH_1):P3E_PCH_M2_RX_DN<0>
  J59      5  PERN3  SCONN75K_APCI0155P004A  I178
  U4     AE41  SATA_0_PCIE3_0_USB3_0_RXN  EMMITSBURG_REV0P9  I119

P3E_PCH_M2_RX_DN<1>   @S9S_MB_2U_LIB.S9S_MB_2U(SCH_1):P3E_PCH_M2_RX_DN<1>
  J59     17  PERN2  SCONN75K_APCI0155P004A  I178
  U4     AD40  SATA_1_PCIE3_1_USB3_1_RXN  EMMITSBURG_REV0P9  I119

P3E_PCH_M2_RX_DN<2>   @S9S_MB_2U_LIB.S9S_MB_2U(SCH_1):P3E_PCH_M2_RX_DN<2>
  J59     29  PERN1  SCONN75K_APCI0155P004A  I178
  U4     AC41  SATA_2_PCIE3_2_USB3_2_RXN  EMMITSBURG_REV0P9  I119

P3E_PCH_M2_RX_DN<3>   @S9S_MB_2U_LIB.S9S_MB_2U(SCH_1):P3E_PCH_M2_RX_DN<3>
  C1420    2      2  Q_CAP_DIFFBUS  I243
  U4     AB40  SATA_3_PCIE3_3_USB3_3_RXN  EMMITSBURG_REV0P9  I119

P3E_PCH_M2_RX_DN<4>   @S9S_MB_2U_LIB.S9S_MB_2U(SCH_1):P3E_PCH_M2_RX_DN<4>
  J41    A60  PERP13  SCONN168_623403212  I115
  U4     AA41  SATA_4_PCIE3_4_USB3_4_RXN  EMMITSBURG_REV0P9  I119

P3E_PCH_M2_RX_DP<0>   @S9S_MB_2U_LIB.S9S_MB_2U(SCH_1):P3E_PCH_M2_RX_DP<0>
  J59      7  PERP3  SCONN75K_APCI0155P004A  I178
  U4     AE43  SATA_0_PCIE3_0_USB3_0_RXP  EMMITSBURG_REV0P9  I119

P3E_PCH_M2_RX_DP<1>   @S9S_MB_2U_LIB.S9S_MB_2U(SCH_1):P3E_PCH_M2_RX_DP<1>
  J59     19  PERP2  SCONN75K_APCI0155P004A  I178
  U4     AD42  SATA_1_PCIE3_1_USB3_1_RXP  EMMITSBURG_REV0P9  I119

P3E_PCH_M2_RX_DP<2>   @S9S_MB_2U_LIB.S9S_MB_2U(SCH_1):P3E_PCH_M2_RX_DP<2>
  J59     31  PERP1  SCONN75K_APCI0155P004A  I178
  U4     AC43  SATA_2_PCIE3_2_USB3_2_RXP  EMMITSBURG_REV0P9  I119

P3E_PCH_M2_RX_DP<3>   @S9S_MB_2U_LIB.S9S_MB_2U(SCH_1):P3E_PCH_M2_RX_DP<3>
  C1421    2      2  Q_CAP_DIFFBUS  I246
  U4     AB42  SATA_3_PCIE3_3_USB3_3_RXP  EMMITSBURG_REV0P9  I119

P3E_PCH_M2_RX_DP<4>   @S9S_MB_2U_LIB.S9S_MB_2U(SCH_1):P3E_PCH_M2_RX_DP<4>
  J41    A59  PERN13  SCONN168_623403212  I115
  U4     AA43  SATA_4_PCIE3_4_USB3_4_RXP  EMMITSBURG_REV0P9  I119

P3E_PCH_M2_TX_C_DN<0>   @S9S_MB_2U_LIB.S9S_MB_2U(SCH_1):P3E_PCH_M2_TX_C_DN<0>
  C1105    2      2  Q_CAP_DIFFBUS  I169
  J59     13  PETP3  SCONN75K_APCI0155P004A  I178

P3E_PCH_M2_TX_C_DN<1>   @S9S_MB_2U_LIB.S9S_MB_2U(SCH_1):P3E_PCH_M2_TX_C_DN<1>
  C1103    2      2  Q_CAP_DIFFBUS  I166
  J59     25  PETP2  SCONN75K_APCI0155P004A  I178

P3E_PCH_M2_TX_C_DN<2>   @S9S_MB_2U_LIB.S9S_MB_2U(SCH_1):P3E_PCH_M2_TX_C_DN<2>
  C1101    2      2  Q_CAP_DIFFBUS  I164
  J59     37  PETP1  SCONN75K_APCI0155P004A  I178

P3E_PCH_M2_TX_C_DN<3>   @S9S_MB_2U_LIB.S9S_MB_2U(SCH_1):P3E_PCH_M2_TX_C_DN<3>
  C1099    2      2  Q_CAP_DIFFBUS  I163
  J59     47  PETN0||SATA-A-  SCONN75K_APCI0155P004A  I178

P3E_PCH_M2_TX_C_DN<4>   @S9S_MB_2U_LIB.S9S_MB_2U(SCH_1):P3E_PCH_M2_TX_C_DN<4>
  C1097    2      2  Q_CAP_DIFFBUS  I198
  J41    B60  PETP13  SCONN168_623403212  I115

P3E_PCH_M2_TX_C_DP<0>   @S9S_MB_2U_LIB.S9S_MB_2U(SCH_1):P3E_PCH_M2_TX_C_DP<0>
  C1104    2      2  Q_CAP_DIFFBUS  I167
  J59     11  PETN3  SCONN75K_APCI0155P004A  I178

P3E_PCH_M2_TX_C_DP<1>   @S9S_MB_2U_LIB.S9S_MB_2U(SCH_1):P3E_PCH_M2_TX_C_DP<1>
  C1102    2      2  Q_CAP_DIFFBUS  I168
  J59     23  PETN2  SCONN75K_APCI0155P004A  I178

P3E_PCH_M2_TX_C_DP<2>   @S9S_MB_2U_LIB.S9S_MB_2U(SCH_1):P3E_PCH_M2_TX_C_DP<2>
  C1100    2      2  Q_CAP_DIFFBUS  I165
  J59     35  PETN1  SCONN75K_APCI0155P004A  I178

P3E_PCH_M2_TX_C_DP<3>   @S9S_MB_2U_LIB.S9S_MB_2U(SCH_1):P3E_PCH_M2_TX_C_DP<3>
  C1098    2      2  Q_CAP_DIFFBUS  I162
  J59     49  PETP0||SATA-A+  SCONN75K_APCI0155P004A  I178

P3E_PCH_M2_TX_C_DP<4>   @S9S_MB_2U_LIB.S9S_MB_2U(SCH_1):P3E_PCH_M2_TX_C_DP<4>
  C1096    2      2  Q_CAP_DIFFBUS  I199
  J41    B59  PETN13  SCONN168_623403212  I115

P3E_PCH_M2_TX_DN<0>   @S9S_MB_2U_LIB.S9S_MB_2U(SCH_1):P3E_PCH_M2_TX_DN<0>
  C1105    1      1  Q_CAP_DIFFBUS  I169
  U4     AL32  SATA_0_PCIE3_0_USB3_0_TXN  EMMITSBURG_REV0P9  I119

P3E_PCH_M2_TX_DN<1>   @S9S_MB_2U_LIB.S9S_MB_2U(SCH_1):P3E_PCH_M2_TX_DN<1>
  C1103    1      1  Q_CAP_DIFFBUS  I166
  U4     AN36  SATA_1_PCIE3_1_USB3_1_TXN  EMMITSBURG_REV0P9  I119

P3E_PCH_M2_TX_DN<2>   @S9S_MB_2U_LIB.S9S_MB_2U(SCH_1):P3E_PCH_M2_TX_DN<2>
  C1101    1      1  Q_CAP_DIFFBUS  I164
  U4     AR36  SATA_2_PCIE3_2_USB3_2_TXN  EMMITSBURG_REV0P9  I119

P3E_PCH_M2_TX_DN<3>   @S9S_MB_2U_LIB.S9S_MB_2U(SCH_1):P3E_PCH_M2_TX_DN<3>
  C1099    1      1  Q_CAP_DIFFBUS  I163
  U4     AK34  SATA_3_PCIE3_3_USB3_3_TXN  EMMITSBURG_REV0P9  I119

P3E_PCH_M2_TX_DN<4>   @S9S_MB_2U_LIB.S9S_MB_2U(SCH_1):P3E_PCH_M2_TX_DN<4>
  C1097    1      1  Q_CAP_DIFFBUS  I198
  U4     AL36  SATA_4_PCIE3_4_USB3_4_TXN  EMMITSBURG_REV0P9  I119

P3E_PCH_M2_TX_DP<0>   @S9S_MB_2U_LIB.S9S_MB_2U(SCH_1):P3E_PCH_M2_TX_DP<0>
  C1104    1      1  Q_CAP_DIFFBUS  I167
  U4     AK31  SATA_0_PCIE3_0_USB3_0_TXP  EMMITSBURG_REV0P9  I119

P3E_PCH_M2_TX_DP<1>   @S9S_MB_2U_LIB.S9S_MB_2U(SCH_1):P3E_PCH_M2_TX_DP<1>
  C1102    1      1  Q_CAP_DIFFBUS  I168
  U4     AP34  SATA_1_PCIE3_1_USB3_1_TXP  EMMITSBURG_REV0P9  I119

P3E_PCH_M2_TX_DP<2>   @S9S_MB_2U_LIB.S9S_MB_2U(SCH_1):P3E_PCH_M2_TX_DP<2>
  C1100    1      1  Q_CAP_DIFFBUS  I165
  U4     AT37  SATA_2_PCIE3_2_USB3_2_TXP  EMMITSBURG_REV0P9  I119

P3E_PCH_M2_TX_DP<3>   @S9S_MB_2U_LIB.S9S_MB_2U(SCH_1):P3E_PCH_M2_TX_DP<3>
  C1098    1      1  Q_CAP_DIFFBUS  I162
  U4     AM34  SATA_3_PCIE3_3_USB3_3_TXP  EMMITSBURG_REV0P9  I119

P3E_PCH_M2_TX_DP<4>   @S9S_MB_2U_LIB.S9S_MB_2U(SCH_1):P3E_PCH_M2_TX_DP<4>
  C1096    1      1  Q_CAP_DIFFBUS  I199
  U4     AM37  SATA_4_PCIE3_4_USB3_4_TXP  EMMITSBURG_REV0P9  I119

P3V3            @S9S_MB_2U_LIB.S9S_MB_2U(SCH_1):P3V3
  C129     1      A  Q_CAPP      I54
  C130     1      A  Q_CAP       I56
  C135     1      A  Q_CAPP      I21
  C136     1      A  Q_CAP       I23
  C1078    1      A  Q_CAP       I88
  C1080    1      A  Q_CAP       I90
  C1082    1      A  Q_CAP       I96
  C1084    1      A  Q_CAP       I97
  C1086    1      A  Q_CAP       I98
  C1088    1      A  Q_CAP       I100
  C1208    1      A  Q_CAP       I94
  C1215    1      A  Q_CAP       I92
  C1216    1      A  Q_CAP       I91
  C1217    1      A  Q_CAP       I89
  C1218    1      A  Q_CAP       I189
  C1219    1      A  Q_CAP       I187
  C1339    1      A  Q_CAP       I66
  C1340    1      A  Q_CAP       I67
  C1446    1      A  Q_CAP       I37
  C1447    1      A  Q_CAP       I35
  C1456    1      A  Q_CAP       I57
  C1457    1      A  Q_CAP       I55
  C1466    1      A  Q_CAP       I88
  C1467    1      A  Q_CAP       I90
  C1476    1      A  Q_CAP       I88
  C1477    1      A  Q_CAP       I91
  C1603    1      A  Q_CAPP      I140
  C1604    1      A  Q_CAP       I141
  D7       1      1  BAT547F     I69
  J33    A42    RFU  SCONN84_123318136  I53
  J34    A42    RFU  SCONN84_123318136  I43
  J35     A3  SIGNAL_A3  SCONN140_G64V3431BHR  I64
  J35     A4  GND_A4  SCONN140_G64V3431BHR  I64
  J55    A68  SIGNAL_A68  SCONN140_G64V3431BHR  I150
  J55    A69  SIGNAL_A69  SCONN140_G64V3431BHR  I150
  J55    B69  SIGNAL_B69  SCONN140_G64V3431BHR  I150
  J57    A68  SIGNAL_A68  SCONN140_G64V3431BHR  I242
  J57    A69  SIGNAL_A69  SCONN140_G64V3431BHR  I242
  J57    B69  SIGNAL_B69  SCONN140_G64V3431BHR  I242
  J59      2  3.3V_1  SCONN75K_APCI0155P004A  I178
  J59      4  3.3V_2  SCONN75K_APCI0155P004A  I178
  J59     12  3.3V_3  SCONN75K_APCI0155P004A  I178
  J59     14  3.3V_4  SCONN75K_APCI0155P004A  I178
  J59     16  3.3V_5  SCONN75K_APCI0155P004A  I178
  J59     18  3.3V_6  SCONN75K_APCI0155P004A  I178
  J59     70  3.3V_7  SCONN75K_APCI0155P004A  I178
  J59     72  3.3V_8  SCONN75K_APCI0155P004A  I178
  J59     74  3.3V_9  SCONN75K_APCI0155P004A  I178
  J61     A7  SMBCLK  SCONN84_123318136  I49
  J61     A8  SMBDAT  SCONN84_123318136  I49
  J61     A9  SMBRST_N  SCONN84_123318136  I49
  J89    B135   B135  SCONN280_ME1028040102011  I282
  J89    B136   B136  SCONN280_ME1028040102011  I282
  J89    B137   B137  SCONN280_ME1028040102011  I282
  J89    B138   B138  SCONN280_ME1028040102011  I282
  J89    B139   B139  SCONN280_ME1028040102011  I282
  J89    B140   B140  SCONN280_ME1028040102011  I282
  L3       1      1  Q_INDUCTOR  I170
  L4       1      1  Q_INDUCTOR  I177
  PQ2      1      1  MOSFET_NCH_1D3S  I90
  PQ2      2      2  MOSFET_NCH_1D3S  I90
  PQ2      3      3  MOSFET_NCH_1D3S  I90
  PR403    1      A  Q_RES       I36
  PR441    1      A  Q_RES       I176
  PR443    1      A  Q_RES       I15
  PR632    1      A  Q_RES       I26
  PR633    1      A  Q_RES       I14
  PR636    1      A  Q_RES       I337
  PR640    1      A  Q_RES       I34
  PR677    1      A  Q_RES       I28
  PR699    1      A  Q_RES       I16
  PR703    1      A  Q_RES       I235
  PR704    1      A  Q_RES       I219
  PR707    1      A  Q_RES       I14
  R112     1      A  Q_RES       I413
  R241     1      A  Q_RES       I167
  R242     1      A  Q_RES       I169
  R484     1      A  Q_RES       I170
  R567     1      A  Q_RES       I179
  R569     1      A  Q_RES       I185
  R573     1      A  Q_RES       I194
  R1000    1      A  Q_RES       I52
  R1001    1      A  Q_RES       I55
  R1002    1      A  Q_RES       I34
  R1003    1      A  Q_RES       I38
  R1542    1      A  Q_RES       I418
  R1706    1      A  Q_RES       I68
  R1788    1      A  Q_RES       I31
  U79      3   DIS2  SLG55221120010VTR  I62
  U79      6  S/DIS1  SLG55221120010VTR  I62

P3V3_AUX        @S9S_MB_2U_LIB.S9S_MB_2U(SCH_1):P3V3_AUX
  C1       1      A  Q_CAP       I15
  C2       1      A  Q_CAP       I192
  C5       1      A  Q_CAP       I120
  C8       1      A  Q_CAP       I121
  C11      1      A  Q_CAP       I121
  C14      1      A  Q_CAP       I120
  C17      1      A  Q_CAP       I120
  C20      1      A  Q_CAP       I123
  C23      1      A  Q_CAP       I121
  C26      1      A  Q_CAP       I122
  C29      1      A  Q_CAP       I123
  C32      1      A  Q_CAP       I122
  C35      1      A  Q_CAP       I122
  C38      1      A  Q_CAP       I123
  C41      1      A  Q_CAP       I121
  C44      1      A  Q_CAP       I121
  C47      1      A  Q_CAP       I56
  C50      1      A  Q_CAP       I122
  C53      1      A  Q_CAP       I122
  C56      1      A  Q_CAP       I121
  C59      1      A  Q_CAP       I121
  C62      1      A  Q_CAP       I124
  C65      1      A  Q_CAP       I122
  C68      1      A  Q_CAP       I122
  C71      1      A  Q_CAP        I4
  C72      1      A  Q_CAP       I116
  C75      1      A  Q_CAP       I124
  C78      1      A  Q_CAP       I54
  C81      1      A  Q_CAP       I120
  C84      1      A  Q_CAP       I121
  C87      1      A  Q_CAP       I121
  C90      1      A  Q_CAP       I122
  C93      1      A  Q_CAP       I122
  C96      1      A  Q_CAP       I123
  C131     1      A  Q_CAP       I103
  C132     1      A  Q_CAP       I106
  C137     1      A  Q_CAP       I24
  C138     1      A  Q_CAP       I26
  C174     1      A  Q_CAP       I151
  C188     1      A  Q_CAP       I44
  C536     1      A  Q_CAP       I182
  C537     1      A  Q_CAP       I24
  C538     1      A  Q_CAP       I84
  C539     1      A  Q_CAP       I70
  C540     1      A  Q_CAP       I81
  C541     1      A  Q_CAP       I61
  C542     1      A  Q_CAP       I80
  C543     1      A  Q_CAP       I100
  C544     1      A  Q_CAP       I94
  C545     1      A  Q_CAP       I93
  C546     1      A  Q_CAP       I135
  C551     1      A  Q_CAP       I105
  C553     1      A  Q_CAP       I40
  C554     1      A  Q_CAP       I52
  C561     1      A  Q_CAP       I18
  C562     1      A  Q_CAP       I31
  C563     1      A  Q_CAP       I50
  C569     1      A  Q_CAP       I22
  C570     1      A  Q_CAP       I33
  C578     1      A  Q_CAP       I169
  C579     1      A  Q_CAP       I123
  C580     1      A  Q_CAP       I165
  C581     1      A  Q_CAP       I148
  C592     1      A  Q_CAP       I393
  C593     1      A  Q_CAP       I395
  C629     1      A  Q_CAP       I55
  C630     1      A  Q_CAP       I10
  C631     1      A  Q_CAP       I75
  C639     1      A  Q_CAP       I59
  C640     1      A  Q_CAP       I47
  C641     1      A  Q_CAP       I16
  C1046    1      A  Q_CAP       I40
  C1053    1      A  Q_CAP       I29
  C1054    1      A  Q_CAP       I30
  C1061    1      A  Q_CAP       I53
  C1069    1      A  Q_CAP       I191
  C1107    1      A  Q_CAP       I248
  C1108    1      A  Q_CAP       I251
  C1110    1      A  Q_CAP       I240
  C1111    1      A  Q_CAP       I244
  C1113    1      A  Q_CAP       I239
  C1114    1      A  Q_CAP       I243
  C1118    1      A  Q_CAP       I236
  C1119    1      A  Q_CAP       I242
  C1122    1      A  Q_CAP       I235
  C1123    1      A  Q_CAP       I241
  C1127    1      A  Q_CAP       I222
  C1128    1      A  Q_CAP       I226
  C1133    1      A  Q_CAP       I221
  C1134    1      A  Q_CAP       I225
  C1138    1      A  Q_CAP       I218
  C1139    1      A  Q_CAP       I224
  C1142    1      A  Q_CAP       I217
  C1143    1      A  Q_CAP       I223
  C1146    1      A  Q_CAP       I210
  C1147    1      A  Q_CAP       I214
  C1150    1      A  Q_CAP       I209
  C1151    1      A  Q_CAP       I213
  C1152    1      A  Q_CAP       I206
  C1153    1      A  Q_CAP       I212
  C1154    1      A  Q_CAP       I205
  C1155    1      A  Q_CAP       I211
  C1156    1      A  Q_CAP       I184
  C1157    1      A  Q_CAP       I187
  C1158    1      A  Q_CAP       I191
  C1159    1      A  Q_CAP       I183
  C1161    1      A  Q_CAP       I186
  C1162    1      A  Q_CAP       I190
  C1163    1      A  Q_CAP       I180
  C1164    1      A  Q_CAP       I182
  C1165    1      A  Q_CAP       I189
  C1167    1      A  Q_CAP       I181
  C1168    1      A  Q_CAP       I188
  C1173    1      A  Q_CAP        I4
  C1175    1      A  Q_CAP       I24
  C1184    1      A  Q_CAP       I91
  C1191    1      A  Q_CAP       I89
  C1201    1      A  Q_CAP       I87
  C1206    1      A  Q_CAP       I78
  C1241    1      A  Q_CAP       I115
  C1243    1      A  Q_CAP       I83
  C1245    1      A  Q_CAP       I81
  C1274    1      A  Q_CAP       I59
  C1275    1      A  Q_CAP       I49
  C1288    1      A  Q_CAP       I112
  C1289    1      A  Q_CAP       I110
  C1290    1      A  Q_CAP       I43
  C1291    1      A  Q_CAP       I16
  C1292    1      A  Q_CAP       I90
  C1305    1      A  Q_CAP       I52
  C1315    1      A  Q_CAP        I8
  C1317    1      A  Q_CAP       I51
  C1320    1      A  Q_CAP       I134
  C1321    1      A  Q_CAP       I55
  C1322    1      A  Q_CAP       I27
  C1332    1      A  Q_CAP       I63
  C1333    1      A  Q_CAP       I64
  C1338    1      A  Q_CAP       I65
  C1347    1      A  Q_CAP        I3
  C1438    1      A  Q_CAP       I49
  C1445    1      A  Q_CAP       I38
  C1448    1      A  Q_CAP       I31
  C1455    1      A  Q_CAP       I58
  C1465    1      A  Q_CAP       I68
  C1475    1      A  Q_CAP       I87
  C1481    1      A  Q_CAP       I41
  C1482    1      A  Q_CAP        I7
  C1485    1      A  Q_CAP       I58
  C1486    1      A  Q_CAP       I24
  C1588    1      A  Q_CAP       I39
  C1589    1      A  Q_CAP       I62
  C1590    1      A  Q_CAP       I82
  C1591    1      A  Q_CAP       I89
  C1592    1      A  Q_CAP        I2
  C1593    1      A  Q_CAP       I22
  C1594    1      A  Q_CAP       I39
  C1595    1      A  Q_CAP       I44
  C1599    1      A  Q_CAP       I41
  C1600    1      A  Q_CAP       I44
  C1605    1      A  Q_CAP       I142
  C1606    1      A  Q_CAP       I143
  C1607    1      A  Q_CAP       I105
  J1       3  VIN_MGMT  SCONN288_ADR50001P013C01  I198
  J2       3  VIN_MGMT  SCONN288_ADR50001P003C01  I177
  J3       3  VIN_MGMT  SCONN288_ADR50001P013C01  I11
  J4       3  VIN_MGMT  SCONN288_ADR50001P003C01  I23
  J5       3  VIN_MGMT  SCONN288_ADR50001P013C01  I24
  J6       3  VIN_MGMT  SCONN288_ADR50001P003C01  I46
  J7       3  VIN_MGMT  SCONN288_ADR50001P013C01  I12
  J8       3  VIN_MGMT  SCONN288_ADR50001P003C01  I50
  J9       3  VIN_MGMT  SCONN288_ADR50001P013C01  I12
  J10      3  VIN_MGMT  SCONN288_ADR50001P003C01  I13
  J11      3  VIN_MGMT  SCONN288_ADR50001P013C01  I25
  J12      3  VIN_MGMT  SCONN288_ADR50001P003C01  I24
  J13      3  VIN_MGMT  SCONN288_ADR50001P013C01  I11
  J14      3  VIN_MGMT  SCONN288_ADR50001P003C01  I47
  J15      3  VIN_MGMT  SCONN288_ADR50001P013C01  I48
  J16      3  VIN_MGMT  SCONN288_ADR50001P003C01   I6
  J17      3  VIN_MGMT  SCONN288_ADR50001P013C01  I12
  J18      3  VIN_MGMT  SCONN288_ADR50001P003C01  I24
  J19      3  VIN_MGMT  SCONN288_ADR50001P013C01  I25
  J20      3  VIN_MGMT  SCONN288_ADR50001P003C01  I47
  J21      3  VIN_MGMT  SCONN288_ADR50001P013C01  I13
  J22      3  VIN_MGMT  SCONN288_ADR50001P003C01  I51
  J23      3  VIN_MGMT  SCONN288_ADR50001P013C01  I25
  J24      3  VIN_MGMT  SCONN288_ADR50001P003C01  I178
  J25      3  VIN_MGMT  SCONN288_ADR50001P013C01  I180
  J26      3  VIN_MGMT  SCONN288_ADR50001P003C01  I180
  J27      3  VIN_MGMT  SCONN288_ADR50001P013C01  I179
  J28      3  VIN_MGMT  SCONN288_ADR50001P003C01  I47
  J29      3  VIN_MGMT  SCONN288_ADR50001P013C01  I179
  J30      3  VIN_MGMT  SCONN288_ADR50001P003C01  I179
  J31      3  VIN_MGMT  SCONN288_ADR50001P013C01  I180
  J32      3  VIN_MGMT  SCONN288_ADR50001P003C01  I179
  J33    B11  3_3VAUX  SCONN84_123318136  I53
  J34    B11  3_3VAUX  SCONN84_123318136  I43
  J35    B15  SIGNAL_B15  SCONN140_G64V3431BHR  I64
  J42     52     52  SCONN60_QSH03001LDAKTR  I44
  J43      4      4  CONN10_G2100HT0038071  I42
  J44      1      1  CONN24_52SH90245BRD  I125
  J44      3      3  CONN24_52SH90245BRD  I125
  J55    A11  SIGNAL_A11  SCONN140_G64V3431BHR  I150
  J57    A11  SIGNAL_A11  SCONN140_G64V3431BHR  I242
  J61    B11  3_3VAUX  SCONN84_123318136  I49
  J62    B11  3_3VAUX  SCONN84_123318136  I33
  J87    B11  3_3VAUX  SCONN84_123318136  I43
  J88    B11  3_3VAUX  SCONN84_123318136  I16
  J89    B22    B22  SCONN280_ME1028040102011  I239
  L1       1      1  Q_INDUCTOR  I20
  L13      1      1  Q_INDUCTOR  I41
  L14      1      1  Q_INDUCTOR  I60
  L36      1      1  Q_INDUCTOR  I228
  OSC1     4    VDD  OSC4_SIT1602AI2233E50000000D  I58
  OSC2     4    VDD  Q_OSC4P     I132
  PC569    2      B  Q_CAP       I35
  PC1866    1      A  Q_CAPP      I38
  PC1867    1      A  Q_CAPP      I39
  PC1868    1      A  Q_CAP       I40
  PC1869    1      A  Q_CAP       I45
  PL66     2      2  Q_INDUCTOR  I37
  PQ2      5      5  MOSFET_NCH_1D3S  I90
  PR73     1      A  Q_RES       I31
  PR109    1      A  Q_RES       I68
  PR117    1      A  Q_RES       I31
  PR130    2      B  Q_RES       I95
  PR131    1      A  Q_RES       I80
  PR160    1      A  Q_RES       I71
  PR169    1      A  Q_RES       I51
  PR172    1      A  Q_RES       I53
  PR176    2      B  Q_RES       I121
  PR177    1      A  Q_RES       I55
  PR186    1      A  Q_RES       I38
  PR206    1      A  Q_RES       I233
  PR215    1      A  Q_RES       I245
  PR217    1      A  Q_RES       I247
  PR220    2      B  Q_RES       I274
  PR223    1      A  Q_RES       I261
  PR232    1      A  Q_RES       I203
  PR241    1      A  Q_RES       I214
  PR243    1      A  Q_RES       I215
  PR249    1      A  Q_RES       I218
  PR262    1      A  Q_RES       I52
  PR270    1      A  Q_RES       I17
  PR283    2      B  Q_RES       I89
  PR284    1      A  Q_RES       I92
  PR307    1      A  Q_RES       I198
  PR323    2      B  Q_RES       I278
  PR335    1      A  Q_RES       I40
  PR361    1      A  Q_RES       I43
  PR370    1      A  Q_RES       I15
  PR372    1      A  Q_RES       I17
  PR375    2      B  Q_RES       I72
  PR378    1      A  Q_RES       I60
  PR395    1      A  Q_RES       I10
  PR523    1      A  Q_RES       I41
  PR524    1      A  Q_RES       I42
  PR570    1      A  Q_RES       I26
  PR571    1      A  Q_RES       I25
  PR831    2      B  Q_RES       I36
  PR836    2      B  Q_RES       I25
  PR1302    1      A  Q_RES       I33
  PR1309    1      A  Q_RES       I25
  PR1313    1      A  Q_RES       I23
  PR1317    1      A  Q_RES       I174
  PR1320    1      A  Q_RES       I187
  PR1326    1      A  Q_RES       I21
  PR1335    1      A  Q_RES        I5
  PR1338    1      A  Q_RES        I8
  PR1647    1      A  Q_RES       I27
  Q33      D      D  MOSFET_PCH_GDS_ESD_PROTECTED  I242
  R8       1      A  Q_RES       I59
  R71      1      A  Q_RES       I60
  R85      1      A  Q_RES       I310
  R86      1      A  Q_RES       I240
  R87      1      A  Q_RES       I79
  R111     1      A  Q_RES       I24
  R139     2      B  Q_RES       I249
  R270     1      A  Q_RES       I93
  R271     1      A  Q_RES       I92
  R272     1      A  Q_RES       I90
  R273     1      A  Q_RES       I89
  R274     1      A  Q_RES       I88
  R283     1      A  Q_RES       I147
  R284     1      A  Q_RES       I148
  R285     1      A  Q_RES       I150
  R286     1      A  Q_RES       I151
  R287     1      A  Q_RES       I152
  R319     1      A  Q_RES       I19
  R320     1      A  Q_RES       I20
  R321     1      A  Q_RES       I21
  R325     1      A  Q_RES       I28
  R326     1      A  Q_RES       I29
  R327     1      A  Q_RES       I30
  R331     1      A  Q_RES       I20
  R333     1      A  Q_RES        I6
  R335     1      A  Q_RES        I5
  R367     1      A  Q_RES       I11
  R369     1      A  Q_RES       I16
  R371     1      A  Q_RES       I45
  R374     1      A  Q_RES       I60
  R378     1      A  Q_RES       I77
  R380     1      A  Q_RES       I78
  R388     1      A  Q_RES       I108
  R391     1      A  Q_RES       I108
  R392     1      A  Q_RES       I335
  R394     2      B  Q_RES       I71
  R395     2      B  Q_RES       I77
  R398     2      B  Q_RES       I71
  R399     2      B  Q_RES       I77
  R402     2      B  Q_RES       I204
  R453     1      A  Q_RES       I77
  R456     1      A  Q_RES       I66
  R463     1      A  Q_RES       I29
  R478     1      A  Q_RES       I176
  R487     1      A  Q_RES       I173
  R494     1      A  Q_RES        I4
  R498     1      A  Q_RES       I24
  R502     1      A  Q_RES       I68
  R512     1      A  Q_RES       I267
  R514     1      A  Q_RES       I259
  R536     1      A  Q_RES        I7
  R538     1      A  Q_RES        I9
  R540     1      A  Q_RES       I10
  R562     1      A  Q_RES       I280
  R592     2      B  Q_RES       I173
  R601     2      B  Q_RES       I172
  R606     2      B  Q_RES       I175
  R607     1      A  Q_RES       I21
  R609     1      A  Q_RES       I39
  R611     1      A  Q_RES       I43
  R613     1      A  Q_RES       I18
  R615     1      A  Q_RES       I51
  R617     1      A  Q_RES       I54
  R619     1      A  Q_RES       I48
  R621     1      A  Q_RES       I55
  R625     1      A  Q_RES       I24
  R627     1      A  Q_RES       I14
  R629     1      A  Q_RES       I13
  R635     2      B  Q_RES       I234
  R640     2      B  Q_RES       I164
  R641     1      A  Q_RES       I54
  R643     1      A  Q_RES       I58
  R645     1      A  Q_RES       I57
  R649     2      B  Q_RES       I174
  R650     1      A  Q_RES       I32
  R651     1      A  Q_RES       I170
  R652     1      A  Q_RES       I169
  R653     1      A  Q_RES       I163
  R654     1      A  Q_RES       I164
  R696     1      A  Q_RES       I63
  R711     1      A  Q_RES       I27
  R713     1      A  Q_RES       I47
  R715     1      A  Q_RES       I28
  R717     1      A  Q_RES       I45
  R719     1      A  Q_RES       I29
  R721     1      A  Q_RES       I62
  R727     2      B  Q_RES       I236
  R728     1      A  Q_RES       I87
  R730     1      A  Q_RES       I86
  R732     1      A  Q_RES       I85
  R735     1      A  Q_RES       I123
  R739     1      A  Q_RES       I109
  R740     1      A  Q_RES       I107
  R766     1      A  Q_RES       I111
  R767     1      A  Q_RES       I113
  R768     1      A  Q_RES       I112
  R770     2      B  Q_RES       I239
  R778     1      A  Q_RES       I15
  R781     1      A  Q_RES        I9
  R783     1      A  Q_RES       I10
  R785     1      A  Q_RES       I13
  R791     1      A  Q_RES       I33
  R792     1      A  Q_RES       I32
  R793     1      A  Q_RES       I116
  R794     1      A  Q_RES       I117
  R795     1      A  Q_RES       I134
  R796     1      A  Q_RES       I135
  R797     1      A  Q_RES       I136
  R798     1      A  Q_RES       I137
  R912     1      A  Q_RES       I278
  R913     2      B  Q_RES       I241
  R914     1      A  Q_RES       I162
  R919     1      A  Q_RES       I75
  R927     1      A  Q_RES       I61
  R928     1      A  Q_RES       I60
  R929     1      A  Q_RES       I59
  R940     1      A  Q_RES       I145
  R941     1      A  Q_RES       I146
  R942     1      A  Q_RES       I147
  R943     1      A  Q_RES       I148
  R944     1      A  Q_RES       I153
  R945     1      A  Q_RES       I154
  R946     1      A  Q_RES       I156
  R947     1      A  Q_RES       I157
  R952     1      A  Q_RES       I201
  R965     1      A  Q_RES       I15
  R966     1      A  Q_RES       I29
  R967     1      A  Q_RES       I14
  R968     1      A  Q_RES       I27
  R977     1      A  Q_RES        I8
  R978     1      A  Q_RES       I16
  R979     1      A  Q_RES        I6
  R980     1      A  Q_RES       I14
  R1004    1      A  Q_RES       I35
  R1065    1      A  Q_RES       I146
  R1066    1      A  Q_RES       I145
  R1067    1      A  Q_RES       I148
  R1068    1      A  Q_RES       I147
  R1069    1      A  Q_RES       I149
  R1070    1      A  Q_RES       I150
  R1071    1      A  Q_RES       I154
  R1072    1      A  Q_RES       I151
  R1089    1      A  Q_RES       I31
  R1090    1      A  Q_RES       I32
  R1091    1      A  Q_RES       I30
  R1092    1      A  Q_RES       I29
  R1099    1      A  Q_RES       I136
  R1104    1      A  Q_RES       I51
  R1106    1      A  Q_RES       I415
  R1123    1      A  Q_RES       I142
  R1125    1      A  Q_RES       I134
  R1127    1      A  Q_RES       I133
  R1129    1      A  Q_RES       I172
  R1133    1      A  Q_RES       I155
  R1138    1      A  Q_RES       I61
  R1143    1      A  Q_RES       I343
  R1146    1      A  Q_RES       I358
  R1149    1      A  Q_RES       I367
  R1150    1      A  Q_RES       I368
  R1194    1      A  Q_RES       I277
  R1195    1      A  Q_RES       I241
  R1198    1      A  Q_RES       I48
  R1204    1      A  Q_RES       I273
  R1216    1      A  Q_RES       I36
  R1217    1      A  Q_RES       I37
  R1220    1      A  Q_RES       I63
  R1222    1      A  Q_RES       I57
  R1223    2      B  Q_RES       I49
  R1224    2      B  Q_RES       I50
  R1225    2      B  Q_RES       I51
  R1256    1      A  Q_RES        I1
  R1257    1      A  Q_RES        I4
  R1258    1      A  Q_RES        I6
  R1259    1      A  Q_RES        I8
  R1305    1      A  Q_RES       I272
  R1314    1      A  Q_RES       I161
  R1319    2      B  Q_RES        I2
  R1320    1      A  Q_RES       I68
  R1321    2      B  Q_RES        I3
  R1325    1      A  Q_RES       I75
  R1331    1      A  Q_RES       I95
  R1332    1      A  Q_RES       I93
  R1336    2      B  Q_RES       I177
  R1339    1      A  Q_RES       I81
  R1370    1      A  Q_RES       I98
  R1376    1      A  Q_RES       I35
  R1377    1      A  Q_RES       I11
  R1380    1      A  Q_RES       I31
  R1381    1      A  Q_RES        I7
  R1382    1      A  Q_RES       I20
  R1383    1      A  Q_RES        I1
  R1384    2      B  Q_RES        I4
  R1385    2      B  Q_RES        I5
  R1386    2      B  Q_RES        I6
  R1387    2      B  Q_RES        I7
  R1396    2      B  Q_RES       I167
  R1399    2      B  Q_RES       I269
  R1401    2      B  Q_RES       I277
  R1434    2      B  Q_RES       I216
  R1435    2      B  Q_RES       I221
  R1436    2      B  Q_RES       I278
  R1437    2      B  Q_RES       I224
  R1438    2      B  Q_RES       I226
  R1439    2      B  Q_RES       I229
  R1440    2      B  Q_RES       I231
  R1449    1      A  Q_RES       I41
  R1450    1      A  Q_RES       I42
  R1451    2      B  Q_RES       I109
  R1452    2      B  Q_RES       I112
  R1453    2      B  Q_RES       I120
  R1454    2      B  Q_RES       I121
  R1458    1      A  Q_RES       I50
  R1459    1      A  Q_RES       I51
  R1460    2      B  Q_RES       I176
  R1465    1      A  Q_RES       I226
  R1467    1      A  Q_RES       I232
  R1471    1      A  Q_RES       I267
  R1473    2      B  Q_RES       I261
  R1474    2      B  Q_RES       I262
  R1475    1      A  Q_RES       I44
  R1477    1      A  Q_RES       I47
  R1483    1      A  Q_RES       I265
  R1488    2      B  Q_RES       I279
  R1492    2      B  Q_RES       I272
  R1493    2      B  Q_RES       I287
  R1496    1      A  Q_RES       I71
  R1498    1      A  Q_RES       I76
  R1522    1      A  Q_RES       I97
  R1528    2      B  Q_RES       I163
  R1529    2      B  Q_RES       I162
  R1532    2      B  Q_RES       I370
  R1533    2      B  Q_RES       I369
  R1534    2      B  Q_RES       I373
  R1540    1      A  Q_RES       I33
  R1545    2      B  Q_RES       I137
  R1546    2      B  Q_RES       I138
  R1549    1      A  Q_RES       I393
  R1550    1      A  Q_RES       I392
  R1551    1      A  Q_RES       I234
  R1554    1      A  Q_RES       I62
  R1558    2      B  Q_RES       I318
  R1575    1      A  Q_RES       I308
  R1576    1      A  Q_RES       I304
  R1579    1      A  Q_RES       I343
  R1580    1      A  Q_RES       I341
  R1581    2      B  Q_RES       I142
  R1582    2      B  Q_RES       I141
  R1583    2      B  Q_RES       I144
  R1584    1      A  Q_RES       I114
  R1586    1      A  Q_RES       I100
  R1588    1      A  Q_RES       I455
  R1593    1      A  Q_RES       I42
  R1601    2      B  Q_RES       I151
  R1608    1      A  Q_RES       I203
  R1609    1      A  Q_RES       I88
  R1610    1      A  Q_RES       I85
  R1613    2      B  Q_RES       I97
  R1615    2      B  Q_RES       I95
  R1617    2      B  Q_RES       I203
  R1645    1      A  Q_RES       I20
  R1658    2      B  Q_RES       I174
  R1659    2      B  Q_RES       I181
  R1660    2      B  Q_RES       I328
  R1667    1      A  Q_RES       I183
  R1675    2      B  Q_RES       I82
  R1681    1      A  Q_RES       I296
  R1690    1      A  Q_RES        I2
  R1691    1      A  Q_RES       I59
  R1694    1      A  Q_RES       I46
  R1712    2      B  Q_RES       I129
  R1713    2      B  Q_RES       I130
  R1731    2      B  Q_RES       I125
  R1732    2      B  Q_RES       I124
  R1741    2      B  Q_RES       I330
  R1765    2      B  Q_RES       I13
  R1784    1      A  Q_RES       I14
  R1786    1      A  Q_RES       I27
  R1794    1      A  Q_RES       I10
  R1809    1      A  Q_RES       I89
  R1813    1      A  Q_RES       I79
  R1820    1      A  Q_RES       I35
  R1822    1      A  Q_RES       I152
  R1823    1      A  Q_RES       I152
  R1828    2      B  Q_RES       I188
  R1841    1      A  Q_RES       I245
  R1854    1      A  Q_RES       I43
  R1857    1      A  Q_RES       I29
  R1905    1      A  Q_RES       I404
  R1906    1      A  Q_RES       I408
  R1907    1      A  Q_RES       I399
  R1908    1      A  Q_RES       I402
  R1955    1      A  Q_RES       I72
  R1958    1      A  Q_RES       I303
  R1963    1      A  Q_RES       I83
  R1964    1      A  Q_RES       I80
  R1967    2      B  Q_RES       I76
  R1968    2      B  Q_RES       I86
  R1973    1      A  Q_RES       I85
  R1974    1      A  Q_RES       I78
  R1977    2      B  Q_RES       I80
  R1978    2      B  Q_RES       I88
  R1979    2      B  Q_RES       I87
  R1983    1      A  Q_RES        I5
  R1984    1      A  Q_RES       I27
  R1987    2      B  Q_RES       I12
  R1988    2      B  Q_RES       I11
  R1989    2      B  Q_RES       I10
  R1993    1      A  Q_RES        I3
  R2000    2      B  Q_RES       I11
  R2001    2      B  Q_RES       I10
  R2014    1      A  Q_RES       I36
  R2015    1      A  Q_RES        I2
  R2017    1      A  Q_RES       I17
  R2018    1      A  Q_RES       I55
  R2019    1      A  Q_RES       I21
  R2022    1      A  Q_RES       I67
  R2023    1      A  Q_RES       I33
  R2036    1      A  Q_RES       I95
  R2037    1      A  Q_RES       I130
  R2040    1      A  Q_RES       I166
  R2041    1      A  Q_RES       I119
  R2042    1      A  Q_RES       I107
  R2043    1      A  Q_RES       I147
  R2046    1      A  Q_RES       I116
  R2047    1      A  Q_RES       I136
  R2051    1      A  Q_RES       I124
  R2052    1      A  Q_RES       I125
  R2053    1      A  Q_RES       I140
  R2054    1      A  Q_RES       I141
  R2055    1      A  Q_RES       I143
  R2056    1      A  Q_RES       I142
  R2057    1      A  Q_RES       I147
  R2058    1      A  Q_RES       I146
  R2079    2      B  Q_RES       I117
  R2080    2      B  Q_RES       I113
  R2081    2      B  Q_RES       I112
  R2089    1      A  Q_RES       I48
  R2091    1      A  Q_RES       I71
  R2093    1      A  Q_RES       I49
  R2095    1      A  Q_RES       I70
  R2097    1      A  Q_RES       I50
  R2099    1      A  Q_RES       I66
  R2121    1      A  Q_RES       I11
  R2122    1      A  Q_RES       I18
  R2123    1      A  Q_RES       I30
  R2124    1      A  Q_RES       I35
  R2125    1      A  Q_RES       I12
  R2126    1      A  Q_RES       I17
  R2127    1      A  Q_RES       I29
  R2128    1      A  Q_RES       I34
  R2133    1      A  Q_RES       I80
  R2138    1      A  Q_RES       I50
  R2140    1      A  Q_RES       I328
  R2157    1      A  Q_RES       I171
  R2158    1      A  Q_RES       I402
  R2167    1      A  Q_RES        I1
  R2168    1      A  Q_RES       I27
  R2170    1      A  Q_RES       I132
  R2173    1      A  Q_RES       I133
  R2174    1      A  Q_RES       I134
  R2175    2      B  Q_RES       I148
  R2176    2      B  Q_RES       I149
  R2177    2      B  Q_RES       I147
  R2180    1      A  Q_RES       I465
  R2191    1      A  Q_RES       I113
  R2193    1      A  Q_RES       I115
  R2195    1      A  Q_RES       I114
  R2197    1      A  Q_RES       I112
  R2198    1      A  Q_RES       I123
  R2199    1      A  Q_RES       I124
  R2200    1      A  Q_RES       I122
  R2201    1      A  Q_RES       I121
  R2202    1      A  Q_RES       I120
  R2203    1      A  Q_RES       I119
  R2204    1      A  Q_RES       I183
  R2205    1      A  Q_RES       I182
  R2206    1      A  Q_RES       I154
  R2207    1      A  Q_RES       I155
  R2212    2      B  Q_RES       I202
  R2213    2      B  Q_RES       I203
  R2330    1      A  Q_RES        I7
  R2338    1      A  Q_RES       I156
  R2367    1      A  Q_RES       I18
  R2384    1      A  Q_RES       I161
  U1     BA21  VCCCPLD_3P3V0  SOCKET4677_AZIFS054P001C01   I8
  U1     BC21  VCCCPLD_3P3V1  SOCKET4677_AZIFS054P001C01   I8
  U2     BA21  VCCCPLD_3P3V0  SOCKET4677_AZIFS054P001C01   I8
  U2     BC21  VCCCPLD_3P3V1  SOCKET4677_AZIFS054P001C01   I8
  U4     AD15  VCCP_3P3_DSW_AD15  EMMITSBURG_REV0P9  I11
  U4     AD17  VCCP_GPPI_1P8_3P3  EMMITSBURG_REV0P9  I11
  U4     AF17  VCCP_3P3_AF17  EMMITSBURG_REV0P9  I11
  U4     AG17  VCCP_3P3_AG17  EMMITSBURG_REV0P9  I11
  U4     AJ17  VCCP_3P3_AJ17  EMMITSBURG_REV0P9  I11
  U4     AK15  VCCP_3P3_AK15  EMMITSBURG_REV0P9  I11
  U4     AL17  VCCP_3P3_AL17  EMMITSBURG_REV0P9  I11
  U4     AN20  VCCP_GPPE_1P8_3P3  EMMITSBURG_REV0P9  I11
  U4     P21  VCCP_3P3_P21  EMMITSBURG_REV0P9  I11
  U4     T15  VCCP_GPPD_1P8_3P3  EMMITSBURG_REV0P9  I11
  U4     V15  VCCP_3P3_DSW_V15  EMMITSBURG_REV0P9  I11
  U10     16    VCC  PCA9546APWR  I194
  U14     16    VCC  IDTQS3VH257QG  I17
  U15     16    VCC  IDTQS3VH257QG  I25
  U16      5    VCC  NC7SZ66M5X  I88
  U17     14    VCC  74CBTLV3126PW  I80
  U18     14    VCC  74CBTLV3126PW  I129
  U21      5    VCC  NC7SB3157   I58
  U22      5    VCC  NC7SB3157   I71
  U23      5    VCC  74LVC1G02GW  I96
  U24     24    VDD  PCA9548APW  I60
  U28      8   VCCB  PCA9617ADP  I39
  U29      8   VCCB  PCA9617ADP  I43
  U30      8   VCCB  PCA9617ADP  I28
  U31      8   VCCB  PCA9617ADP  I37
  U36     16    VCC  PCA9546APWR  I179
  U40      3    IN1  TPS259520DSGR  I42
  U40      4    IN2  TPS259520DSGR  I42
  U50      5    VCC  SN74LVC1G08DBVR  I175
  U51     24    VDD  PCA9555PW   I125
  U52      3    VCC  APX80929SAG7  I161
  U53      5    VCC  SN74LVC1G08DBVR  I150
  U56      3    IN1  TPS259520DSGR  I350
  U56      4    IN2  TPS259520DSGR  I350
  U58      5    VCC  SN74LVC2G07DCKR  I397
  U59      5    VCC  SN74LVC2G07DCKR  I400
  U62      2      A  BAS70057F   I64
  U63      8    VCC  TMP75AIDR    I1
  U64      8    VCC  M24128BWDW6TP  I35
  U65      8    VCC  TMP75AIDR   I84
  U66      5      5  74HC1G126GW  I53
  U67     14    VCC  74CBTLV3126PW   I1
  U68     14    VCC  74CBTLV3126PW   I2
  U75      5    VCC  SN74LVC1G17DCKR   I1
  U77     14    VCC  74CBTLV3126PW  I105
  U79      5      D  SLG55221120010VTR  I62
  U82      5    VCC  74LVC1G126GW  I35
  U83     14    VCC  GTL2014PW   I45
  U84     14    VCC  GTL2014PW   I18
  U85      5    VCC  NC7SB3157   I109
  U86     14    VCC  74CBTLV3126PW  I84
  U90      6    VDD  PI6CV304LE  I46
  U94      6    VCC  ADM1086AKSZREEL7   I1
  U95      5    VCC  SN74LVC1G07DCKR  I41
  U96     10     V+  TS3A24157RSER  I68
  U97     10     V+  TS3A24157RSER  I38
  U98      7  VREF2  PCA9306DCTR  I27
  U104     5    VCC  74LVC1G07GV  I63
  U105     8    VDD  ADS1015IDGSR   I1
  U117     6    VCC  TPS3897PDRYR  I37
  U121     8    VDD  MAX11607EUAT  I48
  U122    C3  VCC_ONE_7  10M04SAU324I7G  I164
  U122   D11  VCCIO7_3  10M04SAU324I7G  I164
  U122    E7  VCCIO8_4  10M04SAU324I7G  I164
  U122    E8  VCCIO8_3  10M04SAU324I7G  I164
  U122    E9  VCCIO8_2  10M04SAU324I7G  I164
  U122   E11  VCCIO7_2  10M04SAU324I7G  I164
  U122   E12  VCCIO7_1  10M04SAU324I7G  I164
  U122    F9  VCCIO8_1  10M04SAU324I7G  I164
  U122   F13  VCC_ONE_6  10M04SAU324I7G  I164
  U122    G5  VCCIO1A_2  10M04SAU324I7G  I164
  U122   G13  VCCIO6_5  10M04SAU324I7G  I164
  U122   G14  VCCIO6_4  10M04SAU324I7G  I164
  U122    H5  VCCIO1A_1  10M04SAU324I7G  I164
  U122   H10  VCC_ONE_4  10M04SAU324I7G  I164
  U122   H13  VCCIO6_3  10M04SAU324I7G  I164
  U122    J5  VCCIO1B_2  10M04SAU324I7G  I164
  U122    J9  VCC_ONE_3  10M04SAU324I7G  I164
  U122   J13  VCCIO6_2  10M04SAU324I7G  I164
  U122   J14  VCCIO6_1  10M04SAU324I7G  I164
  U122    K5  VCCIO1B_1  10M04SAU324I7G  I164
  U122   K10  VCC_ONE_2  10M04SAU324I7G  I164
  U122   K14  VCCIO5_4  10M04SAU324I7G  I164
  U122    L5  VCCIO2_3  10M04SAU324I7G  I164
  U122    L6  VCCIO2_2  10M04SAU324I7G  I164
  U122    L9  VCC_ONE_1  10M04SAU324I7G  I164
  U122   L13  VCCIO5_3  10M04SAU324I7G  I164
  U122   L14  VCCIO5_2  10M04SAU324I7G  I164
  U122    M5  VCCIO2_1  10M04SAU324I7G  I164
  U122   M13  VCCIO5_1  10M04SAU324I7G  I164
  U122    N6  VCC_ONE_5  10M04SAU324I7G  I164
  U123     3    IN1  TPS259520DSGR   I8
  U123     4    IN2  TPS259520DSGR   I8
  U124     3    IN1  TPS259520DSGR  I59
  U124     4    IN2  TPS259520DSGR  I59
  U125     3    IN1  TPS259520DSGR  I25
  U125     4    IN2  TPS259520DSGR  I25
  U130    24    VDD  PCA9555PW    I1
  U131    24    VDD  PCA9555PW   I51
  U132     5    VCC  SN74LVC2G17DCKR  I80
  U133     5    VCC  SN74LVC2G17DCKR  I93
  U134     5    VCC  SN74LVC2G07DCKR   I1
  U135     5    VCC  SN74LVC2G07DCKR  I24
  U136     5    VCC  SN74LVC2G07DCKR  I46
  U137     5    VCC  SN74LVC2G07DCKR  I48
  U141    16    VCC  PCA9546APWR  I91

P3V3_AUX_CLK_GEN_VDDA100M_CK440   @S9S_MB_2U_LIB.S9S_MB_2U(SCH_1):P3V3_AUX_CLK_GEN_VDDA100M_CK440
  C172     1      A  Q_CAP        I6
  C173     1      A  Q_CAP        I4
  R519     2      B  Q_RES        I7
  U13    B17  VDDA100M  9SQ440NQQI8  I180

P3V3_AUX_CLK_GEN_VDDA25M_CK440   @S9S_MB_2U_LIB.S9S_MB_2U(SCH_1):P3V3_AUX_CLK_GEN_VDDA25M_CK440
  C114     1      A  Q_CAP       I47
  C1313    1      A  Q_CAP       I48
  R442     2      B  Q_RES       I36
  U13     B1  VDDA25M  9SQ440NQQI8  I180

P3V3_AUX_CLK_GEN_VDDMXCK_CK440   @S9S_MB_2U_LIB.S9S_MB_2U(SCH_1):P3V3_AUX_CLK_GEN_VDDMXCK_CK440
  C115     1      A  Q_CAP       I66
  C116     1      A  Q_CAP       I65
  C117     1      A  Q_CAP       I64
  C119     1      A  Q_CAP       I67
  C1310    1      A  Q_CAP       I59
  C1312    1      A  Q_CAP       I58
  L14      2      2  Q_INDUCTOR  I60
  R447     1      A  Q_RES       I55
  U13    B29  VDDMXCK_B29  9SQ440NQQI8  I180
  U13    B32  VDDMXCK_B32  9SQ440NQQI8  I180
  U13    B35  VDDMXCK_B35  9SQ440NQQI8  I180
  U13    B40  VDDMXCK_B40  9SQ440NQQI8  I180

P3V3_AUX_CLK_GEN_VDDPT_CK440   @S9S_MB_2U_LIB.S9S_MB_2U(SCH_1):P3V3_AUX_CLK_GEN_VDDPT_CK440
  C120     1      A  Q_CAP       I68
  C1314    1      A  Q_CAP       I53
  R447     2      B  Q_RES       I55
  U13     B6  VDDPT  9SQ440NQQI8  I180

P3V3_AUX_CLK_GEN_VDDXTAL_CK440   @S9S_MB_2U_LIB.S9S_MB_2U(SCH_1):P3V3_AUX_CLK_GEN_VDDXTAL_CK440
  C111     1      A  Q_CAP       I46
  C112     1      A  Q_CAP       I45
  C1309    1      A  Q_CAP       I44
  C1311    1      A  Q_CAP       I43
  L13      2      2  Q_INDUCTOR  I41
  R442     1      A  Q_RES       I36
  U13    A12  VDDXTAL  9SQ440NQQI8  I180

P3V3_AUX_CLK_GEN_VDD_CK440   @S9S_MB_2U_LIB.S9S_MB_2U(SCH_1):P3V3_AUX_CLK_GEN_VDD_CK440
  C108     1      A  Q_CAP       I19
  C109     1      A  Q_CAP       I18
  C110     1      A  Q_CAP       I17
  C171     1      A  Q_CAP        I2
  L1       2      2  Q_INDUCTOR  I20
  R519     1      A  Q_RES        I7
  U13    B21  VDD100M_B21  9SQ440NQQI8  I180
  U13    B23  VDD100M_B23  9SQ440NQQI8  I180

P3V3_AUX_DPLD_ADC_VREF   @S9S_MB_2U_LIB.S9S_MB_2U(SCH_1):P3V3_AUX_DPLD_ADC_VREF
  R507     2      B  Q_RES       I173
  R508     1      A  Q_RES       I172
  U122    F3  ADC_VREF  10M04SAU324I7G  I164

P3V3_AUX_FB     @S9S_MB_2U_LIB.S9S_MB_2U(SCH_1):P3V3_AUX_FB
  PC569    1      A  Q_CAP       I35
  PR830    1      A  Q_RES       I34
  PR831    1      A  Q_RES       I36
  PU9     30     FB  NCP3284MNTXG  I23

P3V3_AUX_ILIM   @S9S_MB_2U_LIB.S9S_MB_2U(SCH_1):P3V3_AUX_ILIM
  PR834    1      A  Q_RES       I13
  PU9      1   ILIM  NCP3284MNTXG  I23

P3V3_AUX_MODE   @S9S_MB_2U_LIB.S9S_MB_2U(SCH_1):P3V3_AUX_MODE
  PR832    1      A  Q_RES        I9
  PU9     36  MODE||FSET  NCP3284MNTXG  I23

P3V3_AUX_SENSE   @S9S_MB_2U_LIB.S9S_MB_2U(SCH_1):P3V3_AUX_SENSE
  C1344    1      A  Q_CAP       I37
  R1786    2      B  Q_RES       I27
  R1787    1      A  Q_RES       I28
  U105     4   AIN0  ADS1015IDGSR   I1
  U121     1   AIN0  MAX11607EUAT  I48

P3V3_AUX_SS     @S9S_MB_2U_LIB.S9S_MB_2U(SCH_1):P3V3_AUX_SS
  PR833    1      A  Q_RES       I11
  PU9     29     SS  NCP3284MNTXG  I23

P3V3_AUX_VCC    @S9S_MB_2U_LIB.S9S_MB_2U(SCH_1):P3V3_AUX_VCC
  PC591    1      A  Q_CAP       I15
  PR389    2      B  Q_RES       I16
  PU9      4    VCC  NCP3284MNTXG  I23

P3V3_AUX_VOS    @S9S_MB_2U_LIB.S9S_MB_2U(SCH_1):P3V3_AUX_VOS
  PR836    1      A  Q_RES       I25
  PU9     28    VOS  NCP3284MNTXG  I23

P3V3_DB2000_FB_VDD   @S9S_MB_2U_LIB.S9S_MB_2U(SCH_1):P3V3_DB2000_FB_VDD
  L4       2      2  Q_INDUCTOR  I177
  R571     1      A  Q_RES       I163
  R572     1      A  Q_RES       I162

P3V3_DB2000_VDD   @S9S_MB_2U_LIB.S9S_MB_2U(SCH_1):P3V3_DB2000_VDD
  C204     1      A  Q_CAP       I171
  C205     1      A  Q_CAP       I172
  C206     1      A  Q_CAP       I173
  C207     1      A  Q_CAP       I174
  C1409    1      A  Q_CAP       I419
  L3       2      2  Q_INDUCTOR  I170
  U38     B2  VDDO3.3_B2  9QXL2001BNHGI8  I119
  U38    B11  VDDO3.3_B11  9QXL2001BNHGI8  I119
  U38     L2  VDDO3.3_L2  9QXL2001BNHGI8  I119
  U38    L11  VDDO3.3_L11  9QXL2001BNHGI8  I119

P3V3_DB2000_VDDA   @S9S_MB_2U_LIB.S9S_MB_2U(SCH_1):P3V3_DB2000_VDDA
  C209     1      A  Q_CAP       I164
  C211     1      A  Q_CAP       I165
  R572     2      B  Q_RES       I162
  U38     B6  VDDA3.3  9QXL2001BNHGI8  I119

P3V3_DB2000_VDDR   @S9S_MB_2U_LIB.S9S_MB_2U(SCH_1):P3V3_DB2000_VDDR
  C208     1      A  Q_CAP       I167
  C210     1      A  Q_CAP       I168
  R571     2      B  Q_RES       I163
  U38     H2  VDDR3.3  9QXL2001BNHGI8  I119

P3V3_E1S_0      @S9S_MB_2U_LIB.S9S_MB_2U(SCH_1):P3V3_E1S_0
  C184     1      A  Q_CAP       I45
  C1282    1      A  Q_CAP        I8
  C1283    1      A  Q_CAP        I7
  J90    B11  3.3VAUX  CONN56_ME2005602311011  I105
  R1673    1      A  Q_RES       I34
  U40      5    OUT  TPS259520DSGR  I42

P3V3_E1S_0_DVDT   @S9S_MB_2U_LIB.S9S_MB_2U(SCH_1):P3V3_E1S_0_DVDT
  C179     1      A  Q_CAP       I38
  U40      1   DVDT  TPS259520DSGR  I42

P3V3_E1S_0_FLT_N   @S9S_MB_2U_LIB.S9S_MB_2U(SCH_1):P3V3_E1S_0_FLT_N
  R1104    2      B  Q_RES       I51
  U40      6   FLT#  TPS259520DSGR  I42

P3V3_E1S_0_ILM   @S9S_MB_2U_LIB.S9S_MB_2U(SCH_1):P3V3_E1S_0_ILM
  R1103    1      A  Q_RES       I48
  U40      7    ILM  TPS259520DSGR  I42

P3V3_E1S_1      @S9S_MB_2U_LIB.S9S_MB_2U(SCH_1):P3V3_E1S_1
  C1284    1      A  Q_CAP       I29
  C1285    1      A  Q_CAP       I27
  C1487    1      A  Q_CAP       I63
  J91    B11  3.3VAUX  CONN56_ME2005602311011  I123
  R2005    1      A  Q_RES       I66
  U124     5    OUT  TPS259520DSGR  I59

P3V3_E1S_1_DVDT   @S9S_MB_2U_LIB.S9S_MB_2U(SCH_1):P3V3_E1S_1_DVDT
  C1484    1      A  Q_CAP       I54
  U124     1   DVDT  TPS259520DSGR  I59

P3V3_E1S_1_FLT_N   @S9S_MB_2U_LIB.S9S_MB_2U(SCH_1):P3V3_E1S_1_FLT_N
  R2022    2      B  Q_RES       I67
  U124     6   FLT#  TPS259520DSGR  I59

P3V3_E1S_1_ILM   @S9S_MB_2U_LIB.S9S_MB_2U(SCH_1):P3V3_E1S_1_ILM
  R2020    1      A  Q_RES       I65
  U124     7    ILM  TPS259520DSGR  I59

P3V3_E1S_2      @S9S_MB_2U_LIB.S9S_MB_2U(SCH_1):P3V3_E1S_2
  C1483    1      A  Q_CAP       I12
  C1499    1      A  Q_CAP        I8
  C1501    1      A  Q_CAP        I6
  J92    B11  3.3VAUX  CONN56_ME2005602311011  I105
  R2006    1      A  Q_RES       I30
  U123     5    OUT  TPS259520DSGR   I8

P3V3_E1S_2_DVDT   @S9S_MB_2U_LIB.S9S_MB_2U(SCH_1):P3V3_E1S_2_DVDT
  C1480    1      A  Q_CAP        I3
  U123     1   DVDT  TPS259520DSGR   I8

P3V3_E1S_2_FLT_N   @S9S_MB_2U_LIB.S9S_MB_2U(SCH_1):P3V3_E1S_2_FLT_N
  R2017    2      B  Q_RES       I17
  U123     6   FLT#  TPS259520DSGR   I8

P3V3_E1S_2_ILM   @S9S_MB_2U_LIB.S9S_MB_2U(SCH_1):P3V3_E1S_2_ILM
  R2016    1      A  Q_RES       I14
  U123     7    ILM  TPS259520DSGR   I8

P3V3_E1S_3      @S9S_MB_2U_LIB.S9S_MB_2U(SCH_1):P3V3_E1S_3
  C1488    1      A  Q_CAP       I29
  C1500    1      A  Q_CAP       I25
  C1502    1      A  Q_CAP       I23
  J93    B11  3.3VAUX  CONN56_ME2005602311011  I123
  R2007    1      A  Q_RES       I54
  U125     5    OUT  TPS259520DSGR  I25

P3V3_E1S_3_DVDT   @S9S_MB_2U_LIB.S9S_MB_2U(SCH_1):P3V3_E1S_3_DVDT
  C575     1      A  Q_CAP       I19
  U125     1   DVDT  TPS259520DSGR  I25

P3V3_E1S_3_FLT_N   @S9S_MB_2U_LIB.S9S_MB_2U(SCH_1):P3V3_E1S_3_FLT_N
  R2023    2      B  Q_RES       I33
  U125     6   FLT#  TPS259520DSGR  I25

P3V3_E1S_3_ILM   @S9S_MB_2U_LIB.S9S_MB_2U(SCH_1):P3V3_E1S_3_ILM
  R2021    1      A  Q_RES       I31
  U125     7    ILM  TPS259520DSGR  I25

P3V3_OCP_DVDT_1   @S9S_MB_2U_LIB.S9S_MB_2U(SCH_1):P3V3_OCP_DVDT_1
  C582     1      A  Q_CAP       I353
  U56      1   DVDT  TPS259520DSGR  I350

P3V3_OCP_ILM1   @S9S_MB_2U_LIB.S9S_MB_2U(SCH_1):P3V3_OCP_ILM1
  R1142    1      A  Q_RES       I345
  U56      7    ILM  TPS259520DSGR  I350

P3V3_OCP_SFF    @S9S_MB_2U_LIB.S9S_MB_2U(SCH_1):P3V3_OCP_SFF
  C587     1      A  Q_CAP       I347
  C1237    1      A  Q_CAP       I334
  C1238    1      A  Q_CAP       I338
  C1239    1      A  Q_CAP       I337
  C1240    1      A  Q_CAP       I335
  J37    B11  +3.3V_EDGE  SCONN168_623403212  I86
  R409     1      A  Q_RES       I147
  R414     1      A  Q_RES       I144
  R420     2      B  Q_RES       I10
  R421     2      B  Q_RES       I11
  R454     1      A  Q_RES       I314
  R1132    1      A  Q_RES       I153
  R1592    1      A  Q_RES       I37
  R1824    1      A  Q_RES       I62
  U56      5    OUT  TPS259520DSGR  I350

P3V3_RTC_AUX    @S9S_MB_2U_LIB.S9S_MB_2U(SCH_1):P3V3_RTC_AUX
  C611     1      A  Q_CAP       I65
  R989     2      B  Q_RES       I68
  R1202    1      A  Q_RES       I70
  R1340    1      A  Q_RES       I57
  U4     AH15  VCCRTC  EMMITSBURG_REV0P9  I11
  U62      3      C  BAS70057F   I64

P3V3_RTC_AUX_SENSE   @S9S_MB_2U_LIB.S9S_MB_2U(SCH_1):P3V3_RTC_AUX_SENSE
  C1346    1      A  Q_CAP       I42
  R1790    2      B  Q_RES       I40
  R1791    1      A  Q_RES       I43
  U105     6   AIN2  ADS1015IDGSR   I1
  U121     3   AIN2  MAX11607EUAT  I48

P3V3_SENSE      @S9S_MB_2U_LIB.S9S_MB_2U(SCH_1):P3V3_SENSE
  C1345    1      A  Q_CAP       I39
  R1788    2      B  Q_RES       I31
  R1789    1      A  Q_RES       I34
  U105     5   AIN1  ADS1015IDGSR   I1
  U121     2   AIN1  MAX11607EUAT  I48

P3V_BAT         @S9S_MB_2U_LIB.S9S_MB_2U(SCH_1):P3V_BAT
  BT1      1      1  CONN2_AAABAT029P15  I63
  R1203    1      A  Q_RES       I62
  R1790    1      A  Q_RES       I40

P3V_BAT_R       @S9S_MB_2U_LIB.S9S_MB_2U(SCH_1):P3V_BAT_R
  J41    B41  GND_B41  SCONN168_623403212  I115
  R1203    2      B  Q_RES       I62
  U62      1      B  BAS70057F   I64

P5E_CPU0_PE0_RX_DN<0>   @S9S_MB_2U_LIB.S9S_MB_2U(SCH_1):P5E_CPU0_PE0_RX_DN<0>
  J90    A17  PERN0  CONN56_ME2005602311011  I105
  U2     BA9  PE0_RX_DN15  SOCKET4677_AZIFS054P001C01  I37

P5E_CPU0_PE0_RX_DN<1>   @S9S_MB_2U_LIB.S9S_MB_2U(SCH_1):P5E_CPU0_PE0_RX_DN<1>
  J90    A20  PERN1  CONN56_ME2005602311011  I105
  U2     AV10  PE0_RX_DN14  SOCKET4677_AZIFS054P001C01  I37

P5E_CPU0_PE0_RX_DN<2>   @S9S_MB_2U_LIB.S9S_MB_2U(SCH_1):P5E_CPU0_PE0_RX_DN<2>
  J90    A23  PERN2  CONN56_ME2005602311011  I105
  U2     AU9  PE0_RX_DN13  SOCKET4677_AZIFS054P001C01  I37

P5E_CPU0_PE0_RX_DN<3>   @S9S_MB_2U_LIB.S9S_MB_2U(SCH_1):P5E_CPU0_PE0_RX_DN<3>
  J90    A26  PERN3  CONN56_ME2005602311011  I105
  U2     AP10  PE0_RX_DN12  SOCKET4677_AZIFS054P001C01  I37

P5E_CPU0_PE0_RX_DN<4>   @S9S_MB_2U_LIB.S9S_MB_2U(SCH_1):P5E_CPU0_PE0_RX_DN<4>
  J91    A17  PERN0  CONN56_ME2005602311011  I123
  U2     AM10  PE0_RX_DN11  SOCKET4677_AZIFS054P001C01  I37

P5E_CPU0_PE0_RX_DN<5>   @S9S_MB_2U_LIB.S9S_MB_2U(SCH_1):P5E_CPU0_PE0_RX_DN<5>
  J91    A20  PERN1  CONN56_ME2005602311011  I123
  U2     AK10  PE0_RX_DN10  SOCKET4677_AZIFS054P001C01  I37

P5E_CPU0_PE0_RX_DN<6>   @S9S_MB_2U_LIB.S9S_MB_2U(SCH_1):P5E_CPU0_PE0_RX_DN<6>
  J91    A23  PERN2  CONN56_ME2005602311011  I123
  U2     AJ9  PE0_RX_DN9  SOCKET4677_AZIFS054P001C01  I37

P5E_CPU0_PE0_RX_DN<7>   @S9S_MB_2U_LIB.S9S_MB_2U(SCH_1):P5E_CPU0_PE0_RX_DN<7>
  J91    A26  PERN3  CONN56_ME2005602311011  I123
  U2     AF10  PE0_RX_DN8  SOCKET4677_AZIFS054P001C01  I37

P5E_CPU0_PE0_RX_DN<8>   @S9S_MB_2U_LIB.S9S_MB_2U(SCH_1):P5E_CPU0_PE0_RX_DN<8>
  J92    A17  PERN0  CONN56_ME2005602311011  I105
  U2     AE9  PE0_RX_DN7  SOCKET4677_AZIFS054P001C01  I37

P5E_CPU0_PE0_RX_DN<9>   @S9S_MB_2U_LIB.S9S_MB_2U(SCH_1):P5E_CPU0_PE0_RX_DN<9>
  J92    A20  PERN1  CONN56_ME2005602311011  I105
  U2     AB10  PE0_RX_DN6  SOCKET4677_AZIFS054P001C01  I37

P5E_CPU0_PE0_RX_DN<10>   @S9S_MB_2U_LIB.S9S_MB_2U(SCH_1):P5E_CPU0_PE0_RX_DN<10>
  J92    A23  PERN2  CONN56_ME2005602311011  I105
  U2     AA9  PE0_RX_DN5  SOCKET4677_AZIFS054P001C01  I37

P5E_CPU0_PE0_RX_DN<11>   @S9S_MB_2U_LIB.S9S_MB_2U(SCH_1):P5E_CPU0_PE0_RX_DN<11>
  J92    A26  PERN3  CONN56_ME2005602311011  I105
  U2     V10  PE0_RX_DN4  SOCKET4677_AZIFS054P001C01  I37

P5E_CPU0_PE0_RX_DN<12>   @S9S_MB_2U_LIB.S9S_MB_2U(SCH_1):P5E_CPU0_PE0_RX_DN<12>
  J93    A17  PERN0  CONN56_ME2005602311011  I123
  U2     T10  PE0_RX_DN3  SOCKET4677_AZIFS054P001C01  I37

P5E_CPU0_PE0_RX_DN<13>   @S9S_MB_2U_LIB.S9S_MB_2U(SCH_1):P5E_CPU0_PE0_RX_DN<13>
  J93    A20  PERN1  CONN56_ME2005602311011  I123
  U2     P10  PE0_RX_DN2  SOCKET4677_AZIFS054P001C01  I37

P5E_CPU0_PE0_RX_DN<14>   @S9S_MB_2U_LIB.S9S_MB_2U(SCH_1):P5E_CPU0_PE0_RX_DN<14>
  J93    A23  PERN2  CONN56_ME2005602311011  I123
  U2     M10  PE0_RX_DN1  SOCKET4677_AZIFS054P001C01  I37

P5E_CPU0_PE0_RX_DN<15>   @S9S_MB_2U_LIB.S9S_MB_2U(SCH_1):P5E_CPU0_PE0_RX_DN<15>
  J93    A26  PERN3  CONN56_ME2005602311011  I123
  U2     K10  PE0_RX_DN0  SOCKET4677_AZIFS054P001C01  I37

P5E_CPU0_PE0_RX_DP<0>   @S9S_MB_2U_LIB.S9S_MB_2U(SCH_1):P5E_CPU0_PE0_RX_DP<0>
  J90    A18  PERP0  CONN56_ME2005602311011  I105
  U2     AY10  PE0_RX_DP15  SOCKET4677_AZIFS054P001C01  I37

P5E_CPU0_PE0_RX_DP<1>   @S9S_MB_2U_LIB.S9S_MB_2U(SCH_1):P5E_CPU0_PE0_RX_DP<1>
  J90    A21  PERP1  CONN56_ME2005602311011  I105
  U2     AW11  PE0_RX_DP14  SOCKET4677_AZIFS054P001C01  I37

P5E_CPU0_PE0_RX_DP<2>   @S9S_MB_2U_LIB.S9S_MB_2U(SCH_1):P5E_CPU0_PE0_RX_DP<2>
  J90    A24  PERP2  CONN56_ME2005602311011  I105
  U2     AT10  PE0_RX_DP13  SOCKET4677_AZIFS054P001C01  I37

P5E_CPU0_PE0_RX_DP<3>   @S9S_MB_2U_LIB.S9S_MB_2U(SCH_1):P5E_CPU0_PE0_RX_DP<3>
  J90    A27  PERP3  CONN56_ME2005602311011  I105
  U2     AR11  PE0_RX_DP12  SOCKET4677_AZIFS054P001C01  I37

P5E_CPU0_PE0_RX_DP<4>   @S9S_MB_2U_LIB.S9S_MB_2U(SCH_1):P5E_CPU0_PE0_RX_DP<4>
  J91    A18  PERP0  CONN56_ME2005602311011  I123
  U2     AN9  PE0_RX_DP11  SOCKET4677_AZIFS054P001C01  I37

P5E_CPU0_PE0_RX_DP<5>   @S9S_MB_2U_LIB.S9S_MB_2U(SCH_1):P5E_CPU0_PE0_RX_DP<5>
  J91    A21  PERP1  CONN56_ME2005602311011  I123
  U2     AL11  PE0_RX_DP10  SOCKET4677_AZIFS054P001C01  I37

P5E_CPU0_PE0_RX_DP<6>   @S9S_MB_2U_LIB.S9S_MB_2U(SCH_1):P5E_CPU0_PE0_RX_DP<6>
  J91    A24  PERP2  CONN56_ME2005602311011  I123
  U2     AH10  PE0_RX_DP9  SOCKET4677_AZIFS054P001C01  I37

P5E_CPU0_PE0_RX_DP<7>   @S9S_MB_2U_LIB.S9S_MB_2U(SCH_1):P5E_CPU0_PE0_RX_DP<7>
  J91    A27  PERP3  CONN56_ME2005602311011  I123
  U2     AG11  PE0_RX_DP8  SOCKET4677_AZIFS054P001C01  I37

P5E_CPU0_PE0_RX_DP<8>   @S9S_MB_2U_LIB.S9S_MB_2U(SCH_1):P5E_CPU0_PE0_RX_DP<8>
  J92    A18  PERP0  CONN56_ME2005602311011  I105
  U2     AD10  PE0_RX_DP7  SOCKET4677_AZIFS054P001C01  I37

P5E_CPU0_PE0_RX_DP<9>   @S9S_MB_2U_LIB.S9S_MB_2U(SCH_1):P5E_CPU0_PE0_RX_DP<9>
  J92    A21  PERP1  CONN56_ME2005602311011  I105
  U2     AC11  PE0_RX_DP6  SOCKET4677_AZIFS054P001C01  I37

P5E_CPU0_PE0_RX_DP<10>   @S9S_MB_2U_LIB.S9S_MB_2U(SCH_1):P5E_CPU0_PE0_RX_DP<10>
  J92    A24  PERP2  CONN56_ME2005602311011  I105
  U2     Y10  PE0_RX_DP5  SOCKET4677_AZIFS054P001C01  I37

P5E_CPU0_PE0_RX_DP<11>   @S9S_MB_2U_LIB.S9S_MB_2U(SCH_1):P5E_CPU0_PE0_RX_DP<11>
  J92    A27  PERP3  CONN56_ME2005602311011  I105
  U2     W11  PE0_RX_DP4  SOCKET4677_AZIFS054P001C01  I37

P5E_CPU0_PE0_RX_DP<12>   @S9S_MB_2U_LIB.S9S_MB_2U(SCH_1):P5E_CPU0_PE0_RX_DP<12>
  J93    A18  PERP0  CONN56_ME2005602311011  I123
  U2      U9  PE0_RX_DP3  SOCKET4677_AZIFS054P001C01  I37

P5E_CPU0_PE0_RX_DP<13>   @S9S_MB_2U_LIB.S9S_MB_2U(SCH_1):P5E_CPU0_PE0_RX_DP<13>
  J93    A21  PERP1  CONN56_ME2005602311011  I123
  U2     R11  PE0_RX_DP2  SOCKET4677_AZIFS054P001C01  I37

P5E_CPU0_PE0_RX_DP<14>   @S9S_MB_2U_LIB.S9S_MB_2U(SCH_1):P5E_CPU0_PE0_RX_DP<14>
  J93    A24  PERP2  CONN56_ME2005602311011  I123
  U2      N9  PE0_RX_DP1  SOCKET4677_AZIFS054P001C01  I37

P5E_CPU0_PE0_RX_DP<15>   @S9S_MB_2U_LIB.S9S_MB_2U(SCH_1):P5E_CPU0_PE0_RX_DP<15>
  J93    A27  PERP3  CONN56_ME2005602311011  I123
  U2     L11  PE0_RX_DP0  SOCKET4677_AZIFS054P001C01  I37

P5E_CPU0_PE0_TX_C_DN<0>   @S9S_MB_2U_LIB.S9S_MB_2U(SCH_1):P5E_CPU0_PE0_TX_C_DN<0>
  C932     1      1  Q_CAP_DIFFBUS  I16
  J90    B17  PETN0  CONN56_ME2005602311011  I105

P5E_CPU0_PE0_TX_C_DN<1>   @S9S_MB_2U_LIB.S9S_MB_2U(SCH_1):P5E_CPU0_PE0_TX_C_DN<1>
  C930     1      1  Q_CAP_DIFFBUS  I18
  J90    B20  PETN1  CONN56_ME2005602311011  I105

P5E_CPU0_PE0_TX_C_DN<2>   @S9S_MB_2U_LIB.S9S_MB_2U(SCH_1):P5E_CPU0_PE0_TX_C_DN<2>
  C928     1      1  Q_CAP_DIFFBUS  I20
  J90    B23  PETN2  CONN56_ME2005602311011  I105

P5E_CPU0_PE0_TX_C_DN<3>   @S9S_MB_2U_LIB.S9S_MB_2U(SCH_1):P5E_CPU0_PE0_TX_C_DN<3>
  C926     1      1  Q_CAP_DIFFBUS  I22
  J90    B26  PETN3  CONN56_ME2005602311011  I105

P5E_CPU0_PE0_TX_C_DN<4>   @S9S_MB_2U_LIB.S9S_MB_2U(SCH_1):P5E_CPU0_PE0_TX_C_DN<4>
  C924     1      1  Q_CAP_DIFFBUS  I24
  J91    B17  PETN0  CONN56_ME2005602311011  I123

P5E_CPU0_PE0_TX_C_DN<5>   @S9S_MB_2U_LIB.S9S_MB_2U(SCH_1):P5E_CPU0_PE0_TX_C_DN<5>
  C922     1      1  Q_CAP_DIFFBUS  I53
  J91    B20  PETN1  CONN56_ME2005602311011  I123

P5E_CPU0_PE0_TX_C_DN<6>   @S9S_MB_2U_LIB.S9S_MB_2U(SCH_1):P5E_CPU0_PE0_TX_C_DN<6>
  C920     1      1  Q_CAP_DIFFBUS  I54
  J91    B23  PETN2  CONN56_ME2005602311011  I123

P5E_CPU0_PE0_TX_C_DN<7>   @S9S_MB_2U_LIB.S9S_MB_2U(SCH_1):P5E_CPU0_PE0_TX_C_DN<7>
  C918     1      1  Q_CAP_DIFFBUS  I57
  J91    B26  PETN3  CONN56_ME2005602311011  I123

P5E_CPU0_PE0_TX_C_DN<8>   @S9S_MB_2U_LIB.S9S_MB_2U(SCH_1):P5E_CPU0_PE0_TX_C_DN<8>
  C916     1      1  Q_CAP_DIFFBUS  I59
  J92    B17  PETN0  CONN56_ME2005602311011  I105

P5E_CPU0_PE0_TX_C_DN<9>   @S9S_MB_2U_LIB.S9S_MB_2U(SCH_1):P5E_CPU0_PE0_TX_C_DN<9>
  C914     1      1  Q_CAP_DIFFBUS  I62
  J92    B20  PETN1  CONN56_ME2005602311011  I105

P5E_CPU0_PE0_TX_C_DN<10>   @S9S_MB_2U_LIB.S9S_MB_2U(SCH_1):P5E_CPU0_PE0_TX_C_DN<10>
  C912     1      1  Q_CAP_DIFFBUS  I64
  J92    B23  PETN2  CONN56_ME2005602311011  I105

P5E_CPU0_PE0_TX_C_DN<11>   @S9S_MB_2U_LIB.S9S_MB_2U(SCH_1):P5E_CPU0_PE0_TX_C_DN<11>
  C910     1      1  Q_CAP_DIFFBUS  I66
  J92    B26  PETN3  CONN56_ME2005602311011  I105

P5E_CPU0_PE0_TX_C_DN<12>   @S9S_MB_2U_LIB.S9S_MB_2U(SCH_1):P5E_CPU0_PE0_TX_C_DN<12>
  C908     1      1  Q_CAP_DIFFBUS  I68
  J93    B17  PETN0  CONN56_ME2005602311011  I123

P5E_CPU0_PE0_TX_C_DN<13>   @S9S_MB_2U_LIB.S9S_MB_2U(SCH_1):P5E_CPU0_PE0_TX_C_DN<13>
  C906     1      1  Q_CAP_DIFFBUS  I69
  J93    B20  PETN1  CONN56_ME2005602311011  I123

P5E_CPU0_PE0_TX_C_DN<14>   @S9S_MB_2U_LIB.S9S_MB_2U(SCH_1):P5E_CPU0_PE0_TX_C_DN<14>
  C904     1      1  Q_CAP_DIFFBUS  I76
  J93    B23  PETN2  CONN56_ME2005602311011  I123

P5E_CPU0_PE0_TX_C_DN<15>   @S9S_MB_2U_LIB.S9S_MB_2U(SCH_1):P5E_CPU0_PE0_TX_C_DN<15>
  C902     1      1  Q_CAP_DIFFBUS  I77
  J93    B26  PETN3  CONN56_ME2005602311011  I123

P5E_CPU0_PE0_TX_C_DP<0>   @S9S_MB_2U_LIB.S9S_MB_2U(SCH_1):P5E_CPU0_PE0_TX_C_DP<0>
  C933     1      1  Q_CAP_DIFFBUS  I15
  J90    B18  PETP0  CONN56_ME2005602311011  I105

P5E_CPU0_PE0_TX_C_DP<1>   @S9S_MB_2U_LIB.S9S_MB_2U(SCH_1):P5E_CPU0_PE0_TX_C_DP<1>
  C931     1      1  Q_CAP_DIFFBUS  I17
  J90    B21  PETP1  CONN56_ME2005602311011  I105

P5E_CPU0_PE0_TX_C_DP<2>   @S9S_MB_2U_LIB.S9S_MB_2U(SCH_1):P5E_CPU0_PE0_TX_C_DP<2>
  C929     1      1  Q_CAP_DIFFBUS  I19
  J90    B24  PETP2  CONN56_ME2005602311011  I105

P5E_CPU0_PE0_TX_C_DP<3>   @S9S_MB_2U_LIB.S9S_MB_2U(SCH_1):P5E_CPU0_PE0_TX_C_DP<3>
  C927     1      1  Q_CAP_DIFFBUS  I21
  J90    B27  PETP3  CONN56_ME2005602311011  I105

P5E_CPU0_PE0_TX_C_DP<4>   @S9S_MB_2U_LIB.S9S_MB_2U(SCH_1):P5E_CPU0_PE0_TX_C_DP<4>
  C925     1      1  Q_CAP_DIFFBUS  I23
  J91    B18  PETP0  CONN56_ME2005602311011  I123

P5E_CPU0_PE0_TX_C_DP<5>   @S9S_MB_2U_LIB.S9S_MB_2U(SCH_1):P5E_CPU0_PE0_TX_C_DP<5>
  C923     1      1  Q_CAP_DIFFBUS  I25
  J91    B21  PETP1  CONN56_ME2005602311011  I123

P5E_CPU0_PE0_TX_C_DP<6>   @S9S_MB_2U_LIB.S9S_MB_2U(SCH_1):P5E_CPU0_PE0_TX_C_DP<6>
  C921     1      1  Q_CAP_DIFFBUS  I55
  J91    B24  PETP2  CONN56_ME2005602311011  I123

P5E_CPU0_PE0_TX_C_DP<7>   @S9S_MB_2U_LIB.S9S_MB_2U(SCH_1):P5E_CPU0_PE0_TX_C_DP<7>
  C919     1      1  Q_CAP_DIFFBUS  I56
  J91    B27  PETP3  CONN56_ME2005602311011  I123

P5E_CPU0_PE0_TX_C_DP<8>   @S9S_MB_2U_LIB.S9S_MB_2U(SCH_1):P5E_CPU0_PE0_TX_C_DP<8>
  C917     1      1  Q_CAP_DIFFBUS  I58
  J92    B18  PETP0  CONN56_ME2005602311011  I105

P5E_CPU0_PE0_TX_C_DP<9>   @S9S_MB_2U_LIB.S9S_MB_2U(SCH_1):P5E_CPU0_PE0_TX_C_DP<9>
  C915     1      1  Q_CAP_DIFFBUS  I61
  J92    B21  PETP1  CONN56_ME2005602311011  I105

P5E_CPU0_PE0_TX_C_DP<10>   @S9S_MB_2U_LIB.S9S_MB_2U(SCH_1):P5E_CPU0_PE0_TX_C_DP<10>
  C913     1      1  Q_CAP_DIFFBUS  I63
  J92    B24  PETP2  CONN56_ME2005602311011  I105

P5E_CPU0_PE0_TX_C_DP<11>   @S9S_MB_2U_LIB.S9S_MB_2U(SCH_1):P5E_CPU0_PE0_TX_C_DP<11>
  C911     1      1  Q_CAP_DIFFBUS  I65
  J92    B27  PETP3  CONN56_ME2005602311011  I105

P5E_CPU0_PE0_TX_C_DP<12>   @S9S_MB_2U_LIB.S9S_MB_2U(SCH_1):P5E_CPU0_PE0_TX_C_DP<12>
  C909     1      1  Q_CAP_DIFFBUS  I67
  J93    B18  PETP0  CONN56_ME2005602311011  I123

P5E_CPU0_PE0_TX_C_DP<13>   @S9S_MB_2U_LIB.S9S_MB_2U(SCH_1):P5E_CPU0_PE0_TX_C_DP<13>
  C907     1      1  Q_CAP_DIFFBUS  I70
  J93    B21  PETP1  CONN56_ME2005602311011  I123

P5E_CPU0_PE0_TX_C_DP<14>   @S9S_MB_2U_LIB.S9S_MB_2U(SCH_1):P5E_CPU0_PE0_TX_C_DP<14>
  C905     1      1  Q_CAP_DIFFBUS  I75
  J93    B24  PETP2  CONN56_ME2005602311011  I123

P5E_CPU0_PE0_TX_C_DP<15>   @S9S_MB_2U_LIB.S9S_MB_2U(SCH_1):P5E_CPU0_PE0_TX_C_DP<15>
  C903     1      1  Q_CAP_DIFFBUS  I78
  J93    B27  PETP3  CONN56_ME2005602311011  I123

P5E_CPU0_PE0_TX_DN<0>   @S9S_MB_2U_LIB.S9S_MB_2U(SCH_1):P5E_CPU0_PE0_TX_DN<0>
  C932     2      2  Q_CAP_DIFFBUS  I16
  U2     BB14  PE0_TX_DN15  SOCKET4677_AZIFS054P001C01  I37

P5E_CPU0_PE0_TX_DN<1>   @S9S_MB_2U_LIB.S9S_MB_2U(SCH_1):P5E_CPU0_PE0_TX_DN<1>
  C930     2      2  Q_CAP_DIFFBUS  I18
  U2     BA13  PE0_TX_DN14  SOCKET4677_AZIFS054P001C01  I37

P5E_CPU0_PE0_TX_DN<2>   @S9S_MB_2U_LIB.S9S_MB_2U(SCH_1):P5E_CPU0_PE0_TX_DN<2>
  C928     2      2  Q_CAP_DIFFBUS  I20
  U2     AV14  PE0_TX_DN13  SOCKET4677_AZIFS054P001C01  I37

P5E_CPU0_PE0_TX_DN<3>   @S9S_MB_2U_LIB.S9S_MB_2U(SCH_1):P5E_CPU0_PE0_TX_DN<3>
  C926     2      2  Q_CAP_DIFFBUS  I22
  U2     AU13  PE0_TX_DN12  SOCKET4677_AZIFS054P001C01  I37

P5E_CPU0_PE0_TX_DN<4>   @S9S_MB_2U_LIB.S9S_MB_2U(SCH_1):P5E_CPU0_PE0_TX_DN<4>
  C924     2      2  Q_CAP_DIFFBUS  I24
  U2     AP14  PE0_TX_DN11  SOCKET4677_AZIFS054P001C01  I37

P5E_CPU0_PE0_TX_DN<5>   @S9S_MB_2U_LIB.S9S_MB_2U(SCH_1):P5E_CPU0_PE0_TX_DN<5>
  C922     2      2  Q_CAP_DIFFBUS  I53
  U2     AN13  PE0_TX_DN10  SOCKET4677_AZIFS054P001C01  I37

P5E_CPU0_PE0_TX_DN<6>   @S9S_MB_2U_LIB.S9S_MB_2U(SCH_1):P5E_CPU0_PE0_TX_DN<6>
  C920     2      2  Q_CAP_DIFFBUS  I54
  U2     AK14  PE0_TX_DN9  SOCKET4677_AZIFS054P001C01  I37

P5E_CPU0_PE0_TX_DN<7>   @S9S_MB_2U_LIB.S9S_MB_2U(SCH_1):P5E_CPU0_PE0_TX_DN<7>
  C918     2      2  Q_CAP_DIFFBUS  I57
  U2     AJ13  PE0_TX_DN8  SOCKET4677_AZIFS054P001C01  I37

P5E_CPU0_PE0_TX_DN<8>   @S9S_MB_2U_LIB.S9S_MB_2U(SCH_1):P5E_CPU0_PE0_TX_DN<8>
  C916     2      2  Q_CAP_DIFFBUS  I59
  U2     AF14  PE0_TX_DN7  SOCKET4677_AZIFS054P001C01  I37

P5E_CPU0_PE0_TX_DN<9>   @S9S_MB_2U_LIB.S9S_MB_2U(SCH_1):P5E_CPU0_PE0_TX_DN<9>
  C914     2      2  Q_CAP_DIFFBUS  I62
  U2     AE13  PE0_TX_DN6  SOCKET4677_AZIFS054P001C01  I37

P5E_CPU0_PE0_TX_DN<10>   @S9S_MB_2U_LIB.S9S_MB_2U(SCH_1):P5E_CPU0_PE0_TX_DN<10>
  C912     2      2  Q_CAP_DIFFBUS  I64
  U2     AB14  PE0_TX_DN5  SOCKET4677_AZIFS054P001C01  I37

P5E_CPU0_PE0_TX_DN<11>   @S9S_MB_2U_LIB.S9S_MB_2U(SCH_1):P5E_CPU0_PE0_TX_DN<11>
  C910     2      2  Q_CAP_DIFFBUS  I66
  U2     AA13  PE0_TX_DN4  SOCKET4677_AZIFS054P001C01  I37

P5E_CPU0_PE0_TX_DN<12>   @S9S_MB_2U_LIB.S9S_MB_2U(SCH_1):P5E_CPU0_PE0_TX_DN<12>
  C908     2      2  Q_CAP_DIFFBUS  I68
  U2     V14  PE0_TX_DN3  SOCKET4677_AZIFS054P001C01  I37

P5E_CPU0_PE0_TX_DN<13>   @S9S_MB_2U_LIB.S9S_MB_2U(SCH_1):P5E_CPU0_PE0_TX_DN<13>
  C906     2      2  Q_CAP_DIFFBUS  I69
  U2     U13  PE0_TX_DN2  SOCKET4677_AZIFS054P001C01  I37

P5E_CPU0_PE0_TX_DN<14>   @S9S_MB_2U_LIB.S9S_MB_2U(SCH_1):P5E_CPU0_PE0_TX_DN<14>
  C904     2      2  Q_CAP_DIFFBUS  I76
  U2     P14  PE0_TX_DN1  SOCKET4677_AZIFS054P001C01  I37

P5E_CPU0_PE0_TX_DN<15>   @S9S_MB_2U_LIB.S9S_MB_2U(SCH_1):P5E_CPU0_PE0_TX_DN<15>
  C902     2      2  Q_CAP_DIFFBUS  I77
  U2     N13  PE0_TX_DN0  SOCKET4677_AZIFS054P001C01  I37

P5E_CPU0_PE0_TX_DP<0>   @S9S_MB_2U_LIB.S9S_MB_2U(SCH_1):P5E_CPU0_PE0_TX_DP<0>
  C933     2      2  Q_CAP_DIFFBUS  I15
  U2     BC15  PE0_TX_DP15  SOCKET4677_AZIFS054P001C01  I37

P5E_CPU0_PE0_TX_DP<1>   @S9S_MB_2U_LIB.S9S_MB_2U(SCH_1):P5E_CPU0_PE0_TX_DP<1>
  C931     2      2  Q_CAP_DIFFBUS  I17
  U2     AY14  PE0_TX_DP14  SOCKET4677_AZIFS054P001C01  I37

P5E_CPU0_PE0_TX_DP<2>   @S9S_MB_2U_LIB.S9S_MB_2U(SCH_1):P5E_CPU0_PE0_TX_DP<2>
  C929     2      2  Q_CAP_DIFFBUS  I19
  U2     AW15  PE0_TX_DP13  SOCKET4677_AZIFS054P001C01  I37

P5E_CPU0_PE0_TX_DP<3>   @S9S_MB_2U_LIB.S9S_MB_2U(SCH_1):P5E_CPU0_PE0_TX_DP<3>
  C927     2      2  Q_CAP_DIFFBUS  I21
  U2     AT14  PE0_TX_DP12  SOCKET4677_AZIFS054P001C01  I37

P5E_CPU0_PE0_TX_DP<4>   @S9S_MB_2U_LIB.S9S_MB_2U(SCH_1):P5E_CPU0_PE0_TX_DP<4>
  C925     2      2  Q_CAP_DIFFBUS  I23
  U2     AR15  PE0_TX_DP11  SOCKET4677_AZIFS054P001C01  I37

P5E_CPU0_PE0_TX_DP<5>   @S9S_MB_2U_LIB.S9S_MB_2U(SCH_1):P5E_CPU0_PE0_TX_DP<5>
  C923     2      2  Q_CAP_DIFFBUS  I25
  U2     AM14  PE0_TX_DP10  SOCKET4677_AZIFS054P001C01  I37

P5E_CPU0_PE0_TX_DP<6>   @S9S_MB_2U_LIB.S9S_MB_2U(SCH_1):P5E_CPU0_PE0_TX_DP<6>
  C921     2      2  Q_CAP_DIFFBUS  I55
  U2     AL15  PE0_TX_DP9  SOCKET4677_AZIFS054P001C01  I37

P5E_CPU0_PE0_TX_DP<7>   @S9S_MB_2U_LIB.S9S_MB_2U(SCH_1):P5E_CPU0_PE0_TX_DP<7>
  C919     2      2  Q_CAP_DIFFBUS  I56
  U2     AH14  PE0_TX_DP8  SOCKET4677_AZIFS054P001C01  I37

P5E_CPU0_PE0_TX_DP<8>   @S9S_MB_2U_LIB.S9S_MB_2U(SCH_1):P5E_CPU0_PE0_TX_DP<8>
  C917     2      2  Q_CAP_DIFFBUS  I58
  U2     AG15  PE0_TX_DP7  SOCKET4677_AZIFS054P001C01  I37

P5E_CPU0_PE0_TX_DP<9>   @S9S_MB_2U_LIB.S9S_MB_2U(SCH_1):P5E_CPU0_PE0_TX_DP<9>
  C915     2      2  Q_CAP_DIFFBUS  I61
  U2     AD14  PE0_TX_DP6  SOCKET4677_AZIFS054P001C01  I37

P5E_CPU0_PE0_TX_DP<10>   @S9S_MB_2U_LIB.S9S_MB_2U(SCH_1):P5E_CPU0_PE0_TX_DP<10>
  C913     2      2  Q_CAP_DIFFBUS  I63
  U2     AC15  PE0_TX_DP5  SOCKET4677_AZIFS054P001C01  I37

P5E_CPU0_PE0_TX_DP<11>   @S9S_MB_2U_LIB.S9S_MB_2U(SCH_1):P5E_CPU0_PE0_TX_DP<11>
  C911     2      2  Q_CAP_DIFFBUS  I65
  U2     Y14  PE0_TX_DP4  SOCKET4677_AZIFS054P001C01  I37

P5E_CPU0_PE0_TX_DP<12>   @S9S_MB_2U_LIB.S9S_MB_2U(SCH_1):P5E_CPU0_PE0_TX_DP<12>
  C909     2      2  Q_CAP_DIFFBUS  I67
  U2     W15  PE0_TX_DP3  SOCKET4677_AZIFS054P001C01  I37

P5E_CPU0_PE0_TX_DP<13>   @S9S_MB_2U_LIB.S9S_MB_2U(SCH_1):P5E_CPU0_PE0_TX_DP<13>
  C907     2      2  Q_CAP_DIFFBUS  I70
  U2     T14  PE0_TX_DP2  SOCKET4677_AZIFS054P001C01  I37

P5E_CPU0_PE0_TX_DP<14>   @S9S_MB_2U_LIB.S9S_MB_2U(SCH_1):P5E_CPU0_PE0_TX_DP<14>
  C905     2      2  Q_CAP_DIFFBUS  I75
  U2     R15  PE0_TX_DP1  SOCKET4677_AZIFS054P001C01  I37

P5E_CPU0_PE0_TX_DP<15>   @S9S_MB_2U_LIB.S9S_MB_2U(SCH_1):P5E_CPU0_PE0_TX_DP<15>
  C903     2      2  Q_CAP_DIFFBUS  I78
  U2     M14  PE0_TX_DP0  SOCKET4677_AZIFS054P001C01  I37

P5E_CPU0_PE1_RX_DN<0>   @S9S_MB_2U_LIB.S9S_MB_2U(SCH_1):P5E_CPU0_PE1_RX_DN<0>
  J37    A18  PERP0  SCONN168_623403212  I86
  U2     CN9  PE1_RX_DP0  SOCKET4677_AZIFS054P001C01  I176

P5E_CPU0_PE1_RX_DN<1>   @S9S_MB_2U_LIB.S9S_MB_2U(SCH_1):P5E_CPU0_PE1_RX_DN<1>
  J37    A21  PERP1  SCONN168_623403212  I86
  U2     CM10  PE1_RX_DP1  SOCKET4677_AZIFS054P001C01  I176

P5E_CPU0_PE1_RX_DN<2>   @S9S_MB_2U_LIB.S9S_MB_2U(SCH_1):P5E_CPU0_PE1_RX_DN<2>
  J37    A24  PERP2  SCONN168_623403212  I86
  U2     CJ9  PE1_RX_DP2  SOCKET4677_AZIFS054P001C01  I176

P5E_CPU0_PE1_RX_DN<3>   @S9S_MB_2U_LIB.S9S_MB_2U(SCH_1):P5E_CPU0_PE1_RX_DN<3>
  J37    A27  PERP3  SCONN168_623403212  I86
  U2     CH10  PE1_RX_DP3  SOCKET4677_AZIFS054P001C01  I176

P5E_CPU0_PE1_RX_DN<4>   @S9S_MB_2U_LIB.S9S_MB_2U(SCH_1):P5E_CPU0_PE1_RX_DN<4>
  J37    A31  PERP4  SCONN168_623403212  I86
  U2     CE9  PE1_RX_DP4  SOCKET4677_AZIFS054P001C01  I176

P5E_CPU0_PE1_RX_DN<5>   @S9S_MB_2U_LIB.S9S_MB_2U(SCH_1):P5E_CPU0_PE1_RX_DN<5>
  J37    A34  PERP5  SCONN168_623403212  I86
  U2     CD10  PE1_RX_DP5  SOCKET4677_AZIFS054P001C01  I176

P5E_CPU0_PE1_RX_DN<6>   @S9S_MB_2U_LIB.S9S_MB_2U(SCH_1):P5E_CPU0_PE1_RX_DN<6>
  J37    A37  PERP6  SCONN168_623403212  I86
  U2     CA9  PE1_RX_DP6  SOCKET4677_AZIFS054P001C01  I176

P5E_CPU0_PE1_RX_DN<7>   @S9S_MB_2U_LIB.S9S_MB_2U(SCH_1):P5E_CPU0_PE1_RX_DN<7>
  J37    A40  PERP7  SCONN168_623403212  I86
  U2     BY10  PE1_RX_DP7  SOCKET4677_AZIFS054P001C01  I176

P5E_CPU0_PE1_RX_DN<8>   @S9S_MB_2U_LIB.S9S_MB_2U(SCH_1):P5E_CPU0_PE1_RX_DN<8>
  J37    A45  PERP8  SCONN168_623403212  I86
  U2     BU9  PE1_RX_DP8  SOCKET4677_AZIFS054P001C01  I176

P5E_CPU0_PE1_RX_DN<9>   @S9S_MB_2U_LIB.S9S_MB_2U(SCH_1):P5E_CPU0_PE1_RX_DN<9>
  J37    A48  PERP9  SCONN168_623403212  I86
  U2     BT10  PE1_RX_DP9  SOCKET4677_AZIFS054P001C01  I176

P5E_CPU0_PE1_RX_DN<10>   @S9S_MB_2U_LIB.S9S_MB_2U(SCH_1):P5E_CPU0_PE1_RX_DN<10>
  J37    A51  PERP10  SCONN168_623403212  I86
  U2     BN9  PE1_RX_DP10  SOCKET4677_AZIFS054P001C01  I176

P5E_CPU0_PE1_RX_DN<11>   @S9S_MB_2U_LIB.S9S_MB_2U(SCH_1):P5E_CPU0_PE1_RX_DN<11>
  J37    A54  PERP11  SCONN168_623403212  I86
  U2     BM10  PE1_RX_DP11  SOCKET4677_AZIFS054P001C01  I176

P5E_CPU0_PE1_RX_DN<12>   @S9S_MB_2U_LIB.S9S_MB_2U(SCH_1):P5E_CPU0_PE1_RX_DN<12>
  J37    A57  PERP12  SCONN168_623403212  I86
  U2     BJ9  PE1_RX_DP12  SOCKET4677_AZIFS054P001C01  I176

P5E_CPU0_PE1_RX_DN<13>   @S9S_MB_2U_LIB.S9S_MB_2U(SCH_1):P5E_CPU0_PE1_RX_DN<13>
  J37    A60  PERP13  SCONN168_623403212  I86
  U2     BH10  PE1_RX_DP13  SOCKET4677_AZIFS054P001C01  I176

P5E_CPU0_PE1_RX_DN<14>   @S9S_MB_2U_LIB.S9S_MB_2U(SCH_1):P5E_CPU0_PE1_RX_DN<14>
  J37    A63  PERP14  SCONN168_623403212  I86
  U2     BE9  PE1_RX_DP14  SOCKET4677_AZIFS054P001C01  I176

P5E_CPU0_PE1_RX_DN<15>   @S9S_MB_2U_LIB.S9S_MB_2U(SCH_1):P5E_CPU0_PE1_RX_DN<15>
  J37    A66  PERP15  SCONN168_623403212  I86
  U2     BD10  PE1_RX_DP15  SOCKET4677_AZIFS054P001C01  I176

P5E_CPU0_PE1_RX_DP<0>   @S9S_MB_2U_LIB.S9S_MB_2U(SCH_1):P5E_CPU0_PE1_RX_DP<0>
  J37    A17  PERN0  SCONN168_623403212  I86
  U2     CP10  PE1_RX_DN0  SOCKET4677_AZIFS054P001C01  I176

P5E_CPU0_PE1_RX_DP<1>   @S9S_MB_2U_LIB.S9S_MB_2U(SCH_1):P5E_CPU0_PE1_RX_DP<1>
  J37    A20  PERN1  SCONN168_623403212  I86
  U2     CL11  PE1_RX_DN1  SOCKET4677_AZIFS054P001C01  I176

P5E_CPU0_PE1_RX_DP<2>   @S9S_MB_2U_LIB.S9S_MB_2U(SCH_1):P5E_CPU0_PE1_RX_DP<2>
  J37    A23  PERN2  SCONN168_623403212  I86
  U2     CK10  PE1_RX_DN2  SOCKET4677_AZIFS054P001C01  I176

P5E_CPU0_PE1_RX_DP<3>   @S9S_MB_2U_LIB.S9S_MB_2U(SCH_1):P5E_CPU0_PE1_RX_DP<3>
  J37    A26  PERN3  SCONN168_623403212  I86
  U2     CG11  PE1_RX_DN3  SOCKET4677_AZIFS054P001C01  I176

P5E_CPU0_PE1_RX_DP<4>   @S9S_MB_2U_LIB.S9S_MB_2U(SCH_1):P5E_CPU0_PE1_RX_DP<4>
  J37    A30  PERN4  SCONN168_623403212  I86
  U2     CF10  PE1_RX_DN4  SOCKET4677_AZIFS054P001C01  I176

P5E_CPU0_PE1_RX_DP<5>   @S9S_MB_2U_LIB.S9S_MB_2U(SCH_1):P5E_CPU0_PE1_RX_DP<5>
  J37    A33  PERN5  SCONN168_623403212  I86
  U2     CC11  PE1_RX_DN5  SOCKET4677_AZIFS054P001C01  I176

P5E_CPU0_PE1_RX_DP<6>   @S9S_MB_2U_LIB.S9S_MB_2U(SCH_1):P5E_CPU0_PE1_RX_DP<6>
  J37    A36  PERN6  SCONN168_623403212  I86
  U2     CB10  PE1_RX_DN6  SOCKET4677_AZIFS054P001C01  I176

P5E_CPU0_PE1_RX_DP<7>   @S9S_MB_2U_LIB.S9S_MB_2U(SCH_1):P5E_CPU0_PE1_RX_DP<7>
  J37    A39  PERN7  SCONN168_623403212  I86
  U2     BW11  PE1_RX_DN7  SOCKET4677_AZIFS054P001C01  I176

P5E_CPU0_PE1_RX_DP<8>   @S9S_MB_2U_LIB.S9S_MB_2U(SCH_1):P5E_CPU0_PE1_RX_DP<8>
  J37    A44  PERN8  SCONN168_623403212  I86
  U2     BV10  PE1_RX_DN8  SOCKET4677_AZIFS054P001C01  I176

P5E_CPU0_PE1_RX_DP<9>   @S9S_MB_2U_LIB.S9S_MB_2U(SCH_1):P5E_CPU0_PE1_RX_DP<9>
  J37    A47  PERN9  SCONN168_623403212  I86
  U2     BR11  PE1_RX_DN9  SOCKET4677_AZIFS054P001C01  I176

P5E_CPU0_PE1_RX_DP<10>   @S9S_MB_2U_LIB.S9S_MB_2U(SCH_1):P5E_CPU0_PE1_RX_DP<10>
  J37    A50  PERN10  SCONN168_623403212  I86
  U2     BP10  PE1_RX_DN10  SOCKET4677_AZIFS054P001C01  I176

P5E_CPU0_PE1_RX_DP<11>   @S9S_MB_2U_LIB.S9S_MB_2U(SCH_1):P5E_CPU0_PE1_RX_DP<11>
  J37    A53  PERN11  SCONN168_623403212  I86
  U2     BL11  PE1_RX_DN11  SOCKET4677_AZIFS054P001C01  I176

P5E_CPU0_PE1_RX_DP<12>   @S9S_MB_2U_LIB.S9S_MB_2U(SCH_1):P5E_CPU0_PE1_RX_DP<12>
  J37    A56  PERN12  SCONN168_623403212  I86
  U2     BK10  PE1_RX_DN12  SOCKET4677_AZIFS054P001C01  I176

P5E_CPU0_PE1_RX_DP<13>   @S9S_MB_2U_LIB.S9S_MB_2U(SCH_1):P5E_CPU0_PE1_RX_DP<13>
  J37    A59  PERN13  SCONN168_623403212  I86
  U2     BG11  PE1_RX_DN13  SOCKET4677_AZIFS054P001C01  I176

P5E_CPU0_PE1_RX_DP<14>   @S9S_MB_2U_LIB.S9S_MB_2U(SCH_1):P5E_CPU0_PE1_RX_DP<14>
  J37    A62  PERN14  SCONN168_623403212  I86
  U2     BF10  PE1_RX_DN14  SOCKET4677_AZIFS054P001C01  I176

P5E_CPU0_PE1_RX_DP<15>   @S9S_MB_2U_LIB.S9S_MB_2U(SCH_1):P5E_CPU0_PE1_RX_DP<15>
  J37    A65  PERN15  SCONN168_623403212  I86
  U2     BC11  PE1_RX_DN15  SOCKET4677_AZIFS054P001C01  I176

P5E_CPU0_PE1_TX_C_DN<0>   @S9S_MB_2U_LIB.S9S_MB_2U(SCH_1):P5E_CPU0_PE1_TX_C_DN<0>
  C964     1      1  Q_CAP_DIFFBUS  I117
  J37    B18  PETP0  SCONN168_623403212  I86

P5E_CPU0_PE1_TX_C_DN<1>   @S9S_MB_2U_LIB.S9S_MB_2U(SCH_1):P5E_CPU0_PE1_TX_C_DN<1>
  C962     1      1  Q_CAP_DIFFBUS  I118
  J37    B21  PETP1  SCONN168_623403212  I86

P5E_CPU0_PE1_TX_C_DN<2>   @S9S_MB_2U_LIB.S9S_MB_2U(SCH_1):P5E_CPU0_PE1_TX_C_DN<2>
  C960     1      1  Q_CAP_DIFFBUS  I119
  J37    B24  PETP2  SCONN168_623403212  I86

P5E_CPU0_PE1_TX_C_DN<3>   @S9S_MB_2U_LIB.S9S_MB_2U(SCH_1):P5E_CPU0_PE1_TX_C_DN<3>
  C958     1      1  Q_CAP_DIFFBUS  I122
  J37    B27  PETP3  SCONN168_623403212  I86

P5E_CPU0_PE1_TX_C_DN<4>   @S9S_MB_2U_LIB.S9S_MB_2U(SCH_1):P5E_CPU0_PE1_TX_C_DN<4>
  C956     1      1  Q_CAP_DIFFBUS  I124
  J37    B31  PETP4  SCONN168_623403212  I86

P5E_CPU0_PE1_TX_C_DN<5>   @S9S_MB_2U_LIB.S9S_MB_2U(SCH_1):P5E_CPU0_PE1_TX_C_DN<5>
  C954     1      1  Q_CAP_DIFFBUS  I162
  J37    B34  PETP5  SCONN168_623403212  I86

P5E_CPU0_PE1_TX_C_DN<6>   @S9S_MB_2U_LIB.S9S_MB_2U(SCH_1):P5E_CPU0_PE1_TX_C_DN<6>
  C952     1      1  Q_CAP_DIFFBUS  I164
  J37    B37  PETP6  SCONN168_623403212  I86

P5E_CPU0_PE1_TX_C_DN<7>   @S9S_MB_2U_LIB.S9S_MB_2U(SCH_1):P5E_CPU0_PE1_TX_C_DN<7>
  C950     1      1  Q_CAP_DIFFBUS  I165
  J37    B40  PETP7  SCONN168_623403212  I86

P5E_CPU0_PE1_TX_C_DN<8>   @S9S_MB_2U_LIB.S9S_MB_2U(SCH_1):P5E_CPU0_PE1_TX_C_DN<8>
  C948     1      1  Q_CAP_DIFFBUS  I168
  J37    B45  PETP8  SCONN168_623403212  I86

P5E_CPU0_PE1_TX_C_DN<9>   @S9S_MB_2U_LIB.S9S_MB_2U(SCH_1):P5E_CPU0_PE1_TX_C_DN<9>
  C946     1      1  Q_CAP_DIFFBUS  I177
  J37    B48  PETP9  SCONN168_623403212  I86

P5E_CPU0_PE1_TX_C_DN<10>   @S9S_MB_2U_LIB.S9S_MB_2U(SCH_1):P5E_CPU0_PE1_TX_C_DN<10>
  C944     1      1  Q_CAP_DIFFBUS  I179
  J37    B51  PETP10  SCONN168_623403212  I86

P5E_CPU0_PE1_TX_C_DN<11>   @S9S_MB_2U_LIB.S9S_MB_2U(SCH_1):P5E_CPU0_PE1_TX_C_DN<11>
  C942     1      1  Q_CAP_DIFFBUS  I181
  J37    B54  PETP11  SCONN168_623403212  I86

P5E_CPU0_PE1_TX_C_DN<12>   @S9S_MB_2U_LIB.S9S_MB_2U(SCH_1):P5E_CPU0_PE1_TX_C_DN<12>
  C940     1      1  Q_CAP_DIFFBUS  I185
  J37    B57  PETP12  SCONN168_623403212  I86

P5E_CPU0_PE1_TX_C_DN<13>   @S9S_MB_2U_LIB.S9S_MB_2U(SCH_1):P5E_CPU0_PE1_TX_C_DN<13>
  C938     1      1  Q_CAP_DIFFBUS  I183
  J37    B60  PETP13  SCONN168_623403212  I86

P5E_CPU0_PE1_TX_C_DN<14>   @S9S_MB_2U_LIB.S9S_MB_2U(SCH_1):P5E_CPU0_PE1_TX_C_DN<14>
  C936     1      1  Q_CAP_DIFFBUS  I200
  J37    B63  PETP14  SCONN168_623403212  I86

P5E_CPU0_PE1_TX_C_DN<15>   @S9S_MB_2U_LIB.S9S_MB_2U(SCH_1):P5E_CPU0_PE1_TX_C_DN<15>
  C934     1      1  Q_CAP_DIFFBUS  I201
  J37    B66  PETP15  SCONN168_623403212  I86

P5E_CPU0_PE1_TX_C_DP<0>   @S9S_MB_2U_LIB.S9S_MB_2U(SCH_1):P5E_CPU0_PE1_TX_C_DP<0>
  C965     1      1  Q_CAP_DIFFBUS  I115
  J37    B17  PETN0  SCONN168_623403212  I86

P5E_CPU0_PE1_TX_C_DP<1>   @S9S_MB_2U_LIB.S9S_MB_2U(SCH_1):P5E_CPU0_PE1_TX_C_DP<1>
  C963     1      1  Q_CAP_DIFFBUS  I116
  J37    B20  PETN1  SCONN168_623403212  I86

P5E_CPU0_PE1_TX_C_DP<2>   @S9S_MB_2U_LIB.S9S_MB_2U(SCH_1):P5E_CPU0_PE1_TX_C_DP<2>
  C961     1      1  Q_CAP_DIFFBUS  I120
  J37    B23  PETN2  SCONN168_623403212  I86

P5E_CPU0_PE1_TX_C_DP<3>   @S9S_MB_2U_LIB.S9S_MB_2U(SCH_1):P5E_CPU0_PE1_TX_C_DP<3>
  C959     1      1  Q_CAP_DIFFBUS  I121
  J37    B26  PETN3  SCONN168_623403212  I86

P5E_CPU0_PE1_TX_C_DP<4>   @S9S_MB_2U_LIB.S9S_MB_2U(SCH_1):P5E_CPU0_PE1_TX_C_DP<4>
  C957     1      1  Q_CAP_DIFFBUS  I123
  J37    B30  PETN4  SCONN168_623403212  I86

P5E_CPU0_PE1_TX_C_DP<5>   @S9S_MB_2U_LIB.S9S_MB_2U(SCH_1):P5E_CPU0_PE1_TX_C_DP<5>
  C955     1      1  Q_CAP_DIFFBUS  I125
  J37    B33  PETN5  SCONN168_623403212  I86

P5E_CPU0_PE1_TX_C_DP<6>   @S9S_MB_2U_LIB.S9S_MB_2U(SCH_1):P5E_CPU0_PE1_TX_C_DP<6>
  C953     1      1  Q_CAP_DIFFBUS  I163
  J37    B36  PETN6  SCONN168_623403212  I86

P5E_CPU0_PE1_TX_C_DP<7>   @S9S_MB_2U_LIB.S9S_MB_2U(SCH_1):P5E_CPU0_PE1_TX_C_DP<7>
  C951     1      1  Q_CAP_DIFFBUS  I166
  J37    B39  PETN7  SCONN168_623403212  I86

P5E_CPU0_PE1_TX_C_DP<8>   @S9S_MB_2U_LIB.S9S_MB_2U(SCH_1):P5E_CPU0_PE1_TX_C_DP<8>
  C949     1      1  Q_CAP_DIFFBUS  I167
  J37    B44  PETN8  SCONN168_623403212  I86

P5E_CPU0_PE1_TX_C_DP<9>   @S9S_MB_2U_LIB.S9S_MB_2U(SCH_1):P5E_CPU0_PE1_TX_C_DP<9>
  C947     1      1  Q_CAP_DIFFBUS  I176
  J37    B47  PETN9  SCONN168_623403212  I86

P5E_CPU0_PE1_TX_C_DP<10>   @S9S_MB_2U_LIB.S9S_MB_2U(SCH_1):P5E_CPU0_PE1_TX_C_DP<10>
  C945     1      1  Q_CAP_DIFFBUS  I178
  J37    B50  PETN10  SCONN168_623403212  I86

P5E_CPU0_PE1_TX_C_DP<11>   @S9S_MB_2U_LIB.S9S_MB_2U(SCH_1):P5E_CPU0_PE1_TX_C_DP<11>
  C943     1      1  Q_CAP_DIFFBUS  I182
  J37    B53  PETN11  SCONN168_623403212  I86

P5E_CPU0_PE1_TX_C_DP<12>   @S9S_MB_2U_LIB.S9S_MB_2U(SCH_1):P5E_CPU0_PE1_TX_C_DP<12>
  C941     1      1  Q_CAP_DIFFBUS  I180
  J37    B56  PETN12  SCONN168_623403212  I86

P5E_CPU0_PE1_TX_C_DP<13>   @S9S_MB_2U_LIB.S9S_MB_2U(SCH_1):P5E_CPU0_PE1_TX_C_DP<13>
  C939     1      1  Q_CAP_DIFFBUS  I184
  J37    B59  PETN13  SCONN168_623403212  I86

P5E_CPU0_PE1_TX_C_DP<14>   @S9S_MB_2U_LIB.S9S_MB_2U(SCH_1):P5E_CPU0_PE1_TX_C_DP<14>
  C937     1      1  Q_CAP_DIFFBUS  I199
  J37    B62  PETN14  SCONN168_623403212  I86

P5E_CPU0_PE1_TX_C_DP<15>   @S9S_MB_2U_LIB.S9S_MB_2U(SCH_1):P5E_CPU0_PE1_TX_C_DP<15>
  C935     1      1  Q_CAP_DIFFBUS  I202
  J37    B65  PETN15  SCONN168_623403212  I86

P5E_CPU0_PE1_TX_DN<0>   @S9S_MB_2U_LIB.S9S_MB_2U(SCH_1):P5E_CPU0_PE1_TX_DN<0>
  C964     2      2  Q_CAP_DIFFBUS  I117
  U2     CP14  PE1_TX_DN0  SOCKET4677_AZIFS054P001C01  I176

P5E_CPU0_PE1_TX_DN<1>   @S9S_MB_2U_LIB.S9S_MB_2U(SCH_1):P5E_CPU0_PE1_TX_DN<1>
  C962     2      2  Q_CAP_DIFFBUS  I118
  U2     CN13  PE1_TX_DN1  SOCKET4677_AZIFS054P001C01  I176

P5E_CPU0_PE1_TX_DN<2>   @S9S_MB_2U_LIB.S9S_MB_2U(SCH_1):P5E_CPU0_PE1_TX_DN<2>
  C960     2      2  Q_CAP_DIFFBUS  I119
  U2     CK14  PE1_TX_DN2  SOCKET4677_AZIFS054P001C01  I176

P5E_CPU0_PE1_TX_DN<3>   @S9S_MB_2U_LIB.S9S_MB_2U(SCH_1):P5E_CPU0_PE1_TX_DN<3>
  C958     2      2  Q_CAP_DIFFBUS  I122
  U2     CJ13  PE1_TX_DN3  SOCKET4677_AZIFS054P001C01  I176

P5E_CPU0_PE1_TX_DN<4>   @S9S_MB_2U_LIB.S9S_MB_2U(SCH_1):P5E_CPU0_PE1_TX_DN<4>
  C956     2      2  Q_CAP_DIFFBUS  I124
  U2     CF14  PE1_TX_DN4  SOCKET4677_AZIFS054P001C01  I176

P5E_CPU0_PE1_TX_DN<5>   @S9S_MB_2U_LIB.S9S_MB_2U(SCH_1):P5E_CPU0_PE1_TX_DN<5>
  C954     2      2  Q_CAP_DIFFBUS  I162
  U2     CE13  PE1_TX_DN5  SOCKET4677_AZIFS054P001C01  I176

P5E_CPU0_PE1_TX_DN<6>   @S9S_MB_2U_LIB.S9S_MB_2U(SCH_1):P5E_CPU0_PE1_TX_DN<6>
  C952     2      2  Q_CAP_DIFFBUS  I164
  U2     CB14  PE1_TX_DN6  SOCKET4677_AZIFS054P001C01  I176

P5E_CPU0_PE1_TX_DN<7>   @S9S_MB_2U_LIB.S9S_MB_2U(SCH_1):P5E_CPU0_PE1_TX_DN<7>
  C950     2      2  Q_CAP_DIFFBUS  I165
  U2     CA13  PE1_TX_DN7  SOCKET4677_AZIFS054P001C01  I176

P5E_CPU0_PE1_TX_DN<8>   @S9S_MB_2U_LIB.S9S_MB_2U(SCH_1):P5E_CPU0_PE1_TX_DN<8>
  C948     2      2  Q_CAP_DIFFBUS  I168
  U2     BV14  PE1_TX_DN8  SOCKET4677_AZIFS054P001C01  I176

P5E_CPU0_PE1_TX_DN<9>   @S9S_MB_2U_LIB.S9S_MB_2U(SCH_1):P5E_CPU0_PE1_TX_DN<9>
  C946     2      2  Q_CAP_DIFFBUS  I177
  U2     BU13  PE1_TX_DN9  SOCKET4677_AZIFS054P001C01  I176

P5E_CPU0_PE1_TX_DN<10>   @S9S_MB_2U_LIB.S9S_MB_2U(SCH_1):P5E_CPU0_PE1_TX_DN<10>
  C944     2      2  Q_CAP_DIFFBUS  I179
  U2     BP14  PE1_TX_DN10  SOCKET4677_AZIFS054P001C01  I176

P5E_CPU0_PE1_TX_DN<11>   @S9S_MB_2U_LIB.S9S_MB_2U(SCH_1):P5E_CPU0_PE1_TX_DN<11>
  C942     2      2  Q_CAP_DIFFBUS  I181
  U2     BN13  PE1_TX_DN11  SOCKET4677_AZIFS054P001C01  I176

P5E_CPU0_PE1_TX_DN<12>   @S9S_MB_2U_LIB.S9S_MB_2U(SCH_1):P5E_CPU0_PE1_TX_DN<12>
  C940     2      2  Q_CAP_DIFFBUS  I185
  U2     BK14  PE1_TX_DN12  SOCKET4677_AZIFS054P001C01  I176

P5E_CPU0_PE1_TX_DN<13>   @S9S_MB_2U_LIB.S9S_MB_2U(SCH_1):P5E_CPU0_PE1_TX_DN<13>
  C938     2      2  Q_CAP_DIFFBUS  I183
  U2     BJ13  PE1_TX_DN13  SOCKET4677_AZIFS054P001C01  I176

P5E_CPU0_PE1_TX_DN<14>   @S9S_MB_2U_LIB.S9S_MB_2U(SCH_1):P5E_CPU0_PE1_TX_DN<14>
  C936     2      2  Q_CAP_DIFFBUS  I200
  U2     BF14  PE1_TX_DN14  SOCKET4677_AZIFS054P001C01  I176

P5E_CPU0_PE1_TX_DN<15>   @S9S_MB_2U_LIB.S9S_MB_2U(SCH_1):P5E_CPU0_PE1_TX_DN<15>
  C934     2      2  Q_CAP_DIFFBUS  I201
  U2     BE13  PE1_TX_DN15  SOCKET4677_AZIFS054P001C01  I176

P5E_CPU0_PE1_TX_DP<0>   @S9S_MB_2U_LIB.S9S_MB_2U(SCH_1):P5E_CPU0_PE1_TX_DP<0>
  C965     2      2  Q_CAP_DIFFBUS  I115
  U2     CR15  PE1_TX_DP0  SOCKET4677_AZIFS054P001C01  I176

P5E_CPU0_PE1_TX_DP<1>   @S9S_MB_2U_LIB.S9S_MB_2U(SCH_1):P5E_CPU0_PE1_TX_DP<1>
  C963     2      2  Q_CAP_DIFFBUS  I116
  U2     CM14  PE1_TX_DP1  SOCKET4677_AZIFS054P001C01  I176

P5E_CPU0_PE1_TX_DP<2>   @S9S_MB_2U_LIB.S9S_MB_2U(SCH_1):P5E_CPU0_PE1_TX_DP<2>
  C961     2      2  Q_CAP_DIFFBUS  I120
  U2     CL15  PE1_TX_DP2  SOCKET4677_AZIFS054P001C01  I176

P5E_CPU0_PE1_TX_DP<3>   @S9S_MB_2U_LIB.S9S_MB_2U(SCH_1):P5E_CPU0_PE1_TX_DP<3>
  C959     2      2  Q_CAP_DIFFBUS  I121
  U2     CH14  PE1_TX_DP3  SOCKET4677_AZIFS054P001C01  I176

P5E_CPU0_PE1_TX_DP<4>   @S9S_MB_2U_LIB.S9S_MB_2U(SCH_1):P5E_CPU0_PE1_TX_DP<4>
  C957     2      2  Q_CAP_DIFFBUS  I123
  U2     CG15  PE1_TX_DP4  SOCKET4677_AZIFS054P001C01  I176

P5E_CPU0_PE1_TX_DP<5>   @S9S_MB_2U_LIB.S9S_MB_2U(SCH_1):P5E_CPU0_PE1_TX_DP<5>
  C955     2      2  Q_CAP_DIFFBUS  I125
  U2     CD14  PE1_TX_DP5  SOCKET4677_AZIFS054P001C01  I176

P5E_CPU0_PE1_TX_DP<6>   @S9S_MB_2U_LIB.S9S_MB_2U(SCH_1):P5E_CPU0_PE1_TX_DP<6>
  C953     2      2  Q_CAP_DIFFBUS  I163
  U2     CC15  PE1_TX_DP6  SOCKET4677_AZIFS054P001C01  I176

P5E_CPU0_PE1_TX_DP<7>   @S9S_MB_2U_LIB.S9S_MB_2U(SCH_1):P5E_CPU0_PE1_TX_DP<7>
  C951     2      2  Q_CAP_DIFFBUS  I166
  U2     BY14  PE1_TX_DP7  SOCKET4677_AZIFS054P001C01  I176

P5E_CPU0_PE1_TX_DP<8>   @S9S_MB_2U_LIB.S9S_MB_2U(SCH_1):P5E_CPU0_PE1_TX_DP<8>
  C949     2      2  Q_CAP_DIFFBUS  I167
  U2     BW15  PE1_TX_DP8  SOCKET4677_AZIFS054P001C01  I176

P5E_CPU0_PE1_TX_DP<9>   @S9S_MB_2U_LIB.S9S_MB_2U(SCH_1):P5E_CPU0_PE1_TX_DP<9>
  C947     2      2  Q_CAP_DIFFBUS  I176
  U2     BT14  PE1_TX_DP9  SOCKET4677_AZIFS054P001C01  I176

P5E_CPU0_PE1_TX_DP<10>   @S9S_MB_2U_LIB.S9S_MB_2U(SCH_1):P5E_CPU0_PE1_TX_DP<10>
  C945     2      2  Q_CAP_DIFFBUS  I178
  U2     BR15  PE1_TX_DP10  SOCKET4677_AZIFS054P001C01  I176

P5E_CPU0_PE1_TX_DP<11>   @S9S_MB_2U_LIB.S9S_MB_2U(SCH_1):P5E_CPU0_PE1_TX_DP<11>
  C943     2      2  Q_CAP_DIFFBUS  I182
  U2     BM14  PE1_TX_DP11  SOCKET4677_AZIFS054P001C01  I176

P5E_CPU0_PE1_TX_DP<12>   @S9S_MB_2U_LIB.S9S_MB_2U(SCH_1):P5E_CPU0_PE1_TX_DP<12>
  C941     2      2  Q_CAP_DIFFBUS  I180
  U2     BL15  PE1_TX_DP12  SOCKET4677_AZIFS054P001C01  I176

P5E_CPU0_PE1_TX_DP<13>   @S9S_MB_2U_LIB.S9S_MB_2U(SCH_1):P5E_CPU0_PE1_TX_DP<13>
  C939     2      2  Q_CAP_DIFFBUS  I184
  U2     BH14  PE1_TX_DP13  SOCKET4677_AZIFS054P001C01  I176

P5E_CPU0_PE1_TX_DP<14>   @S9S_MB_2U_LIB.S9S_MB_2U(SCH_1):P5E_CPU0_PE1_TX_DP<14>
  C937     2      2  Q_CAP_DIFFBUS  I199
  U2     BG15  PE1_TX_DP14  SOCKET4677_AZIFS054P001C01  I176

P5E_CPU0_PE1_TX_DP<15>   @S9S_MB_2U_LIB.S9S_MB_2U(SCH_1):P5E_CPU0_PE1_TX_DP<15>
  C935     2      2  Q_CAP_DIFFBUS  I202
  U2     BD14  PE1_TX_DP15  SOCKET4677_AZIFS054P001C01  I176

P5E_CPU0_PE2_RX_DN<0>   @S9S_MB_2U_LIB.S9S_MB_2U(SCH_1):P5E_CPU0_PE2_RX_DN<0>
  J55    B66  SIGNAL_B66  SCONN140_G64V3431BHR  I150
  U2     CU9  PE2_RX_DN0  SOCKET4677_AZIFS054P001C01  I139

P5E_CPU0_PE2_RX_DN<1>   @S9S_MB_2U_LIB.S9S_MB_2U(SCH_1):P5E_CPU0_PE2_RX_DN<1>
  J55    B63  SIGNAL_B63  SCONN140_G64V3431BHR  I150
  U2     CY10  PE2_RX_DN1  SOCKET4677_AZIFS054P001C01  I139

P5E_CPU0_PE2_RX_DN<2>   @S9S_MB_2U_LIB.S9S_MB_2U(SCH_1):P5E_CPU0_PE2_RX_DN<2>
  J55    B60  SIGNAL_B60  SCONN140_G64V3431BHR  I150
  U2     DA9  PE2_RX_DN2  SOCKET4677_AZIFS054P001C01  I139

P5E_CPU0_PE2_RX_DN<3>   @S9S_MB_2U_LIB.S9S_MB_2U(SCH_1):P5E_CPU0_PE2_RX_DN<3>
  J55    B57  SIGNAL_B57  SCONN140_G64V3431BHR  I150
  U2     DD10  PE2_RX_DN3  SOCKET4677_AZIFS054P001C01  I139

P5E_CPU0_PE2_RX_DN<4>   @S9S_MB_2U_LIB.S9S_MB_2U(SCH_1):P5E_CPU0_PE2_RX_DN<4>
  J55    B54  SIGNAL_B54  SCONN140_G64V3431BHR  I150
  U2     DE9  PE2_RX_DN4  SOCKET4677_AZIFS054P001C01  I139

P5E_CPU0_PE2_RX_DN<5>   @S9S_MB_2U_LIB.S9S_MB_2U(SCH_1):P5E_CPU0_PE2_RX_DN<5>
  J55    B51  SIGNAL_B51  SCONN140_G64V3431BHR  I150
  U2     DH10  PE2_RX_DN5  SOCKET4677_AZIFS054P001C01  I139

P5E_CPU0_PE2_RX_DN<6>   @S9S_MB_2U_LIB.S9S_MB_2U(SCH_1):P5E_CPU0_PE2_RX_DN<6>
  J55    B48  SIGNAL_B48  SCONN140_G64V3431BHR  I150
  U2     DJ9  PE2_RX_DN6  SOCKET4677_AZIFS054P001C01  I139

P5E_CPU0_PE2_RX_DN<7>   @S9S_MB_2U_LIB.S9S_MB_2U(SCH_1):P5E_CPU0_PE2_RX_DN<7>
  J55    B45  SIGNAL_B45  SCONN140_G64V3431BHR  I150
  U2     DM10  PE2_RX_DN7  SOCKET4677_AZIFS054P001C01  I139

P5E_CPU0_PE2_RX_DN<8>   @S9S_MB_2U_LIB.S9S_MB_2U(SCH_1):P5E_CPU0_PE2_RX_DN<8>
  J55    B40  SIGNAL_B40  SCONN140_G64V3431BHR  I150
  U2     DN9  PE2_RX_DN8  SOCKET4677_AZIFS054P001C01  I139

P5E_CPU0_PE2_RX_DN<9>   @S9S_MB_2U_LIB.S9S_MB_2U(SCH_1):P5E_CPU0_PE2_RX_DN<9>
  J55    B37  SIGNAL_B37  SCONN140_G64V3431BHR  I150
  U2     DT10  PE2_RX_DN9  SOCKET4677_AZIFS054P001C01  I139

P5E_CPU0_PE2_RX_DN<10>   @S9S_MB_2U_LIB.S9S_MB_2U(SCH_1):P5E_CPU0_PE2_RX_DN<10>
  J55    B34  SIGNAL_B34  SCONN140_G64V3431BHR  I150
  U2     DU9  PE2_RX_DN10  SOCKET4677_AZIFS054P001C01  I139

P5E_CPU0_PE2_RX_DN<11>   @S9S_MB_2U_LIB.S9S_MB_2U(SCH_1):P5E_CPU0_PE2_RX_DN<11>
  J55    B31  SIGNAL_B31  SCONN140_G64V3431BHR  I150
  U2     DY10  PE2_RX_DN11  SOCKET4677_AZIFS054P001C01  I139

P5E_CPU0_PE2_RX_DN<12>   @S9S_MB_2U_LIB.S9S_MB_2U(SCH_1):P5E_CPU0_PE2_RX_DN<12>
  J55    B27  SIGNAL_B27  SCONN140_G64V3431BHR  I150
  U2     EA9  PE2_RX_DN12  SOCKET4677_AZIFS054P001C01  I139

P5E_CPU0_PE2_RX_DN<13>   @S9S_MB_2U_LIB.S9S_MB_2U(SCH_1):P5E_CPU0_PE2_RX_DN<13>
  J55    B24  SIGNAL_B24  SCONN140_G64V3431BHR  I150
  U2     ED10  PE2_RX_DN13  SOCKET4677_AZIFS054P001C01  I139

P5E_CPU0_PE2_RX_DN<14>   @S9S_MB_2U_LIB.S9S_MB_2U(SCH_1):P5E_CPU0_PE2_RX_DN<14>
  J55    B21  SIGNAL_B21  SCONN140_G64V3431BHR  I150
  U2     EE9  PE2_RX_DN14  SOCKET4677_AZIFS054P001C01  I139

P5E_CPU0_PE2_RX_DN<15>   @S9S_MB_2U_LIB.S9S_MB_2U(SCH_1):P5E_CPU0_PE2_RX_DN<15>
  J55    B18  SIGNAL_B18  SCONN140_G64V3431BHR  I150
  U2     EH10  PE2_RX_DN15  SOCKET4677_AZIFS054P001C01  I139

P5E_CPU0_PE2_RX_DP<0>   @S9S_MB_2U_LIB.S9S_MB_2U(SCH_1):P5E_CPU0_PE2_RX_DP<0>
  J55    B65  SIGNAL_B65  SCONN140_G64V3431BHR  I150
  U2     CV10  PE2_RX_DP0  SOCKET4677_AZIFS054P001C01  I139

P5E_CPU0_PE2_RX_DP<1>   @S9S_MB_2U_LIB.S9S_MB_2U(SCH_1):P5E_CPU0_PE2_RX_DP<1>
  J55    B62  SIGNAL_B62  SCONN140_G64V3431BHR  I150
  U2     CW11  PE2_RX_DP1  SOCKET4677_AZIFS054P001C01  I139

P5E_CPU0_PE2_RX_DP<2>   @S9S_MB_2U_LIB.S9S_MB_2U(SCH_1):P5E_CPU0_PE2_RX_DP<2>
  J55    B59  SIGNAL_B59  SCONN140_G64V3431BHR  I150
  U2     DB10  PE2_RX_DP2  SOCKET4677_AZIFS054P001C01  I139

P5E_CPU0_PE2_RX_DP<3>   @S9S_MB_2U_LIB.S9S_MB_2U(SCH_1):P5E_CPU0_PE2_RX_DP<3>
  J55    B56  SIGNAL_B56  SCONN140_G64V3431BHR  I150
  U2     DC11  PE2_RX_DP3  SOCKET4677_AZIFS054P001C01  I139

P5E_CPU0_PE2_RX_DP<4>   @S9S_MB_2U_LIB.S9S_MB_2U(SCH_1):P5E_CPU0_PE2_RX_DP<4>
  J55    B53  SIGNAL_B53  SCONN140_G64V3431BHR  I150
  U2     DF10  PE2_RX_DP4  SOCKET4677_AZIFS054P001C01  I139

P5E_CPU0_PE2_RX_DP<5>   @S9S_MB_2U_LIB.S9S_MB_2U(SCH_1):P5E_CPU0_PE2_RX_DP<5>
  J55    B50  SIGNAL_B50  SCONN140_G64V3431BHR  I150
  U2     DG11  PE2_RX_DP5  SOCKET4677_AZIFS054P001C01  I139

P5E_CPU0_PE2_RX_DP<6>   @S9S_MB_2U_LIB.S9S_MB_2U(SCH_1):P5E_CPU0_PE2_RX_DP<6>
  J55    B47  SIGNAL_B47  SCONN140_G64V3431BHR  I150
  U2     DK10  PE2_RX_DP6  SOCKET4677_AZIFS054P001C01  I139

P5E_CPU0_PE2_RX_DP<7>   @S9S_MB_2U_LIB.S9S_MB_2U(SCH_1):P5E_CPU0_PE2_RX_DP<7>
  J55    B44  SIGNAL_B44  SCONN140_G64V3431BHR  I150
  U2     DL11  PE2_RX_DP7  SOCKET4677_AZIFS054P001C01  I139

P5E_CPU0_PE2_RX_DP<8>   @S9S_MB_2U_LIB.S9S_MB_2U(SCH_1):P5E_CPU0_PE2_RX_DP<8>
  J55    B39  SIGNAL_B39  SCONN140_G64V3431BHR  I150
  U2     DP10  PE2_RX_DP8  SOCKET4677_AZIFS054P001C01  I139

P5E_CPU0_PE2_RX_DP<9>   @S9S_MB_2U_LIB.S9S_MB_2U(SCH_1):P5E_CPU0_PE2_RX_DP<9>
  J55    B36  SIGNAL_B36  SCONN140_G64V3431BHR  I150
  U2     DR11  PE2_RX_DP9  SOCKET4677_AZIFS054P001C01  I139

P5E_CPU0_PE2_RX_DP<10>   @S9S_MB_2U_LIB.S9S_MB_2U(SCH_1):P5E_CPU0_PE2_RX_DP<10>
  J55    B33  SIGNAL_B33  SCONN140_G64V3431BHR  I150
  U2     DV10  PE2_RX_DP10  SOCKET4677_AZIFS054P001C01  I139

P5E_CPU0_PE2_RX_DP<11>   @S9S_MB_2U_LIB.S9S_MB_2U(SCH_1):P5E_CPU0_PE2_RX_DP<11>
  J55    B30  SIGNAL_B30  SCONN140_G64V3431BHR  I150
  U2     DW11  PE2_RX_DP11  SOCKET4677_AZIFS054P001C01  I139

P5E_CPU0_PE2_RX_DP<12>   @S9S_MB_2U_LIB.S9S_MB_2U(SCH_1):P5E_CPU0_PE2_RX_DP<12>
  J55    B26  SIGNAL_B26  SCONN140_G64V3431BHR  I150
  U2     EB10  PE2_RX_DP12  SOCKET4677_AZIFS054P001C01  I139

P5E_CPU0_PE2_RX_DP<13>   @S9S_MB_2U_LIB.S9S_MB_2U(SCH_1):P5E_CPU0_PE2_RX_DP<13>
  J55    B23  SIGNAL_B23  SCONN140_G64V3431BHR  I150
  U2     EC11  PE2_RX_DP13  SOCKET4677_AZIFS054P001C01  I139

P5E_CPU0_PE2_RX_DP<14>   @S9S_MB_2U_LIB.S9S_MB_2U(SCH_1):P5E_CPU0_PE2_RX_DP<14>
  J55    B20  SIGNAL_B20  SCONN140_G64V3431BHR  I150
  U2     EF10  PE2_RX_DP14  SOCKET4677_AZIFS054P001C01  I139

P5E_CPU0_PE2_RX_DP<15>   @S9S_MB_2U_LIB.S9S_MB_2U(SCH_1):P5E_CPU0_PE2_RX_DP<15>
  J55    B17  SIGNAL_B17  SCONN140_G64V3431BHR  I150
  U2     EG11  PE2_RX_DP15  SOCKET4677_AZIFS054P001C01  I139

P5E_CPU0_PE2_TX_C_DN<0>   @S9S_MB_2U_LIB.S9S_MB_2U(SCH_1):P5E_CPU0_PE2_TX_C_DN<0>
  C868     1      1  Q_CAP_DIFFBUS  I229
  J55    A66  SIGNAL_A66  SCONN140_G64V3431BHR  I150

P5E_CPU0_PE2_TX_C_DN<1>   @S9S_MB_2U_LIB.S9S_MB_2U(SCH_1):P5E_CPU0_PE2_TX_C_DN<1>
  C866     1      1  Q_CAP_DIFFBUS  I230
  J55    A63  SIGNAL_A63  SCONN140_G64V3431BHR  I150

P5E_CPU0_PE2_TX_C_DN<2>   @S9S_MB_2U_LIB.S9S_MB_2U(SCH_1):P5E_CPU0_PE2_TX_C_DN<2>
  C864     1      1  Q_CAP_DIFFBUS  I234
  J55    A60  SIGNAL_A60  SCONN140_G64V3431BHR  I150

P5E_CPU0_PE2_TX_C_DN<3>   @S9S_MB_2U_LIB.S9S_MB_2U(SCH_1):P5E_CPU0_PE2_TX_C_DN<3>
  C862     1      1  Q_CAP_DIFFBUS  I237
  J55    A57  SIGNAL_A57  SCONN140_G64V3431BHR  I150

P5E_CPU0_PE2_TX_C_DN<4>   @S9S_MB_2U_LIB.S9S_MB_2U(SCH_1):P5E_CPU0_PE2_TX_C_DN<4>
  C860     1      1  Q_CAP_DIFFBUS  I235
  J55    A54  SIGNAL_A54  SCONN140_G64V3431BHR  I150

P5E_CPU0_PE2_TX_C_DN<5>   @S9S_MB_2U_LIB.S9S_MB_2U(SCH_1):P5E_CPU0_PE2_TX_C_DN<5>
  C858     1      1  Q_CAP_DIFFBUS  I243
  J55    A51  SIGNAL_A51  SCONN140_G64V3431BHR  I150

P5E_CPU0_PE2_TX_C_DN<6>   @S9S_MB_2U_LIB.S9S_MB_2U(SCH_1):P5E_CPU0_PE2_TX_C_DN<6>
  C856     1      1  Q_CAP_DIFFBUS  I245
  J55    A48  SIGNAL_A48  SCONN140_G64V3431BHR  I150

P5E_CPU0_PE2_TX_C_DN<7>   @S9S_MB_2U_LIB.S9S_MB_2U(SCH_1):P5E_CPU0_PE2_TX_C_DN<7>
  C854     1      1  Q_CAP_DIFFBUS  I248
  J55    A45  SIGNAL_A45  SCONN140_G64V3431BHR  I150

P5E_CPU0_PE2_TX_C_DN<8>   @S9S_MB_2U_LIB.S9S_MB_2U(SCH_1):P5E_CPU0_PE2_TX_C_DN<8>
  C852     1      1  Q_CAP_DIFFBUS  I269
  J55    A40  SIGNAL_A40  SCONN140_G64V3431BHR  I150

P5E_CPU0_PE2_TX_C_DN<9>   @S9S_MB_2U_LIB.S9S_MB_2U(SCH_1):P5E_CPU0_PE2_TX_C_DN<9>
  C850     1      1  Q_CAP_DIFFBUS  I272
  J55    A37  SIGNAL_A37  SCONN140_G64V3431BHR  I150

P5E_CPU0_PE2_TX_C_DN<10>   @S9S_MB_2U_LIB.S9S_MB_2U(SCH_1):P5E_CPU0_PE2_TX_C_DN<10>
  C848     1      1  Q_CAP_DIFFBUS  I273
  J55    A34  SIGNAL_A34  SCONN140_G64V3431BHR  I150

P5E_CPU0_PE2_TX_C_DN<11>   @S9S_MB_2U_LIB.S9S_MB_2U(SCH_1):P5E_CPU0_PE2_TX_C_DN<11>
  C846     1      1  Q_CAP_DIFFBUS  I274
  J55    A31  SIGNAL_A31  SCONN140_G64V3431BHR  I150

P5E_CPU0_PE2_TX_C_DN<12>   @S9S_MB_2U_LIB.S9S_MB_2U(SCH_1):P5E_CPU0_PE2_TX_C_DN<12>
  C844     1      1  Q_CAP_DIFFBUS  I276
  J55    A27  SIGNAL_A27  SCONN140_G64V3431BHR  I150

P5E_CPU0_PE2_TX_C_DN<13>   @S9S_MB_2U_LIB.S9S_MB_2U(SCH_1):P5E_CPU0_PE2_TX_C_DN<13>
  C842     1      1  Q_CAP_DIFFBUS  I285
  J55    A24  SIGNAL_A24  SCONN140_G64V3431BHR  I150

P5E_CPU0_PE2_TX_C_DN<14>   @S9S_MB_2U_LIB.S9S_MB_2U(SCH_1):P5E_CPU0_PE2_TX_C_DN<14>
  C840     1      1  Q_CAP_DIFFBUS  I288
  J55    A21  SIGNAL_A21  SCONN140_G64V3431BHR  I150

P5E_CPU0_PE2_TX_C_DN<15>   @S9S_MB_2U_LIB.S9S_MB_2U(SCH_1):P5E_CPU0_PE2_TX_C_DN<15>
  C838     1      1  Q_CAP_DIFFBUS  I287
  J55    A18  SIGNAL_A18  SCONN140_G64V3431BHR  I150

P5E_CPU0_PE2_TX_C_DP<0>   @S9S_MB_2U_LIB.S9S_MB_2U(SCH_1):P5E_CPU0_PE2_TX_C_DP<0>
  C869     1      1  Q_CAP_DIFFBUS  I228
  J55    A65  SIGNAL_A65  SCONN140_G64V3431BHR  I150

P5E_CPU0_PE2_TX_C_DP<1>   @S9S_MB_2U_LIB.S9S_MB_2U(SCH_1):P5E_CPU0_PE2_TX_C_DP<1>
  C867     1      1  Q_CAP_DIFFBUS  I231
  J55    A62  SIGNAL_A62  SCONN140_G64V3431BHR  I150

P5E_CPU0_PE2_TX_C_DP<2>   @S9S_MB_2U_LIB.S9S_MB_2U(SCH_1):P5E_CPU0_PE2_TX_C_DP<2>
  C865     1      1  Q_CAP_DIFFBUS  I232
  J55    A59  SIGNAL_A59  SCONN140_G64V3431BHR  I150

P5E_CPU0_PE2_TX_C_DP<3>   @S9S_MB_2U_LIB.S9S_MB_2U(SCH_1):P5E_CPU0_PE2_TX_C_DP<3>
  C863     1      1  Q_CAP_DIFFBUS  I233
  J55    A56  SIGNAL_A56  SCONN140_G64V3431BHR  I150

P5E_CPU0_PE2_TX_C_DP<4>   @S9S_MB_2U_LIB.S9S_MB_2U(SCH_1):P5E_CPU0_PE2_TX_C_DP<4>
  C861     1      1  Q_CAP_DIFFBUS  I236
  J55    A53  SIGNAL_A53  SCONN140_G64V3431BHR  I150

P5E_CPU0_PE2_TX_C_DP<5>   @S9S_MB_2U_LIB.S9S_MB_2U(SCH_1):P5E_CPU0_PE2_TX_C_DP<5>
  C859     1      1  Q_CAP_DIFFBUS  I244
  J55    A50  SIGNAL_A50  SCONN140_G64V3431BHR  I150

P5E_CPU0_PE2_TX_C_DP<6>   @S9S_MB_2U_LIB.S9S_MB_2U(SCH_1):P5E_CPU0_PE2_TX_C_DP<6>
  C857     1      1  Q_CAP_DIFFBUS  I246
  J55    A47  SIGNAL_A47  SCONN140_G64V3431BHR  I150

P5E_CPU0_PE2_TX_C_DP<7>   @S9S_MB_2U_LIB.S9S_MB_2U(SCH_1):P5E_CPU0_PE2_TX_C_DP<7>
  C855     1      1  Q_CAP_DIFFBUS  I247
  J55    A44  SIGNAL_A44  SCONN140_G64V3431BHR  I150

P5E_CPU0_PE2_TX_C_DP<8>   @S9S_MB_2U_LIB.S9S_MB_2U(SCH_1):P5E_CPU0_PE2_TX_C_DP<8>
  C853     1      1  Q_CAP_DIFFBUS  I268
  J55    A39  SIGNAL_A39  SCONN140_G64V3431BHR  I150

P5E_CPU0_PE2_TX_C_DP<9>   @S9S_MB_2U_LIB.S9S_MB_2U(SCH_1):P5E_CPU0_PE2_TX_C_DP<9>
  C851     1      1  Q_CAP_DIFFBUS  I270
  J55    A36  SIGNAL_A36  SCONN140_G64V3431BHR  I150

P5E_CPU0_PE2_TX_C_DP<10>   @S9S_MB_2U_LIB.S9S_MB_2U(SCH_1):P5E_CPU0_PE2_TX_C_DP<10>
  C849     1      1  Q_CAP_DIFFBUS  I271
  J55    A33  SIGNAL_A33  SCONN140_G64V3431BHR  I150

P5E_CPU0_PE2_TX_C_DP<11>   @S9S_MB_2U_LIB.S9S_MB_2U(SCH_1):P5E_CPU0_PE2_TX_C_DP<11>
  C847     1      1  Q_CAP_DIFFBUS  I275
  J55    A30  SIGNAL_A30  SCONN140_G64V3431BHR  I150

P5E_CPU0_PE2_TX_C_DP<12>   @S9S_MB_2U_LIB.S9S_MB_2U(SCH_1):P5E_CPU0_PE2_TX_C_DP<12>
  C845     1      1  Q_CAP_DIFFBUS  I277
  J55    A26  SIGNAL_A26  SCONN140_G64V3431BHR  I150

P5E_CPU0_PE2_TX_C_DP<13>   @S9S_MB_2U_LIB.S9S_MB_2U(SCH_1):P5E_CPU0_PE2_TX_C_DP<13>
  C843     1      1  Q_CAP_DIFFBUS  I283
  J55    A23  SIGNAL_A23  SCONN140_G64V3431BHR  I150

P5E_CPU0_PE2_TX_C_DP<14>   @S9S_MB_2U_LIB.S9S_MB_2U(SCH_1):P5E_CPU0_PE2_TX_C_DP<14>
  C841     1      1  Q_CAP_DIFFBUS  I284
  J55    A20  SIGNAL_A20  SCONN140_G64V3431BHR  I150

P5E_CPU0_PE2_TX_C_DP<15>   @S9S_MB_2U_LIB.S9S_MB_2U(SCH_1):P5E_CPU0_PE2_TX_C_DP<15>
  C839     1      1  Q_CAP_DIFFBUS  I286
  J55    A17  SIGNAL_A17  SCONN140_G64V3431BHR  I150

P5E_CPU0_PE2_TX_DN<0>   @S9S_MB_2U_LIB.S9S_MB_2U(SCH_1):P5E_CPU0_PE2_TX_DN<0>
  C868     2      2  Q_CAP_DIFFBUS  I229
  U2     CT14  PE2_TX_DP0  SOCKET4677_AZIFS054P001C01  I139

P5E_CPU0_PE2_TX_DN<1>   @S9S_MB_2U_LIB.S9S_MB_2U(SCH_1):P5E_CPU0_PE2_TX_DN<1>
  C866     2      2  Q_CAP_DIFFBUS  I230
  U2     CW15  PE2_TX_DP1  SOCKET4677_AZIFS054P001C01  I139

P5E_CPU0_PE2_TX_DN<2>   @S9S_MB_2U_LIB.S9S_MB_2U(SCH_1):P5E_CPU0_PE2_TX_DN<2>
  C864     2      2  Q_CAP_DIFFBUS  I234
  U2     CY14  PE2_TX_DP2  SOCKET4677_AZIFS054P001C01  I139

P5E_CPU0_PE2_TX_DN<3>   @S9S_MB_2U_LIB.S9S_MB_2U(SCH_1):P5E_CPU0_PE2_TX_DN<3>
  C862     2      2  Q_CAP_DIFFBUS  I237
  U2     DC15  PE2_TX_DP3  SOCKET4677_AZIFS054P001C01  I139

P5E_CPU0_PE2_TX_DN<4>   @S9S_MB_2U_LIB.S9S_MB_2U(SCH_1):P5E_CPU0_PE2_TX_DN<4>
  C860     2      2  Q_CAP_DIFFBUS  I235
  U2     DD14  PE2_TX_DP4  SOCKET4677_AZIFS054P001C01  I139

P5E_CPU0_PE2_TX_DN<5>   @S9S_MB_2U_LIB.S9S_MB_2U(SCH_1):P5E_CPU0_PE2_TX_DN<5>
  C858     2      2  Q_CAP_DIFFBUS  I243
  U2     DG15  PE2_TX_DP5  SOCKET4677_AZIFS054P001C01  I139

P5E_CPU0_PE2_TX_DN<6>   @S9S_MB_2U_LIB.S9S_MB_2U(SCH_1):P5E_CPU0_PE2_TX_DN<6>
  C856     2      2  Q_CAP_DIFFBUS  I245
  U2     DH14  PE2_TX_DP6  SOCKET4677_AZIFS054P001C01  I139

P5E_CPU0_PE2_TX_DN<7>   @S9S_MB_2U_LIB.S9S_MB_2U(SCH_1):P5E_CPU0_PE2_TX_DN<7>
  C854     2      2  Q_CAP_DIFFBUS  I248
  U2     DL15  PE2_TX_DP7  SOCKET4677_AZIFS054P001C01  I139

P5E_CPU0_PE2_TX_DN<8>   @S9S_MB_2U_LIB.S9S_MB_2U(SCH_1):P5E_CPU0_PE2_TX_DN<8>
  C852     2      2  Q_CAP_DIFFBUS  I269
  U2     DM14  PE2_TX_DP8  SOCKET4677_AZIFS054P001C01  I139

P5E_CPU0_PE2_TX_DN<9>   @S9S_MB_2U_LIB.S9S_MB_2U(SCH_1):P5E_CPU0_PE2_TX_DN<9>
  C850     2      2  Q_CAP_DIFFBUS  I272
  U2     DR15  PE2_TX_DP9  SOCKET4677_AZIFS054P001C01  I139

P5E_CPU0_PE2_TX_DN<10>   @S9S_MB_2U_LIB.S9S_MB_2U(SCH_1):P5E_CPU0_PE2_TX_DN<10>
  C848     2      2  Q_CAP_DIFFBUS  I273
  U2     DT14  PE2_TX_DP10  SOCKET4677_AZIFS054P001C01  I139

P5E_CPU0_PE2_TX_DN<11>   @S9S_MB_2U_LIB.S9S_MB_2U(SCH_1):P5E_CPU0_PE2_TX_DN<11>
  C846     2      2  Q_CAP_DIFFBUS  I274
  U2     DW15  PE2_TX_DP11  SOCKET4677_AZIFS054P001C01  I139

P5E_CPU0_PE2_TX_DN<12>   @S9S_MB_2U_LIB.S9S_MB_2U(SCH_1):P5E_CPU0_PE2_TX_DN<12>
  C844     2      2  Q_CAP_DIFFBUS  I276
  U2     DY14  PE2_TX_DP12  SOCKET4677_AZIFS054P001C01  I139

P5E_CPU0_PE2_TX_DN<13>   @S9S_MB_2U_LIB.S9S_MB_2U(SCH_1):P5E_CPU0_PE2_TX_DN<13>
  C842     2      2  Q_CAP_DIFFBUS  I285
  U2     EC15  PE2_TX_DP13  SOCKET4677_AZIFS054P001C01  I139

P5E_CPU0_PE2_TX_DN<14>   @S9S_MB_2U_LIB.S9S_MB_2U(SCH_1):P5E_CPU0_PE2_TX_DN<14>
  C840     2      2  Q_CAP_DIFFBUS  I288
  U2     ED14  PE2_TX_DP14  SOCKET4677_AZIFS054P001C01  I139

P5E_CPU0_PE2_TX_DN<15>   @S9S_MB_2U_LIB.S9S_MB_2U(SCH_1):P5E_CPU0_PE2_TX_DN<15>
  C838     2      2  Q_CAP_DIFFBUS  I287
  U2     EG15  PE2_TX_DP15  SOCKET4677_AZIFS054P001C01  I139

P5E_CPU0_PE2_TX_DP<0>   @S9S_MB_2U_LIB.S9S_MB_2U(SCH_1):P5E_CPU0_PE2_TX_DP<0>
  C869     2      2  Q_CAP_DIFFBUS  I228
  U2     CU13  PE2_TX_DN0  SOCKET4677_AZIFS054P001C01  I139

P5E_CPU0_PE2_TX_DP<1>   @S9S_MB_2U_LIB.S9S_MB_2U(SCH_1):P5E_CPU0_PE2_TX_DP<1>
  C867     2      2  Q_CAP_DIFFBUS  I231
  U2     CV14  PE2_TX_DN1  SOCKET4677_AZIFS054P001C01  I139

P5E_CPU0_PE2_TX_DP<2>   @S9S_MB_2U_LIB.S9S_MB_2U(SCH_1):P5E_CPU0_PE2_TX_DP<2>
  C865     2      2  Q_CAP_DIFFBUS  I232
  U2     DA13  PE2_TX_DN2  SOCKET4677_AZIFS054P001C01  I139

P5E_CPU0_PE2_TX_DP<3>   @S9S_MB_2U_LIB.S9S_MB_2U(SCH_1):P5E_CPU0_PE2_TX_DP<3>
  C863     2      2  Q_CAP_DIFFBUS  I233
  U2     DB14  PE2_TX_DN3  SOCKET4677_AZIFS054P001C01  I139

P5E_CPU0_PE2_TX_DP<4>   @S9S_MB_2U_LIB.S9S_MB_2U(SCH_1):P5E_CPU0_PE2_TX_DP<4>
  C861     2      2  Q_CAP_DIFFBUS  I236
  U2     DE13  PE2_TX_DN4  SOCKET4677_AZIFS054P001C01  I139

P5E_CPU0_PE2_TX_DP<5>   @S9S_MB_2U_LIB.S9S_MB_2U(SCH_1):P5E_CPU0_PE2_TX_DP<5>
  C859     2      2  Q_CAP_DIFFBUS  I244
  U2     DF14  PE2_TX_DN5  SOCKET4677_AZIFS054P001C01  I139

P5E_CPU0_PE2_TX_DP<6>   @S9S_MB_2U_LIB.S9S_MB_2U(SCH_1):P5E_CPU0_PE2_TX_DP<6>
  C857     2      2  Q_CAP_DIFFBUS  I246
  U2     DJ13  PE2_TX_DN6  SOCKET4677_AZIFS054P001C01  I139

P5E_CPU0_PE2_TX_DP<7>   @S9S_MB_2U_LIB.S9S_MB_2U(SCH_1):P5E_CPU0_PE2_TX_DP<7>
  C855     2      2  Q_CAP_DIFFBUS  I247
  U2     DK14  PE2_TX_DN7  SOCKET4677_AZIFS054P001C01  I139

P5E_CPU0_PE2_TX_DP<8>   @S9S_MB_2U_LIB.S9S_MB_2U(SCH_1):P5E_CPU0_PE2_TX_DP<8>
  C853     2      2  Q_CAP_DIFFBUS  I268
  U2     DN13  PE2_TX_DN8  SOCKET4677_AZIFS054P001C01  I139

P5E_CPU0_PE2_TX_DP<9>   @S9S_MB_2U_LIB.S9S_MB_2U(SCH_1):P5E_CPU0_PE2_TX_DP<9>
  C851     2      2  Q_CAP_DIFFBUS  I270
  U2     DP14  PE2_TX_DN9  SOCKET4677_AZIFS054P001C01  I139

P5E_CPU0_PE2_TX_DP<10>   @S9S_MB_2U_LIB.S9S_MB_2U(SCH_1):P5E_CPU0_PE2_TX_DP<10>
  C849     2      2  Q_CAP_DIFFBUS  I271
  U2     DU13  PE2_TX_DN10  SOCKET4677_AZIFS054P001C01  I139

P5E_CPU0_PE2_TX_DP<11>   @S9S_MB_2U_LIB.S9S_MB_2U(SCH_1):P5E_CPU0_PE2_TX_DP<11>
  C847     2      2  Q_CAP_DIFFBUS  I275
  U2     DV14  PE2_TX_DN11  SOCKET4677_AZIFS054P001C01  I139

P5E_CPU0_PE2_TX_DP<12>   @S9S_MB_2U_LIB.S9S_MB_2U(SCH_1):P5E_CPU0_PE2_TX_DP<12>
  C845     2      2  Q_CAP_DIFFBUS  I277
  U2     EA13  PE2_TX_DN12  SOCKET4677_AZIFS054P001C01  I139

P5E_CPU0_PE2_TX_DP<13>   @S9S_MB_2U_LIB.S9S_MB_2U(SCH_1):P5E_CPU0_PE2_TX_DP<13>
  C843     2      2  Q_CAP_DIFFBUS  I283
  U2     EB14  PE2_TX_DN13  SOCKET4677_AZIFS054P001C01  I139

P5E_CPU0_PE2_TX_DP<14>   @S9S_MB_2U_LIB.S9S_MB_2U(SCH_1):P5E_CPU0_PE2_TX_DP<14>
  C841     2      2  Q_CAP_DIFFBUS  I284
  U2     EE13  PE2_TX_DN14  SOCKET4677_AZIFS054P001C01  I139

P5E_CPU0_PE2_TX_DP<15>   @S9S_MB_2U_LIB.S9S_MB_2U(SCH_1):P5E_CPU0_PE2_TX_DP<15>
  C839     2      2  Q_CAP_DIFFBUS  I286
  U2     EF14  PE2_TX_DN15  SOCKET4677_AZIFS054P001C01  I139

P5E_CPU0_PE3_RX_DN<0>   @S9S_MB_2U_LIB.S9S_MB_2U(SCH_1):P5E_CPU0_PE3_RX_DN<0>
  J62    A17  PETN0  SCONN84_123318136  I33
  U2     EH89  PE3_RX_DN0  SOCKET4677_AZIFS054P001C01  I140

P5E_CPU0_PE3_RX_DN<1>   @S9S_MB_2U_LIB.S9S_MB_2U(SCH_1):P5E_CPU0_PE3_RX_DN<1>
  J62    A20  PETN1  SCONN84_123318136  I33
  U2     ED91  PE3_RX_DN1  SOCKET4677_AZIFS054P001C01  I140

P5E_CPU0_PE3_RX_DN<2>   @S9S_MB_2U_LIB.S9S_MB_2U(SCH_1):P5E_CPU0_PE3_RX_DN<2>
  J62    A23  PETN2  SCONN84_123318136  I33
  U2     EC90  PE3_RX_DN2  SOCKET4677_AZIFS054P001C01  I140

P5E_CPU0_PE3_RX_DN<3>   @S9S_MB_2U_LIB.S9S_MB_2U(SCH_1):P5E_CPU0_PE3_RX_DN<3>
  J62    A26  PETN3  SCONN84_123318136  I33
  U2     DY91  PE3_RX_DN3  SOCKET4677_AZIFS054P001C01  I140

P5E_CPU0_PE3_RX_DN<4>   @S9S_MB_2U_LIB.S9S_MB_2U(SCH_1):P5E_CPU0_PE3_RX_DN<4>
  J62    A30  PETN4  SCONN84_123318136  I33
  U2     DV89  PE3_RX_DN4  SOCKET4677_AZIFS054P001C01  I140

P5E_CPU0_PE3_RX_DN<5>   @S9S_MB_2U_LIB.S9S_MB_2U(SCH_1):P5E_CPU0_PE3_RX_DN<5>
  J62    A33  PETN5  SCONN84_123318136  I33
  U2     DU90  PE3_RX_DN5  SOCKET4677_AZIFS054P001C01  I140

P5E_CPU0_PE3_RX_DN<6>   @S9S_MB_2U_LIB.S9S_MB_2U(SCH_1):P5E_CPU0_PE3_RX_DN<6>
  J62    A36  PETN6  SCONN84_123318136  I33
  U2     DP89  PE3_RX_DN6  SOCKET4677_AZIFS054P001C01  I140

P5E_CPU0_PE3_RX_DN<7>   @S9S_MB_2U_LIB.S9S_MB_2U(SCH_1):P5E_CPU0_PE3_RX_DN<7>
  J62    A39  PETN7  SCONN84_123318136  I33
  U2     DN90  PE3_RX_DN7  SOCKET4677_AZIFS054P001C01  I140

P5E_CPU0_PE3_RX_DN<8>   @S9S_MB_2U_LIB.S9S_MB_2U(SCH_1):P5E_CPU0_PE3_RX_DN<8>
  J87    A17  PETN0  SCONN84_123318136  I43
  U2     DL90  PE3_RX_DN8  SOCKET4677_AZIFS054P001C01  I140

P5E_CPU0_PE3_RX_DN<9>   @S9S_MB_2U_LIB.S9S_MB_2U(SCH_1):P5E_CPU0_PE3_RX_DN<9>
  J87    A20  PETN1  SCONN84_123318136  I43
  U2     DH91  PE3_RX_DN9  SOCKET4677_AZIFS054P001C01  I140

P5E_CPU0_PE3_RX_DN<10>   @S9S_MB_2U_LIB.S9S_MB_2U(SCH_1):P5E_CPU0_PE3_RX_DN<10>
  J87    A23  PETN2  SCONN84_123318136  I43
  U2     DG90  PE3_RX_DN10  SOCKET4677_AZIFS054P001C01  I140

P5E_CPU0_PE3_RX_DN<11>   @S9S_MB_2U_LIB.S9S_MB_2U(SCH_1):P5E_CPU0_PE3_RX_DN<11>
  J87    A26  PETN3  SCONN84_123318136  I43
  U2     DD91  PE3_RX_DN11  SOCKET4677_AZIFS054P001C01  I140

P5E_CPU0_PE3_RX_DN<12>   @S9S_MB_2U_LIB.S9S_MB_2U(SCH_1):P5E_CPU0_PE3_RX_DN<12>
  J87    A30  PETN4  SCONN84_123318136  I43
  U2     DB89  PE3_RX_DN12  SOCKET4677_AZIFS054P001C01  I140

P5E_CPU0_PE3_RX_DN<13>   @S9S_MB_2U_LIB.S9S_MB_2U(SCH_1):P5E_CPU0_PE3_RX_DN<13>
  J87    A33  PETN5  SCONN84_123318136  I43
  U2     DA90  PE3_RX_DN13  SOCKET4677_AZIFS054P001C01  I140

P5E_CPU0_PE3_RX_DN<14>   @S9S_MB_2U_LIB.S9S_MB_2U(SCH_1):P5E_CPU0_PE3_RX_DN<14>
  J87    A36  PETN6  SCONN84_123318136  I43
  U2     CV89  PE3_RX_DN14  SOCKET4677_AZIFS054P001C01  I140

P5E_CPU0_PE3_RX_DN<15>   @S9S_MB_2U_LIB.S9S_MB_2U(SCH_1):P5E_CPU0_PE3_RX_DN<15>
  J87    A39  PETN7  SCONN84_123318136  I43
  U2     CU90  PE3_RX_DN15  SOCKET4677_AZIFS054P001C01  I140

P5E_CPU0_PE3_RX_DP<0>   @S9S_MB_2U_LIB.S9S_MB_2U(SCH_1):P5E_CPU0_PE3_RX_DP<0>
  J62    A18  PETP0  SCONN84_123318136  I33
  U2     EJ90  PE3_RX_DP0  SOCKET4677_AZIFS054P001C01  I140

P5E_CPU0_PE3_RX_DP<1>   @S9S_MB_2U_LIB.S9S_MB_2U(SCH_1):P5E_CPU0_PE3_RX_DP<1>
  J62    A21  PETP1  SCONN84_123318136  I33
  U2     EE90  PE3_RX_DP1  SOCKET4677_AZIFS054P001C01  I140

P5E_CPU0_PE3_RX_DP<2>   @S9S_MB_2U_LIB.S9S_MB_2U(SCH_1):P5E_CPU0_PE3_RX_DP<2>
  J62    A24  PETP2  SCONN84_123318136  I33
  U2     EB89  PE3_RX_DP2  SOCKET4677_AZIFS054P001C01  I140

P5E_CPU0_PE3_RX_DP<3>   @S9S_MB_2U_LIB.S9S_MB_2U(SCH_1):P5E_CPU0_PE3_RX_DP<3>
  J62    A27  PETP3  SCONN84_123318136  I33
  U2     EA90  PE3_RX_DP3  SOCKET4677_AZIFS054P001C01  I140

P5E_CPU0_PE3_RX_DP<4>   @S9S_MB_2U_LIB.S9S_MB_2U(SCH_1):P5E_CPU0_PE3_RX_DP<4>
  J62    A31  PETP4  SCONN84_123318136  I33
  U2     DW90  PE3_RX_DP4  SOCKET4677_AZIFS054P001C01  I140

P5E_CPU0_PE3_RX_DP<5>   @S9S_MB_2U_LIB.S9S_MB_2U(SCH_1):P5E_CPU0_PE3_RX_DP<5>
  J62    A34  PETP5  SCONN84_123318136  I33
  U2     DT91  PE3_RX_DP5  SOCKET4677_AZIFS054P001C01  I140

P5E_CPU0_PE3_RX_DP<6>   @S9S_MB_2U_LIB.S9S_MB_2U(SCH_1):P5E_CPU0_PE3_RX_DP<6>
  J62    A37  PETP6  SCONN84_123318136  I33
  U2     DR90  PE3_RX_DP6  SOCKET4677_AZIFS054P001C01  I140

P5E_CPU0_PE3_RX_DP<7>   @S9S_MB_2U_LIB.S9S_MB_2U(SCH_1):P5E_CPU0_PE3_RX_DP<7>
  J62    A40  PETP7  SCONN84_123318136  I33
  U2     DM91  PE3_RX_DP7  SOCKET4677_AZIFS054P001C01  I140

P5E_CPU0_PE3_RX_DP<8>   @S9S_MB_2U_LIB.S9S_MB_2U(SCH_1):P5E_CPU0_PE3_RX_DP<8>
  J87    A18  PETP0  SCONN84_123318136  I43
  U2     DK89  PE3_RX_DP8  SOCKET4677_AZIFS054P001C01  I140

P5E_CPU0_PE3_RX_DP<9>   @S9S_MB_2U_LIB.S9S_MB_2U(SCH_1):P5E_CPU0_PE3_RX_DP<9>
  J87    A21  PETP1  SCONN84_123318136  I43
  U2     DJ90  PE3_RX_DP9  SOCKET4677_AZIFS054P001C01  I140

P5E_CPU0_PE3_RX_DP<10>   @S9S_MB_2U_LIB.S9S_MB_2U(SCH_1):P5E_CPU0_PE3_RX_DP<10>
  J87    A24  PETP2  SCONN84_123318136  I43
  U2     DF89  PE3_RX_DP10  SOCKET4677_AZIFS054P001C01  I140

P5E_CPU0_PE3_RX_DP<11>   @S9S_MB_2U_LIB.S9S_MB_2U(SCH_1):P5E_CPU0_PE3_RX_DP<11>
  J87    A27  PETP3  SCONN84_123318136  I43
  U2     DE90  PE3_RX_DP11  SOCKET4677_AZIFS054P001C01  I140

P5E_CPU0_PE3_RX_DP<12>   @S9S_MB_2U_LIB.S9S_MB_2U(SCH_1):P5E_CPU0_PE3_RX_DP<12>
  J87    A31  PETP4  SCONN84_123318136  I43
  U2     DC90  PE3_RX_DP12  SOCKET4677_AZIFS054P001C01  I140

P5E_CPU0_PE3_RX_DP<13>   @S9S_MB_2U_LIB.S9S_MB_2U(SCH_1):P5E_CPU0_PE3_RX_DP<13>
  J87    A34  PETP5  SCONN84_123318136  I43
  U2     CY91  PE3_RX_DP13  SOCKET4677_AZIFS054P001C01  I140

P5E_CPU0_PE3_RX_DP<14>   @S9S_MB_2U_LIB.S9S_MB_2U(SCH_1):P5E_CPU0_PE3_RX_DP<14>
  J87    A37  PETP6  SCONN84_123318136  I43
  U2     CW90  PE3_RX_DP14  SOCKET4677_AZIFS054P001C01  I140

P5E_CPU0_PE3_RX_DP<15>   @S9S_MB_2U_LIB.S9S_MB_2U(SCH_1):P5E_CPU0_PE3_RX_DP<15>
  J87    A40  PETP7  SCONN84_123318136  I43
  U2     CT91  PE3_RX_DP15  SOCKET4677_AZIFS054P001C01  I140

P5E_CPU0_PE3_TX_C_DN<0>   @S9S_MB_2U_LIB.S9S_MB_2U(SCH_1):P5E_CPU0_PE3_TX_C_DN<0>
  C900     1      1  Q_CAP_DIFFBUS  I121
  J62    B17  PERN0  SCONN84_123318136  I33

P5E_CPU0_PE3_TX_C_DN<1>   @S9S_MB_2U_LIB.S9S_MB_2U(SCH_1):P5E_CPU0_PE3_TX_C_DN<1>
  C898     1      1  Q_CAP_DIFFBUS  I123
  J62    B20  PERN1  SCONN84_123318136  I33

P5E_CPU0_PE3_TX_C_DN<2>   @S9S_MB_2U_LIB.S9S_MB_2U(SCH_1):P5E_CPU0_PE3_TX_C_DN<2>
  C896     1      1  Q_CAP_DIFFBUS  I125
  J62    B23  PERN2  SCONN84_123318136  I33

P5E_CPU0_PE3_TX_C_DN<3>   @S9S_MB_2U_LIB.S9S_MB_2U(SCH_1):P5E_CPU0_PE3_TX_C_DN<3>
  C894     1      1  Q_CAP_DIFFBUS  I127
  J62    B26  PERN3  SCONN84_123318136  I33

P5E_CPU0_PE3_TX_C_DN<4>   @S9S_MB_2U_LIB.S9S_MB_2U(SCH_1):P5E_CPU0_PE3_TX_C_DN<4>
  C892     1      1  Q_CAP_DIFFBUS  I129
  J62    B30  PERN4  SCONN84_123318136  I33

P5E_CPU0_PE3_TX_C_DN<5>   @S9S_MB_2U_LIB.S9S_MB_2U(SCH_1):P5E_CPU0_PE3_TX_C_DN<5>
  C890     1      1  Q_CAP_DIFFBUS  I135
  J62    B33  PERN5  SCONN84_123318136  I33

P5E_CPU0_PE3_TX_C_DN<6>   @S9S_MB_2U_LIB.S9S_MB_2U(SCH_1):P5E_CPU0_PE3_TX_C_DN<6>
  C888     1      1  Q_CAP_DIFFBUS  I137
  J62    B36  PERN6  SCONN84_123318136  I33

P5E_CPU0_PE3_TX_C_DN<7>   @S9S_MB_2U_LIB.S9S_MB_2U(SCH_1):P5E_CPU0_PE3_TX_C_DN<7>
  C886     1      1  Q_CAP_DIFFBUS  I139
  J62    B39  PERN7  SCONN84_123318136  I33

P5E_CPU0_PE3_TX_C_DN<8>   @S9S_MB_2U_LIB.S9S_MB_2U(SCH_1):P5E_CPU0_PE3_TX_C_DN<8>
  C884     1      1  Q_CAP_DIFFBUS  I153
  J87    B17  PERN0  SCONN84_123318136  I43

P5E_CPU0_PE3_TX_C_DN<9>   @S9S_MB_2U_LIB.S9S_MB_2U(SCH_1):P5E_CPU0_PE3_TX_C_DN<9>
  C882     1      1  Q_CAP_DIFFBUS  I155
  J87    B20  PERN1  SCONN84_123318136  I43

P5E_CPU0_PE3_TX_C_DN<10>   @S9S_MB_2U_LIB.S9S_MB_2U(SCH_1):P5E_CPU0_PE3_TX_C_DN<10>
  C880     1      1  Q_CAP_DIFFBUS  I157
  J87    B23  PERN2  SCONN84_123318136  I43

P5E_CPU0_PE3_TX_C_DN<11>   @S9S_MB_2U_LIB.S9S_MB_2U(SCH_1):P5E_CPU0_PE3_TX_C_DN<11>
  C878     1      1  Q_CAP_DIFFBUS  I159
  J87    B26  PERN3  SCONN84_123318136  I43

P5E_CPU0_PE3_TX_C_DN<12>   @S9S_MB_2U_LIB.S9S_MB_2U(SCH_1):P5E_CPU0_PE3_TX_C_DN<12>
  C876     1      1  Q_CAP_DIFFBUS  I161
  J87    B30  PERN4  SCONN84_123318136  I43

P5E_CPU0_PE3_TX_C_DN<13>   @S9S_MB_2U_LIB.S9S_MB_2U(SCH_1):P5E_CPU0_PE3_TX_C_DN<13>
  C874     1      1  Q_CAP_DIFFBUS  I166
  J87    B33  PERN5  SCONN84_123318136  I43

P5E_CPU0_PE3_TX_C_DN<14>   @S9S_MB_2U_LIB.S9S_MB_2U(SCH_1):P5E_CPU0_PE3_TX_C_DN<14>
  C872     1      1  Q_CAP_DIFFBUS  I168
  J87    B36  PERN6  SCONN84_123318136  I43

P5E_CPU0_PE3_TX_C_DN<15>   @S9S_MB_2U_LIB.S9S_MB_2U(SCH_1):P5E_CPU0_PE3_TX_C_DN<15>
  C870     1      1  Q_CAP_DIFFBUS  I170
  J87    B39  PERN7  SCONN84_123318136  I43

P5E_CPU0_PE3_TX_C_DP<0>   @S9S_MB_2U_LIB.S9S_MB_2U(SCH_1):P5E_CPU0_PE3_TX_C_DP<0>
  C901     1      1  Q_CAP_DIFFBUS  I120
  J62    B18  PERP0  SCONN84_123318136  I33

P5E_CPU0_PE3_TX_C_DP<1>   @S9S_MB_2U_LIB.S9S_MB_2U(SCH_1):P5E_CPU0_PE3_TX_C_DP<1>
  C899     1      1  Q_CAP_DIFFBUS  I122
  J62    B21  PERP1  SCONN84_123318136  I33

P5E_CPU0_PE3_TX_C_DP<2>   @S9S_MB_2U_LIB.S9S_MB_2U(SCH_1):P5E_CPU0_PE3_TX_C_DP<2>
  C897     1      1  Q_CAP_DIFFBUS  I124
  J62    B24  PERP2  SCONN84_123318136  I33

P5E_CPU0_PE3_TX_C_DP<3>   @S9S_MB_2U_LIB.S9S_MB_2U(SCH_1):P5E_CPU0_PE3_TX_C_DP<3>
  C895     1      1  Q_CAP_DIFFBUS  I126
  J62    B27  PERP3  SCONN84_123318136  I33

P5E_CPU0_PE3_TX_C_DP<4>   @S9S_MB_2U_LIB.S9S_MB_2U(SCH_1):P5E_CPU0_PE3_TX_C_DP<4>
  C893     1      1  Q_CAP_DIFFBUS  I128
  J62    B31  PERP4  SCONN84_123318136  I33

P5E_CPU0_PE3_TX_C_DP<5>   @S9S_MB_2U_LIB.S9S_MB_2U(SCH_1):P5E_CPU0_PE3_TX_C_DP<5>
  C891     1      1  Q_CAP_DIFFBUS  I134
  J62    B34  PERP5  SCONN84_123318136  I33

P5E_CPU0_PE3_TX_C_DP<6>   @S9S_MB_2U_LIB.S9S_MB_2U(SCH_1):P5E_CPU0_PE3_TX_C_DP<6>
  C889     1      1  Q_CAP_DIFFBUS  I136
  J62    B37  PERP6  SCONN84_123318136  I33

P5E_CPU0_PE3_TX_C_DP<7>   @S9S_MB_2U_LIB.S9S_MB_2U(SCH_1):P5E_CPU0_PE3_TX_C_DP<7>
  C887     1      1  Q_CAP_DIFFBUS  I138
  J62    B40  PERP7  SCONN84_123318136  I33

P5E_CPU0_PE3_TX_C_DP<8>   @S9S_MB_2U_LIB.S9S_MB_2U(SCH_1):P5E_CPU0_PE3_TX_C_DP<8>
  C885     1      1  Q_CAP_DIFFBUS  I152
  J87    B18  PERP0  SCONN84_123318136  I43

P5E_CPU0_PE3_TX_C_DP<9>   @S9S_MB_2U_LIB.S9S_MB_2U(SCH_1):P5E_CPU0_PE3_TX_C_DP<9>
  C883     1      1  Q_CAP_DIFFBUS  I154
  J87    B21  PERP1  SCONN84_123318136  I43

P5E_CPU0_PE3_TX_C_DP<10>   @S9S_MB_2U_LIB.S9S_MB_2U(SCH_1):P5E_CPU0_PE3_TX_C_DP<10>
  C881     1      1  Q_CAP_DIFFBUS  I156
  J87    B24  PERP2  SCONN84_123318136  I43

P5E_CPU0_PE3_TX_C_DP<11>   @S9S_MB_2U_LIB.S9S_MB_2U(SCH_1):P5E_CPU0_PE3_TX_C_DP<11>
  C879     1      1  Q_CAP_DIFFBUS  I158
  J87    B27  PERP3  SCONN84_123318136  I43

P5E_CPU0_PE3_TX_C_DP<12>   @S9S_MB_2U_LIB.S9S_MB_2U(SCH_1):P5E_CPU0_PE3_TX_C_DP<12>
  C877     1      1  Q_CAP_DIFFBUS  I160
  J87    B31  PERP4  SCONN84_123318136  I43

P5E_CPU0_PE3_TX_C_DP<13>   @S9S_MB_2U_LIB.S9S_MB_2U(SCH_1):P5E_CPU0_PE3_TX_C_DP<13>
  C875     1      1  Q_CAP_DIFFBUS  I165
  J87    B34  PERP5  SCONN84_123318136  I43

P5E_CPU0_PE3_TX_C_DP<14>   @S9S_MB_2U_LIB.S9S_MB_2U(SCH_1):P5E_CPU0_PE3_TX_C_DP<14>
  C873     1      1  Q_CAP_DIFFBUS  I167
  J87    B37  PERP6  SCONN84_123318136  I43

P5E_CPU0_PE3_TX_C_DP<15>   @S9S_MB_2U_LIB.S9S_MB_2U(SCH_1):P5E_CPU0_PE3_TX_C_DP<15>
  C871     1      1  Q_CAP_DIFFBUS  I169
  J87    B40  PERP7  SCONN84_123318136  I43

P5E_CPU0_PE3_TX_DN<0>   @S9S_MB_2U_LIB.S9S_MB_2U(SCH_1):P5E_CPU0_PE3_TX_DN<0>
  C900     2      2  Q_CAP_DIFFBUS  I121
  U2     EE86  PE3_TX_DN0  SOCKET4677_AZIFS054P001C01  I140

P5E_CPU0_PE3_TX_DN<1>   @S9S_MB_2U_LIB.S9S_MB_2U(SCH_1):P5E_CPU0_PE3_TX_DN<1>
  C898     2      2  Q_CAP_DIFFBUS  I123
  U2     EB85  PE3_TX_DN1  SOCKET4677_AZIFS054P001C01  I140

P5E_CPU0_PE3_TX_DN<2>   @S9S_MB_2U_LIB.S9S_MB_2U(SCH_1):P5E_CPU0_PE3_TX_DN<2>
  C896     2      2  Q_CAP_DIFFBUS  I125
  U2     DY87  PE3_TX_DN2  SOCKET4677_AZIFS054P001C01  I140

P5E_CPU0_PE3_TX_DN<3>   @S9S_MB_2U_LIB.S9S_MB_2U(SCH_1):P5E_CPU0_PE3_TX_DN<3>
  C894     2      2  Q_CAP_DIFFBUS  I127
  U2     DV85  PE3_TX_DN3  SOCKET4677_AZIFS054P001C01  I140

P5E_CPU0_PE3_TX_DN<4>   @S9S_MB_2U_LIB.S9S_MB_2U(SCH_1):P5E_CPU0_PE3_TX_DN<4>
  C892     2      2  Q_CAP_DIFFBUS  I129
  U2     DT87  PE3_TX_DN4  SOCKET4677_AZIFS054P001C01  I140

P5E_CPU0_PE3_TX_DN<5>   @S9S_MB_2U_LIB.S9S_MB_2U(SCH_1):P5E_CPU0_PE3_TX_DN<5>
  C890     2      2  Q_CAP_DIFFBUS  I135
  U2     DP85  PE3_TX_DN5  SOCKET4677_AZIFS054P001C01  I140

P5E_CPU0_PE3_TX_DN<6>   @S9S_MB_2U_LIB.S9S_MB_2U(SCH_1):P5E_CPU0_PE3_TX_DN<6>
  C888     2      2  Q_CAP_DIFFBUS  I137
  U2     DM87  PE3_TX_DN6  SOCKET4677_AZIFS054P001C01  I140

P5E_CPU0_PE3_TX_DN<7>   @S9S_MB_2U_LIB.S9S_MB_2U(SCH_1):P5E_CPU0_PE3_TX_DN<7>
  C886     2      2  Q_CAP_DIFFBUS  I139
  U2     DK85  PE3_TX_DN7  SOCKET4677_AZIFS054P001C01  I140

P5E_CPU0_PE3_TX_DN<8>   @S9S_MB_2U_LIB.S9S_MB_2U(SCH_1):P5E_CPU0_PE3_TX_DN<8>
  C884     2      2  Q_CAP_DIFFBUS  I153
  U2     DH87  PE3_TX_DN8  SOCKET4677_AZIFS054P001C01  I140

P5E_CPU0_PE3_TX_DN<9>   @S9S_MB_2U_LIB.S9S_MB_2U(SCH_1):P5E_CPU0_PE3_TX_DN<9>
  C882     2      2  Q_CAP_DIFFBUS  I155
  U2     DF85  PE3_TX_DN9  SOCKET4677_AZIFS054P001C01  I140

P5E_CPU0_PE3_TX_DN<10>   @S9S_MB_2U_LIB.S9S_MB_2U(SCH_1):P5E_CPU0_PE3_TX_DN<10>
  C880     2      2  Q_CAP_DIFFBUS  I157
  U2     DD87  PE3_TX_DN10  SOCKET4677_AZIFS054P001C01  I140

P5E_CPU0_PE3_TX_DN<11>   @S9S_MB_2U_LIB.S9S_MB_2U(SCH_1):P5E_CPU0_PE3_TX_DN<11>
  C878     2      2  Q_CAP_DIFFBUS  I159
  U2     DB85  PE3_TX_DN11  SOCKET4677_AZIFS054P001C01  I140

P5E_CPU0_PE3_TX_DN<12>   @S9S_MB_2U_LIB.S9S_MB_2U(SCH_1):P5E_CPU0_PE3_TX_DN<12>
  C876     2      2  Q_CAP_DIFFBUS  I161
  U2     CY87  PE3_TX_DN12  SOCKET4677_AZIFS054P001C01  I140

P5E_CPU0_PE3_TX_DN<13>   @S9S_MB_2U_LIB.S9S_MB_2U(SCH_1):P5E_CPU0_PE3_TX_DN<13>
  C874     2      2  Q_CAP_DIFFBUS  I166
  U2     CV85  PE3_TX_DN13  SOCKET4677_AZIFS054P001C01  I140

P5E_CPU0_PE3_TX_DN<14>   @S9S_MB_2U_LIB.S9S_MB_2U(SCH_1):P5E_CPU0_PE3_TX_DN<14>
  C872     2      2  Q_CAP_DIFFBUS  I168
  U2     CT87  PE3_TX_DN14  SOCKET4677_AZIFS054P001C01  I140

P5E_CPU0_PE3_TX_DN<15>   @S9S_MB_2U_LIB.S9S_MB_2U(SCH_1):P5E_CPU0_PE3_TX_DN<15>
  C870     2      2  Q_CAP_DIFFBUS  I170
  U2     CP85  PE3_TX_DN15  SOCKET4677_AZIFS054P001C01  I140

P5E_CPU0_PE3_TX_DP<0>   @S9S_MB_2U_LIB.S9S_MB_2U(SCH_1):P5E_CPU0_PE3_TX_DP<0>
  C901     2      2  Q_CAP_DIFFBUS  I120
  U2     ED87  PE3_TX_DP0  SOCKET4677_AZIFS054P001C01  I140

P5E_CPU0_PE3_TX_DP<1>   @S9S_MB_2U_LIB.S9S_MB_2U(SCH_1):P5E_CPU0_PE3_TX_DP<1>
  C899     2      2  Q_CAP_DIFFBUS  I122
  U2     EC86  PE3_TX_DP1  SOCKET4677_AZIFS054P001C01  I140

P5E_CPU0_PE3_TX_DP<2>   @S9S_MB_2U_LIB.S9S_MB_2U(SCH_1):P5E_CPU0_PE3_TX_DP<2>
  C897     2      2  Q_CAP_DIFFBUS  I124
  U2     EA86  PE3_TX_DP2  SOCKET4677_AZIFS054P001C01  I140

P5E_CPU0_PE3_TX_DP<3>   @S9S_MB_2U_LIB.S9S_MB_2U(SCH_1):P5E_CPU0_PE3_TX_DP<3>
  C895     2      2  Q_CAP_DIFFBUS  I126
  U2     DW86  PE3_TX_DP3  SOCKET4677_AZIFS054P001C01  I140

P5E_CPU0_PE3_TX_DP<4>   @S9S_MB_2U_LIB.S9S_MB_2U(SCH_1):P5E_CPU0_PE3_TX_DP<4>
  C893     2      2  Q_CAP_DIFFBUS  I128
  U2     DU86  PE3_TX_DP4  SOCKET4677_AZIFS054P001C01  I140

P5E_CPU0_PE3_TX_DP<5>   @S9S_MB_2U_LIB.S9S_MB_2U(SCH_1):P5E_CPU0_PE3_TX_DP<5>
  C891     2      2  Q_CAP_DIFFBUS  I134
  U2     DR86  PE3_TX_DP5  SOCKET4677_AZIFS054P001C01  I140

P5E_CPU0_PE3_TX_DP<6>   @S9S_MB_2U_LIB.S9S_MB_2U(SCH_1):P5E_CPU0_PE3_TX_DP<6>
  C889     2      2  Q_CAP_DIFFBUS  I136
  U2     DN86  PE3_TX_DP6  SOCKET4677_AZIFS054P001C01  I140

P5E_CPU0_PE3_TX_DP<7>   @S9S_MB_2U_LIB.S9S_MB_2U(SCH_1):P5E_CPU0_PE3_TX_DP<7>
  C887     2      2  Q_CAP_DIFFBUS  I138
  U2     DL86  PE3_TX_DP7  SOCKET4677_AZIFS054P001C01  I140

P5E_CPU0_PE3_TX_DP<8>   @S9S_MB_2U_LIB.S9S_MB_2U(SCH_1):P5E_CPU0_PE3_TX_DP<8>
  C885     2      2  Q_CAP_DIFFBUS  I152
  U2     DJ86  PE3_TX_DP8  SOCKET4677_AZIFS054P001C01  I140

P5E_CPU0_PE3_TX_DP<9>   @S9S_MB_2U_LIB.S9S_MB_2U(SCH_1):P5E_CPU0_PE3_TX_DP<9>
  C883     2      2  Q_CAP_DIFFBUS  I154
  U2     DG86  PE3_TX_DP9  SOCKET4677_AZIFS054P001C01  I140

P5E_CPU0_PE3_TX_DP<10>   @S9S_MB_2U_LIB.S9S_MB_2U(SCH_1):P5E_CPU0_PE3_TX_DP<10>
  C881     2      2  Q_CAP_DIFFBUS  I156
  U2     DE86  PE3_TX_DP10  SOCKET4677_AZIFS054P001C01  I140

P5E_CPU0_PE3_TX_DP<11>   @S9S_MB_2U_LIB.S9S_MB_2U(SCH_1):P5E_CPU0_PE3_TX_DP<11>
  C879     2      2  Q_CAP_DIFFBUS  I158
  U2     DC86  PE3_TX_DP11  SOCKET4677_AZIFS054P001C01  I140

P5E_CPU0_PE3_TX_DP<12>   @S9S_MB_2U_LIB.S9S_MB_2U(SCH_1):P5E_CPU0_PE3_TX_DP<12>
  C877     2      2  Q_CAP_DIFFBUS  I160
  U2     DA86  PE3_TX_DP12  SOCKET4677_AZIFS054P001C01  I140

P5E_CPU0_PE3_TX_DP<13>   @S9S_MB_2U_LIB.S9S_MB_2U(SCH_1):P5E_CPU0_PE3_TX_DP<13>
  C875     2      2  Q_CAP_DIFFBUS  I165
  U2     CW86  PE3_TX_DP13  SOCKET4677_AZIFS054P001C01  I140

P5E_CPU0_PE3_TX_DP<14>   @S9S_MB_2U_LIB.S9S_MB_2U(SCH_1):P5E_CPU0_PE3_TX_DP<14>
  C873     2      2  Q_CAP_DIFFBUS  I167
  U2     CU86  PE3_TX_DP14  SOCKET4677_AZIFS054P001C01  I140

P5E_CPU0_PE3_TX_DP<15>   @S9S_MB_2U_LIB.S9S_MB_2U(SCH_1):P5E_CPU0_PE3_TX_DP<15>
  C871     2      2  Q_CAP_DIFFBUS  I169
  U2     CR86  PE3_TX_DP15  SOCKET4677_AZIFS054P001C01  I140

P5E_CPU0_PE4_RX_DN<0>   @S9S_MB_2U_LIB.S9S_MB_2U(SCH_1):P5E_CPU0_PE4_RX_DN<0>
  J33    A39  PETN7  SCONN84_123318136  I53
  U2     BB89  PE4_RX_DN15  SOCKET4677_AZIFS054P001C01  I139

P5E_CPU0_PE4_RX_DN<1>   @S9S_MB_2U_LIB.S9S_MB_2U(SCH_1):P5E_CPU0_PE4_RX_DN<1>
  J33    A37  PETP6  SCONN84_123318136  I53
  U2     AY91  PE4_RX_DN14  SOCKET4677_AZIFS054P001C01  I139

P5E_CPU0_PE4_RX_DN<2>   @S9S_MB_2U_LIB.S9S_MB_2U(SCH_1):P5E_CPU0_PE4_RX_DN<2>
  J33    A33  PETN5  SCONN84_123318136  I53
  U2     AV89  PE4_RX_DN13  SOCKET4677_AZIFS054P001C01  I139

P5E_CPU0_PE4_RX_DN<3>   @S9S_MB_2U_LIB.S9S_MB_2U(SCH_1):P5E_CPU0_PE4_RX_DN<3>
  J33    A30  PETN4  SCONN84_123318136  I53
  U2     AT91  PE4_RX_DN12  SOCKET4677_AZIFS054P001C01  I139

P5E_CPU0_PE4_RX_DN<4>   @S9S_MB_2U_LIB.S9S_MB_2U(SCH_1):P5E_CPU0_PE4_RX_DN<4>
  J33    A26  PETN3  SCONN84_123318136  I53
  U2     AP89  PE4_RX_DN11  SOCKET4677_AZIFS054P001C01  I139

P5E_CPU0_PE4_RX_DN<5>   @S9S_MB_2U_LIB.S9S_MB_2U(SCH_1):P5E_CPU0_PE4_RX_DN<5>
  J33    A24  PETP2  SCONN84_123318136  I53
  U2     AM91  PE4_RX_DN10  SOCKET4677_AZIFS054P001C01  I139

P5E_CPU0_PE4_RX_DN<6>   @S9S_MB_2U_LIB.S9S_MB_2U(SCH_1):P5E_CPU0_PE4_RX_DN<6>
  J33    A20  PETN1  SCONN84_123318136  I53
  U2     AK89  PE4_RX_DN9  SOCKET4677_AZIFS054P001C01  I139

P5E_CPU0_PE4_RX_DN<7>   @S9S_MB_2U_LIB.S9S_MB_2U(SCH_1):P5E_CPU0_PE4_RX_DN<7>
  J33    A17  PETN0  SCONN84_123318136  I53
  U2     AH91  PE4_RX_DN8  SOCKET4677_AZIFS054P001C01  I139

P5E_CPU0_PE4_RX_DN<8>   @S9S_MB_2U_LIB.S9S_MB_2U(SCH_1):P5E_CPU0_PE4_RX_DN<8>
  J34    A39  PETN7  SCONN84_123318136  I43
  U2     AF89  PE4_RX_DN7  SOCKET4677_AZIFS054P001C01  I139

P5E_CPU0_PE4_RX_DN<9>   @S9S_MB_2U_LIB.S9S_MB_2U(SCH_1):P5E_CPU0_PE4_RX_DN<9>
  J34    A36  PETN6  SCONN84_123318136  I43
  U2     AD91  PE4_RX_DN6  SOCKET4677_AZIFS054P001C01  I139

P5E_CPU0_PE4_RX_DN<10>   @S9S_MB_2U_LIB.S9S_MB_2U(SCH_1):P5E_CPU0_PE4_RX_DN<10>
  J34    A33  PETN5  SCONN84_123318136  I43
  U2     AB89  PE4_RX_DN5  SOCKET4677_AZIFS054P001C01  I139

P5E_CPU0_PE4_RX_DN<11>   @S9S_MB_2U_LIB.S9S_MB_2U(SCH_1):P5E_CPU0_PE4_RX_DN<11>
  J34    A30  PETN4  SCONN84_123318136  I43
  U2     Y91  PE4_RX_DN4  SOCKET4677_AZIFS054P001C01  I139

P5E_CPU0_PE4_RX_DN<12>   @S9S_MB_2U_LIB.S9S_MB_2U(SCH_1):P5E_CPU0_PE4_RX_DN<12>
  J34    A26  PETN3  SCONN84_123318136  I43
  U2     V89  PE4_RX_DN3  SOCKET4677_AZIFS054P001C01  I139

P5E_CPU0_PE4_RX_DN<13>   @S9S_MB_2U_LIB.S9S_MB_2U(SCH_1):P5E_CPU0_PE4_RX_DN<13>
  J34    A23  PETN2  SCONN84_123318136  I43
  U2     T91  PE4_RX_DN2  SOCKET4677_AZIFS054P001C01  I139

P5E_CPU0_PE4_RX_DN<14>   @S9S_MB_2U_LIB.S9S_MB_2U(SCH_1):P5E_CPU0_PE4_RX_DN<14>
  J34    A20  PETN1  SCONN84_123318136  I43
  U2     P89  PE4_RX_DN1  SOCKET4677_AZIFS054P001C01  I139

P5E_CPU0_PE4_RX_DN<15>   @S9S_MB_2U_LIB.S9S_MB_2U(SCH_1):P5E_CPU0_PE4_RX_DN<15>
  J34    A17  PETN0  SCONN84_123318136  I43
  U2     J90  PE4_RX_DN0  SOCKET4677_AZIFS054P001C01  I139

P5E_CPU0_PE4_RX_DP<0>   @S9S_MB_2U_LIB.S9S_MB_2U(SCH_1):P5E_CPU0_PE4_RX_DP<0>
  J33    A40  PETP7  SCONN84_123318136  I53
  U2     BA90  PE4_RX_DP15  SOCKET4677_AZIFS054P001C01  I139

P5E_CPU0_PE4_RX_DP<1>   @S9S_MB_2U_LIB.S9S_MB_2U(SCH_1):P5E_CPU0_PE4_RX_DP<1>
  J33    A36  PETN6  SCONN84_123318136  I53
  U2     AW90  PE4_RX_DP14  SOCKET4677_AZIFS054P001C01  I139

P5E_CPU0_PE4_RX_DP<2>   @S9S_MB_2U_LIB.S9S_MB_2U(SCH_1):P5E_CPU0_PE4_RX_DP<2>
  J33    A34  PETP5  SCONN84_123318136  I53
  U2     AU90  PE4_RX_DP13  SOCKET4677_AZIFS054P001C01  I139

P5E_CPU0_PE4_RX_DP<3>   @S9S_MB_2U_LIB.S9S_MB_2U(SCH_1):P5E_CPU0_PE4_RX_DP<3>
  J33    A31  PETP4  SCONN84_123318136  I53
  U2     AR90  PE4_RX_DP12  SOCKET4677_AZIFS054P001C01  I139

P5E_CPU0_PE4_RX_DP<4>   @S9S_MB_2U_LIB.S9S_MB_2U(SCH_1):P5E_CPU0_PE4_RX_DP<4>
  J33    A27  PETP3  SCONN84_123318136  I53
  U2     AN90  PE4_RX_DP11  SOCKET4677_AZIFS054P001C01  I139

P5E_CPU0_PE4_RX_DP<5>   @S9S_MB_2U_LIB.S9S_MB_2U(SCH_1):P5E_CPU0_PE4_RX_DP<5>
  J33    A23  PETN2  SCONN84_123318136  I53
  U2     AL90  PE4_RX_DP10  SOCKET4677_AZIFS054P001C01  I139

P5E_CPU0_PE4_RX_DP<6>   @S9S_MB_2U_LIB.S9S_MB_2U(SCH_1):P5E_CPU0_PE4_RX_DP<6>
  J33    A21  PETP1  SCONN84_123318136  I53
  U2     AJ90  PE4_RX_DP9  SOCKET4677_AZIFS054P001C01  I139

P5E_CPU0_PE4_RX_DP<7>   @S9S_MB_2U_LIB.S9S_MB_2U(SCH_1):P5E_CPU0_PE4_RX_DP<7>
  J33    A18  PETP0  SCONN84_123318136  I53
  U2     AG90  PE4_RX_DP8  SOCKET4677_AZIFS054P001C01  I139

P5E_CPU0_PE4_RX_DP<8>   @S9S_MB_2U_LIB.S9S_MB_2U(SCH_1):P5E_CPU0_PE4_RX_DP<8>
  J34    A40  PETP7  SCONN84_123318136  I43
  U2     AE90  PE4_RX_DP7  SOCKET4677_AZIFS054P001C01  I139

P5E_CPU0_PE4_RX_DP<9>   @S9S_MB_2U_LIB.S9S_MB_2U(SCH_1):P5E_CPU0_PE4_RX_DP<9>
  J34    A37  PETP6  SCONN84_123318136  I43
  U2     AC90  PE4_RX_DP6  SOCKET4677_AZIFS054P001C01  I139

P5E_CPU0_PE4_RX_DP<10>   @S9S_MB_2U_LIB.S9S_MB_2U(SCH_1):P5E_CPU0_PE4_RX_DP<10>
  J34    A34  PETP5  SCONN84_123318136  I43
  U2     AA90  PE4_RX_DP5  SOCKET4677_AZIFS054P001C01  I139

P5E_CPU0_PE4_RX_DP<11>   @S9S_MB_2U_LIB.S9S_MB_2U(SCH_1):P5E_CPU0_PE4_RX_DP<11>
  J34    A31  PETP4  SCONN84_123318136  I43
  U2     W90  PE4_RX_DP4  SOCKET4677_AZIFS054P001C01  I139

P5E_CPU0_PE4_RX_DP<12>   @S9S_MB_2U_LIB.S9S_MB_2U(SCH_1):P5E_CPU0_PE4_RX_DP<12>
  J34    A27  PETP3  SCONN84_123318136  I43
  U2     U90  PE4_RX_DP3  SOCKET4677_AZIFS054P001C01  I139

P5E_CPU0_PE4_RX_DP<13>   @S9S_MB_2U_LIB.S9S_MB_2U(SCH_1):P5E_CPU0_PE4_RX_DP<13>
  J34    A24  PETP2  SCONN84_123318136  I43
  U2     R90  PE4_RX_DP2  SOCKET4677_AZIFS054P001C01  I139

P5E_CPU0_PE4_RX_DP<14>   @S9S_MB_2U_LIB.S9S_MB_2U(SCH_1):P5E_CPU0_PE4_RX_DP<14>
  J34    A21  PETP1  SCONN84_123318136  I43
  U2     N90  PE4_RX_DP1  SOCKET4677_AZIFS054P001C01  I139

P5E_CPU0_PE4_RX_DP<15>   @S9S_MB_2U_LIB.S9S_MB_2U(SCH_1):P5E_CPU0_PE4_RX_DP<15>
  J34    A18  PETP0  SCONN84_123318136  I43
  U2     K89  PE4_RX_DP0  SOCKET4677_AZIFS054P001C01  I139

P5E_CPU0_PE4_TX_C_DN<0>   @S9S_MB_2U_LIB.S9S_MB_2U(SCH_1):P5E_CPU0_PE4_TX_C_DN<0>
  C1578    1      1  Q_CAP_DIFFBUS  I230
  J33    B40  PERP7  SCONN84_123318136  I53

P5E_CPU0_PE4_TX_C_DN<1>   @S9S_MB_2U_LIB.S9S_MB_2U(SCH_1):P5E_CPU0_PE4_TX_C_DN<1>
  C1576    1      1  Q_CAP_DIFFBUS  I312
  J33    B37  PERP6  SCONN84_123318136  I53

P5E_CPU0_PE4_TX_C_DN<2>   @S9S_MB_2U_LIB.S9S_MB_2U(SCH_1):P5E_CPU0_PE4_TX_C_DN<2>
  C1574    1      1  Q_CAP_DIFFBUS  I232
  J33    B34  PERP5  SCONN84_123318136  I53

P5E_CPU0_PE4_TX_C_DN<3>   @S9S_MB_2U_LIB.S9S_MB_2U(SCH_1):P5E_CPU0_PE4_TX_C_DN<3>
  C1572    1      1  Q_CAP_DIFFBUS  I234
  J33    B31  PERP4  SCONN84_123318136  I53

P5E_CPU0_PE4_TX_C_DN<4>   @S9S_MB_2U_LIB.S9S_MB_2U(SCH_1):P5E_CPU0_PE4_TX_C_DN<4>
  C1570    1      1  Q_CAP_DIFFBUS  I235
  J33    B27  PERP3  SCONN84_123318136  I53

P5E_CPU0_PE4_TX_C_DN<5>   @S9S_MB_2U_LIB.S9S_MB_2U(SCH_1):P5E_CPU0_PE4_TX_C_DN<5>
  C1568    1      1  Q_CAP_DIFFBUS  I238
  J33    B24  PERP2  SCONN84_123318136  I53

P5E_CPU0_PE4_TX_C_DN<6>   @S9S_MB_2U_LIB.S9S_MB_2U(SCH_1):P5E_CPU0_PE4_TX_C_DN<6>
  C1566    1      1  Q_CAP_DIFFBUS  I240
  J33    B21  PERP1  SCONN84_123318136  I53

P5E_CPU0_PE4_TX_C_DN<7>   @S9S_MB_2U_LIB.S9S_MB_2U(SCH_1):P5E_CPU0_PE4_TX_C_DN<7>
  C1564    1      1  Q_CAP_DIFFBUS  I242
  J33    B18  PERP0  SCONN84_123318136  I53

P5E_CPU0_PE4_TX_C_DN<8>   @S9S_MB_2U_LIB.S9S_MB_2U(SCH_1):P5E_CPU0_PE4_TX_C_DN<8>
  C1562    1      1  Q_CAP_DIFFBUS  I260
  J34    B40  PERP7  SCONN84_123318136  I43

P5E_CPU0_PE4_TX_C_DN<9>   @S9S_MB_2U_LIB.S9S_MB_2U(SCH_1):P5E_CPU0_PE4_TX_C_DN<9>
  C1560    1      1  Q_CAP_DIFFBUS  I262
  J34    B37  PERP6  SCONN84_123318136  I43

P5E_CPU0_PE4_TX_C_DN<10>   @S9S_MB_2U_LIB.S9S_MB_2U(SCH_1):P5E_CPU0_PE4_TX_C_DN<10>
  C1558    1      1  Q_CAP_DIFFBUS  I264
  J34    B34  PERP5  SCONN84_123318136  I43

P5E_CPU0_PE4_TX_C_DN<11>   @S9S_MB_2U_LIB.S9S_MB_2U(SCH_1):P5E_CPU0_PE4_TX_C_DN<11>
  C1556    1      1  Q_CAP_DIFFBUS  I265
  J34    B31  PERP4  SCONN84_123318136  I43

P5E_CPU0_PE4_TX_C_DN<12>   @S9S_MB_2U_LIB.S9S_MB_2U(SCH_1):P5E_CPU0_PE4_TX_C_DN<12>
  C1554    1      1  Q_CAP_DIFFBUS  I268
  J34    B27  PERP3  SCONN84_123318136  I43

P5E_CPU0_PE4_TX_C_DN<13>   @S9S_MB_2U_LIB.S9S_MB_2U(SCH_1):P5E_CPU0_PE4_TX_C_DN<13>
  C1552    1      1  Q_CAP_DIFFBUS  I270
  J34    B24  PERP2  SCONN84_123318136  I43

P5E_CPU0_PE4_TX_C_DN<14>   @S9S_MB_2U_LIB.S9S_MB_2U(SCH_1):P5E_CPU0_PE4_TX_C_DN<14>
  C1550    1      1  Q_CAP_DIFFBUS  I272
  J34    B21  PERP1  SCONN84_123318136  I43

P5E_CPU0_PE4_TX_C_DN<15>   @S9S_MB_2U_LIB.S9S_MB_2U(SCH_1):P5E_CPU0_PE4_TX_C_DN<15>
  C1548    1      1  Q_CAP_DIFFBUS  I273
  J34    B18  PERP0  SCONN84_123318136  I43

P5E_CPU0_PE4_TX_C_DP<0>   @S9S_MB_2U_LIB.S9S_MB_2U(SCH_1):P5E_CPU0_PE4_TX_C_DP<0>
  C1579    1      1  Q_CAP_DIFFBUS  I229
  J33    B39  PERN7  SCONN84_123318136  I53

P5E_CPU0_PE4_TX_C_DP<1>   @S9S_MB_2U_LIB.S9S_MB_2U(SCH_1):P5E_CPU0_PE4_TX_C_DP<1>
  C1577    1      1  Q_CAP_DIFFBUS  I311
  J33    B36  PERN6  SCONN84_123318136  I53

P5E_CPU0_PE4_TX_C_DP<2>   @S9S_MB_2U_LIB.S9S_MB_2U(SCH_1):P5E_CPU0_PE4_TX_C_DP<2>
  C1575    1      1  Q_CAP_DIFFBUS  I231
  J33    B33  PERN5  SCONN84_123318136  I53

P5E_CPU0_PE4_TX_C_DP<3>   @S9S_MB_2U_LIB.S9S_MB_2U(SCH_1):P5E_CPU0_PE4_TX_C_DP<3>
  C1573    1      1  Q_CAP_DIFFBUS  I233
  J33    B30  PERN4  SCONN84_123318136  I53

P5E_CPU0_PE4_TX_C_DP<4>   @S9S_MB_2U_LIB.S9S_MB_2U(SCH_1):P5E_CPU0_PE4_TX_C_DP<4>
  C1571    1      1  Q_CAP_DIFFBUS  I236
  J33    B26  PERN3  SCONN84_123318136  I53

P5E_CPU0_PE4_TX_C_DP<5>   @S9S_MB_2U_LIB.S9S_MB_2U(SCH_1):P5E_CPU0_PE4_TX_C_DP<5>
  C1569    1      1  Q_CAP_DIFFBUS  I237
  J33    B23  PERN2  SCONN84_123318136  I53

P5E_CPU0_PE4_TX_C_DP<6>   @S9S_MB_2U_LIB.S9S_MB_2U(SCH_1):P5E_CPU0_PE4_TX_C_DP<6>
  C1567    1      1  Q_CAP_DIFFBUS  I239
  J33    B20  PERN1  SCONN84_123318136  I53

P5E_CPU0_PE4_TX_C_DP<7>   @S9S_MB_2U_LIB.S9S_MB_2U(SCH_1):P5E_CPU0_PE4_TX_C_DP<7>
  C1565    1      1  Q_CAP_DIFFBUS  I241
  J33    B17  PERN0  SCONN84_123318136  I53

P5E_CPU0_PE4_TX_C_DP<8>   @S9S_MB_2U_LIB.S9S_MB_2U(SCH_1):P5E_CPU0_PE4_TX_C_DP<8>
  C1563    1      1  Q_CAP_DIFFBUS  I259
  J34    B39  PERN7  SCONN84_123318136  I43

P5E_CPU0_PE4_TX_C_DP<9>   @S9S_MB_2U_LIB.S9S_MB_2U(SCH_1):P5E_CPU0_PE4_TX_C_DP<9>
  C1561    1      1  Q_CAP_DIFFBUS  I261
  J34    B36  PERN6  SCONN84_123318136  I43

P5E_CPU0_PE4_TX_C_DP<10>   @S9S_MB_2U_LIB.S9S_MB_2U(SCH_1):P5E_CPU0_PE4_TX_C_DP<10>
  C1559    1      1  Q_CAP_DIFFBUS  I263
  J34    B33  PERN5  SCONN84_123318136  I43

P5E_CPU0_PE4_TX_C_DP<11>   @S9S_MB_2U_LIB.S9S_MB_2U(SCH_1):P5E_CPU0_PE4_TX_C_DP<11>
  C1557    1      1  Q_CAP_DIFFBUS  I266
  J34    B30  PERN4  SCONN84_123318136  I43

P5E_CPU0_PE4_TX_C_DP<12>   @S9S_MB_2U_LIB.S9S_MB_2U(SCH_1):P5E_CPU0_PE4_TX_C_DP<12>
  C1555    1      1  Q_CAP_DIFFBUS  I267
  J34    B26  PERN3  SCONN84_123318136  I43

P5E_CPU0_PE4_TX_C_DP<13>   @S9S_MB_2U_LIB.S9S_MB_2U(SCH_1):P5E_CPU0_PE4_TX_C_DP<13>
  C1553    1      1  Q_CAP_DIFFBUS  I269
  J34    B23  PERN2  SCONN84_123318136  I43

P5E_CPU0_PE4_TX_C_DP<14>   @S9S_MB_2U_LIB.S9S_MB_2U(SCH_1):P5E_CPU0_PE4_TX_C_DP<14>
  C1551    1      1  Q_CAP_DIFFBUS  I271
  J34    B20  PERN1  SCONN84_123318136  I43

P5E_CPU0_PE4_TX_C_DP<15>   @S9S_MB_2U_LIB.S9S_MB_2U(SCH_1):P5E_CPU0_PE4_TX_C_DP<15>
  C1549    1      1  Q_CAP_DIFFBUS  I274
  J34    B17  PERN0  SCONN84_123318136  I43

P5E_CPU0_PE4_TX_DN<0>   @S9S_MB_2U_LIB.S9S_MB_2U(SCH_1):P5E_CPU0_PE4_TX_DN<0>
  C1578    2      2  Q_CAP_DIFFBUS  I230
  U2     BA86  PE4_TX_DN15  SOCKET4677_AZIFS054P001C01  I139

P5E_CPU0_PE4_TX_DN<1>   @S9S_MB_2U_LIB.S9S_MB_2U(SCH_1):P5E_CPU0_PE4_TX_DN<1>
  C1576    2      2  Q_CAP_DIFFBUS  I312
  U2     AW86  PE4_TX_DN14  SOCKET4677_AZIFS054P001C01  I139

P5E_CPU0_PE4_TX_DN<2>   @S9S_MB_2U_LIB.S9S_MB_2U(SCH_1):P5E_CPU0_PE4_TX_DN<2>
  C1574    2      2  Q_CAP_DIFFBUS  I232
  U2     AU86  PE4_TX_DN13  SOCKET4677_AZIFS054P001C01  I139

P5E_CPU0_PE4_TX_DN<3>   @S9S_MB_2U_LIB.S9S_MB_2U(SCH_1):P5E_CPU0_PE4_TX_DN<3>
  C1572    2      2  Q_CAP_DIFFBUS  I234
  U2     AR86  PE4_TX_DN12  SOCKET4677_AZIFS054P001C01  I139

P5E_CPU0_PE4_TX_DN<4>   @S9S_MB_2U_LIB.S9S_MB_2U(SCH_1):P5E_CPU0_PE4_TX_DN<4>
  C1570    2      2  Q_CAP_DIFFBUS  I235
  U2     AP85  PE4_TX_DN11  SOCKET4677_AZIFS054P001C01  I139

P5E_CPU0_PE4_TX_DN<5>   @S9S_MB_2U_LIB.S9S_MB_2U(SCH_1):P5E_CPU0_PE4_TX_DN<5>
  C1568    2      2  Q_CAP_DIFFBUS  I238
  U2     AL86  PE4_TX_DN10  SOCKET4677_AZIFS054P001C01  I139

P5E_CPU0_PE4_TX_DN<6>   @S9S_MB_2U_LIB.S9S_MB_2U(SCH_1):P5E_CPU0_PE4_TX_DN<6>
  C1566    2      2  Q_CAP_DIFFBUS  I240
  U2     AJ86  PE4_TX_DN9  SOCKET4677_AZIFS054P001C01  I139

P5E_CPU0_PE4_TX_DN<7>   @S9S_MB_2U_LIB.S9S_MB_2U(SCH_1):P5E_CPU0_PE4_TX_DN<7>
  C1564    2      2  Q_CAP_DIFFBUS  I242
  U2     AG86  PE4_TX_DN8  SOCKET4677_AZIFS054P001C01  I139

P5E_CPU0_PE4_TX_DN<8>   @S9S_MB_2U_LIB.S9S_MB_2U(SCH_1):P5E_CPU0_PE4_TX_DN<8>
  C1562    2      2  Q_CAP_DIFFBUS  I260
  U2     AE86  PE4_TX_DN7  SOCKET4677_AZIFS054P001C01  I139

P5E_CPU0_PE4_TX_DN<9>   @S9S_MB_2U_LIB.S9S_MB_2U(SCH_1):P5E_CPU0_PE4_TX_DN<9>
  C1560    2      2  Q_CAP_DIFFBUS  I262
  U2     AC86  PE4_TX_DN6  SOCKET4677_AZIFS054P001C01  I139

P5E_CPU0_PE4_TX_DN<10>   @S9S_MB_2U_LIB.S9S_MB_2U(SCH_1):P5E_CPU0_PE4_TX_DN<10>
  C1558    2      2  Q_CAP_DIFFBUS  I264
  U2     AA86  PE4_TX_DN5  SOCKET4677_AZIFS054P001C01  I139

P5E_CPU0_PE4_TX_DN<11>   @S9S_MB_2U_LIB.S9S_MB_2U(SCH_1):P5E_CPU0_PE4_TX_DN<11>
  C1556    2      2  Q_CAP_DIFFBUS  I265
  U2     W86  PE4_TX_DN4  SOCKET4677_AZIFS054P001C01  I139

P5E_CPU0_PE4_TX_DN<12>   @S9S_MB_2U_LIB.S9S_MB_2U(SCH_1):P5E_CPU0_PE4_TX_DN<12>
  C1554    2      2  Q_CAP_DIFFBUS  I268
  U2     U86  PE4_TX_DN3  SOCKET4677_AZIFS054P001C01  I139

P5E_CPU0_PE4_TX_DN<13>   @S9S_MB_2U_LIB.S9S_MB_2U(SCH_1):P5E_CPU0_PE4_TX_DN<13>
  C1552    2      2  Q_CAP_DIFFBUS  I270
  U2     R86  PE4_TX_DN2  SOCKET4677_AZIFS054P001C01  I139

P5E_CPU0_PE4_TX_DN<14>   @S9S_MB_2U_LIB.S9S_MB_2U(SCH_1):P5E_CPU0_PE4_TX_DN<14>
  C1550    2      2  Q_CAP_DIFFBUS  I272
  U2     P85  PE4_TX_DN1  SOCKET4677_AZIFS054P001C01  I139

P5E_CPU0_PE4_TX_DN<15>   @S9S_MB_2U_LIB.S9S_MB_2U(SCH_1):P5E_CPU0_PE4_TX_DN<15>
  C1548    2      2  Q_CAP_DIFFBUS  I273
  U2     L86  PE4_TX_DN0  SOCKET4677_AZIFS054P001C01  I139

P5E_CPU0_PE4_TX_DP<0>   @S9S_MB_2U_LIB.S9S_MB_2U(SCH_1):P5E_CPU0_PE4_TX_DP<0>
  C1579    2      2  Q_CAP_DIFFBUS  I229
  U2     BB85  PE4_TX_DP15  SOCKET4677_AZIFS054P001C01  I139

P5E_CPU0_PE4_TX_DP<1>   @S9S_MB_2U_LIB.S9S_MB_2U(SCH_1):P5E_CPU0_PE4_TX_DP<1>
  C1577    2      2  Q_CAP_DIFFBUS  I311
  U2     AY87  PE4_TX_DP14  SOCKET4677_AZIFS054P001C01  I139

P5E_CPU0_PE4_TX_DP<2>   @S9S_MB_2U_LIB.S9S_MB_2U(SCH_1):P5E_CPU0_PE4_TX_DP<2>
  C1575    2      2  Q_CAP_DIFFBUS  I231
  U2     AV85  PE4_TX_DP13  SOCKET4677_AZIFS054P001C01  I139

P5E_CPU0_PE4_TX_DP<3>   @S9S_MB_2U_LIB.S9S_MB_2U(SCH_1):P5E_CPU0_PE4_TX_DP<3>
  C1573    2      2  Q_CAP_DIFFBUS  I233
  U2     AT87  PE4_TX_DP12  SOCKET4677_AZIFS054P001C01  I139

P5E_CPU0_PE4_TX_DP<4>   @S9S_MB_2U_LIB.S9S_MB_2U(SCH_1):P5E_CPU0_PE4_TX_DP<4>
  C1571    2      2  Q_CAP_DIFFBUS  I236
  U2     AN86  PE4_TX_DP11  SOCKET4677_AZIFS054P001C01  I139

P5E_CPU0_PE4_TX_DP<5>   @S9S_MB_2U_LIB.S9S_MB_2U(SCH_1):P5E_CPU0_PE4_TX_DP<5>
  C1569    2      2  Q_CAP_DIFFBUS  I237
  U2     AM87  PE4_TX_DP10  SOCKET4677_AZIFS054P001C01  I139

P5E_CPU0_PE4_TX_DP<6>   @S9S_MB_2U_LIB.S9S_MB_2U(SCH_1):P5E_CPU0_PE4_TX_DP<6>
  C1567    2      2  Q_CAP_DIFFBUS  I239
  U2     AK85  PE4_TX_DP9  SOCKET4677_AZIFS054P001C01  I139

P5E_CPU0_PE4_TX_DP<7>   @S9S_MB_2U_LIB.S9S_MB_2U(SCH_1):P5E_CPU0_PE4_TX_DP<7>
  C1565    2      2  Q_CAP_DIFFBUS  I241
  U2     AH87  PE4_TX_DP8  SOCKET4677_AZIFS054P001C01  I139

P5E_CPU0_PE4_TX_DP<8>   @S9S_MB_2U_LIB.S9S_MB_2U(SCH_1):P5E_CPU0_PE4_TX_DP<8>
  C1563    2      2  Q_CAP_DIFFBUS  I259
  U2     AF85  PE4_TX_DP7  SOCKET4677_AZIFS054P001C01  I139

P5E_CPU0_PE4_TX_DP<9>   @S9S_MB_2U_LIB.S9S_MB_2U(SCH_1):P5E_CPU0_PE4_TX_DP<9>
  C1561    2      2  Q_CAP_DIFFBUS  I261
  U2     AD87  PE4_TX_DP6  SOCKET4677_AZIFS054P001C01  I139

P5E_CPU0_PE4_TX_DP<10>   @S9S_MB_2U_LIB.S9S_MB_2U(SCH_1):P5E_CPU0_PE4_TX_DP<10>
  C1559    2      2  Q_CAP_DIFFBUS  I263
  U2     AB85  PE4_TX_DP5  SOCKET4677_AZIFS054P001C01  I139

P5E_CPU0_PE4_TX_DP<11>   @S9S_MB_2U_LIB.S9S_MB_2U(SCH_1):P5E_CPU0_PE4_TX_DP<11>
  C1557    2      2  Q_CAP_DIFFBUS  I266
  U2     Y87  PE4_TX_DP4  SOCKET4677_AZIFS054P001C01  I139

P5E_CPU0_PE4_TX_DP<12>   @S9S_MB_2U_LIB.S9S_MB_2U(SCH_1):P5E_CPU0_PE4_TX_DP<12>
  C1555    2      2  Q_CAP_DIFFBUS  I267
  U2     V85  PE4_TX_DP3  SOCKET4677_AZIFS054P001C01  I139

P5E_CPU0_PE4_TX_DP<13>   @S9S_MB_2U_LIB.S9S_MB_2U(SCH_1):P5E_CPU0_PE4_TX_DP<13>
  C1553    2      2  Q_CAP_DIFFBUS  I269
  U2     T87  PE4_TX_DP2  SOCKET4677_AZIFS054P001C01  I139

P5E_CPU0_PE4_TX_DP<14>   @S9S_MB_2U_LIB.S9S_MB_2U(SCH_1):P5E_CPU0_PE4_TX_DP<14>
  C1551    2      2  Q_CAP_DIFFBUS  I271
  U2     N86  PE4_TX_DP1  SOCKET4677_AZIFS054P001C01  I139

P5E_CPU0_PE4_TX_DP<15>   @S9S_MB_2U_LIB.S9S_MB_2U(SCH_1):P5E_CPU0_PE4_TX_DP<15>
  C1549    2      2  Q_CAP_DIFFBUS  I274
  U2     M87  PE4_TX_DP0  SOCKET4677_AZIFS054P001C01  I139

P5E_CPU1_PE0_RX_DN<0>   @S9S_MB_2U_LIB.S9S_MB_2U(SCH_1):P5E_CPU1_PE0_RX_DN<0>
  J89    A83    A83  SCONN280_ME1028040102011  I239
  U1     BA9  PE0_RX_DN15  SOCKET4677_AZIFS054P001C01  I80

P5E_CPU1_PE0_RX_DN<1>   @S9S_MB_2U_LIB.S9S_MB_2U(SCH_1):P5E_CPU1_PE0_RX_DN<1>
  J89    A80    A80  SCONN280_ME1028040102011  I239
  U1     AV10  PE0_RX_DN14  SOCKET4677_AZIFS054P001C01  I80

P5E_CPU1_PE0_RX_DN<2>   @S9S_MB_2U_LIB.S9S_MB_2U(SCH_1):P5E_CPU1_PE0_RX_DN<2>
  J89    A77    A77  SCONN280_ME1028040102011  I239
  U1     AU9  PE0_RX_DN13  SOCKET4677_AZIFS054P001C01  I80

P5E_CPU1_PE0_RX_DN<3>   @S9S_MB_2U_LIB.S9S_MB_2U(SCH_1):P5E_CPU1_PE0_RX_DN<3>
  J89    A74    A74  SCONN280_ME1028040102011  I239
  U1     AP10  PE0_RX_DN12  SOCKET4677_AZIFS054P001C01  I80

P5E_CPU1_PE0_RX_DN<4>   @S9S_MB_2U_LIB.S9S_MB_2U(SCH_1):P5E_CPU1_PE0_RX_DN<4>
  J89    A71    A71  SCONN280_ME1028040102011  I239
  U1     AM10  PE0_RX_DN11  SOCKET4677_AZIFS054P001C01  I80

P5E_CPU1_PE0_RX_DN<5>   @S9S_MB_2U_LIB.S9S_MB_2U(SCH_1):P5E_CPU1_PE0_RX_DN<5>
  J89    A68    A68  SCONN280_ME1028040102011  I239
  U1     AK10  PE0_RX_DN10  SOCKET4677_AZIFS054P001C01  I80

P5E_CPU1_PE0_RX_DN<6>   @S9S_MB_2U_LIB.S9S_MB_2U(SCH_1):P5E_CPU1_PE0_RX_DN<6>
  J89    A65    A65  SCONN280_ME1028040102011  I239
  U1     AJ9  PE0_RX_DN9  SOCKET4677_AZIFS054P001C01  I80

P5E_CPU1_PE0_RX_DN<7>   @S9S_MB_2U_LIB.S9S_MB_2U(SCH_1):P5E_CPU1_PE0_RX_DN<7>
  J89    A62    A62  SCONN280_ME1028040102011  I239
  U1     AF10  PE0_RX_DN8  SOCKET4677_AZIFS054P001C01  I80

P5E_CPU1_PE0_RX_DN<8>   @S9S_MB_2U_LIB.S9S_MB_2U(SCH_1):P5E_CPU1_PE0_RX_DN<8>
  J89    A59    A59  SCONN280_ME1028040102011  I239
  U1     AE9  PE0_RX_DN7  SOCKET4677_AZIFS054P001C01  I80

P5E_CPU1_PE0_RX_DN<9>   @S9S_MB_2U_LIB.S9S_MB_2U(SCH_1):P5E_CPU1_PE0_RX_DN<9>
  J89    A55    A55  SCONN280_ME1028040102011  I239
  U1     AB10  PE0_RX_DN6  SOCKET4677_AZIFS054P001C01  I80

P5E_CPU1_PE0_RX_DN<10>   @S9S_MB_2U_LIB.S9S_MB_2U(SCH_1):P5E_CPU1_PE0_RX_DN<10>
  J89    A52    A52  SCONN280_ME1028040102011  I239
  U1     AA9  PE0_RX_DN5  SOCKET4677_AZIFS054P001C01  I80

P5E_CPU1_PE0_RX_DN<11>   @S9S_MB_2U_LIB.S9S_MB_2U(SCH_1):P5E_CPU1_PE0_RX_DN<11>
  J89    A49    A49  SCONN280_ME1028040102011  I239
  U1     V10  PE0_RX_DN4  SOCKET4677_AZIFS054P001C01  I80

P5E_CPU1_PE0_RX_DN<12>   @S9S_MB_2U_LIB.S9S_MB_2U(SCH_1):P5E_CPU1_PE0_RX_DN<12>
  J89    A46    A46  SCONN280_ME1028040102011  I239
  U1     T10  PE0_RX_DN3  SOCKET4677_AZIFS054P001C01  I80

P5E_CPU1_PE0_RX_DN<13>   @S9S_MB_2U_LIB.S9S_MB_2U(SCH_1):P5E_CPU1_PE0_RX_DN<13>
  J89    A43    A43  SCONN280_ME1028040102011  I239
  U1     P10  PE0_RX_DN2  SOCKET4677_AZIFS054P001C01  I80

P5E_CPU1_PE0_RX_DN<14>   @S9S_MB_2U_LIB.S9S_MB_2U(SCH_1):P5E_CPU1_PE0_RX_DN<14>
  J89    A40    A40  SCONN280_ME1028040102011  I239
  U1     M10  PE0_RX_DN1  SOCKET4677_AZIFS054P001C01  I80

P5E_CPU1_PE0_RX_DN<15>   @S9S_MB_2U_LIB.S9S_MB_2U(SCH_1):P5E_CPU1_PE0_RX_DN<15>
  J89    A37    A37  SCONN280_ME1028040102011  I239
  U1     K10  PE0_RX_DN0  SOCKET4677_AZIFS054P001C01  I80

P5E_CPU1_PE0_RX_DP<0>   @S9S_MB_2U_LIB.S9S_MB_2U(SCH_1):P5E_CPU1_PE0_RX_DP<0>
  J89    A82    A82  SCONN280_ME1028040102011  I239
  U1     AY10  PE0_RX_DP15  SOCKET4677_AZIFS054P001C01  I80

P5E_CPU1_PE0_RX_DP<1>   @S9S_MB_2U_LIB.S9S_MB_2U(SCH_1):P5E_CPU1_PE0_RX_DP<1>
  J89    A79    A79  SCONN280_ME1028040102011  I239
  U1     AW11  PE0_RX_DP14  SOCKET4677_AZIFS054P001C01  I80

P5E_CPU1_PE0_RX_DP<2>   @S9S_MB_2U_LIB.S9S_MB_2U(SCH_1):P5E_CPU1_PE0_RX_DP<2>
  J89    A76    A76  SCONN280_ME1028040102011  I239
  U1     AT10  PE0_RX_DP13  SOCKET4677_AZIFS054P001C01  I80

P5E_CPU1_PE0_RX_DP<3>   @S9S_MB_2U_LIB.S9S_MB_2U(SCH_1):P5E_CPU1_PE0_RX_DP<3>
  J89    A73    A73  SCONN280_ME1028040102011  I239
  U1     AR11  PE0_RX_DP12  SOCKET4677_AZIFS054P001C01  I80

P5E_CPU1_PE0_RX_DP<4>   @S9S_MB_2U_LIB.S9S_MB_2U(SCH_1):P5E_CPU1_PE0_RX_DP<4>
  J89    A70    A70  SCONN280_ME1028040102011  I239
  U1     AN9  PE0_RX_DP11  SOCKET4677_AZIFS054P001C01  I80

P5E_CPU1_PE0_RX_DP<5>   @S9S_MB_2U_LIB.S9S_MB_2U(SCH_1):P5E_CPU1_PE0_RX_DP<5>
  J89    A67    A67  SCONN280_ME1028040102011  I239
  U1     AL11  PE0_RX_DP10  SOCKET4677_AZIFS054P001C01  I80

P5E_CPU1_PE0_RX_DP<6>   @S9S_MB_2U_LIB.S9S_MB_2U(SCH_1):P5E_CPU1_PE0_RX_DP<6>
  J89    A64    A64  SCONN280_ME1028040102011  I239
  U1     AH10  PE0_RX_DP9  SOCKET4677_AZIFS054P001C01  I80

P5E_CPU1_PE0_RX_DP<7>   @S9S_MB_2U_LIB.S9S_MB_2U(SCH_1):P5E_CPU1_PE0_RX_DP<7>
  J89    A61    A61  SCONN280_ME1028040102011  I239
  U1     AG11  PE0_RX_DP8  SOCKET4677_AZIFS054P001C01  I80

P5E_CPU1_PE0_RX_DP<8>   @S9S_MB_2U_LIB.S9S_MB_2U(SCH_1):P5E_CPU1_PE0_RX_DP<8>
  J89    A58    A58  SCONN280_ME1028040102011  I239
  U1     AD10  PE0_RX_DP7  SOCKET4677_AZIFS054P001C01  I80

P5E_CPU1_PE0_RX_DP<9>   @S9S_MB_2U_LIB.S9S_MB_2U(SCH_1):P5E_CPU1_PE0_RX_DP<9>
  J89    A54    A54  SCONN280_ME1028040102011  I239
  U1     AC11  PE0_RX_DP6  SOCKET4677_AZIFS054P001C01  I80

P5E_CPU1_PE0_RX_DP<10>   @S9S_MB_2U_LIB.S9S_MB_2U(SCH_1):P5E_CPU1_PE0_RX_DP<10>
  J89    A51    A51  SCONN280_ME1028040102011  I239
  U1     Y10  PE0_RX_DP5  SOCKET4677_AZIFS054P001C01  I80

P5E_CPU1_PE0_RX_DP<11>   @S9S_MB_2U_LIB.S9S_MB_2U(SCH_1):P5E_CPU1_PE0_RX_DP<11>
  J89    A48    A48  SCONN280_ME1028040102011  I239
  U1     W11  PE0_RX_DP4  SOCKET4677_AZIFS054P001C01  I80

P5E_CPU1_PE0_RX_DP<12>   @S9S_MB_2U_LIB.S9S_MB_2U(SCH_1):P5E_CPU1_PE0_RX_DP<12>
  J89    A45    A45  SCONN280_ME1028040102011  I239
  U1      U9  PE0_RX_DP3  SOCKET4677_AZIFS054P001C01  I80

P5E_CPU1_PE0_RX_DP<13>   @S9S_MB_2U_LIB.S9S_MB_2U(SCH_1):P5E_CPU1_PE0_RX_DP<13>
  J89    A42    A42  SCONN280_ME1028040102011  I239
  U1     R11  PE0_RX_DP2  SOCKET4677_AZIFS054P001C01  I80

P5E_CPU1_PE0_RX_DP<14>   @S9S_MB_2U_LIB.S9S_MB_2U(SCH_1):P5E_CPU1_PE0_RX_DP<14>
  J89    A39    A39  SCONN280_ME1028040102011  I239
  U1      N9  PE0_RX_DP1  SOCKET4677_AZIFS054P001C01  I80

P5E_CPU1_PE0_RX_DP<15>   @S9S_MB_2U_LIB.S9S_MB_2U(SCH_1):P5E_CPU1_PE0_RX_DP<15>
  J89    A36    A36  SCONN280_ME1028040102011  I239
  U1     L11  PE0_RX_DP0  SOCKET4677_AZIFS054P001C01  I80

P5E_CPU1_PE0_TX_C_DN<0>   @S9S_MB_2U_LIB.S9S_MB_2U(SCH_1):P5E_CPU1_PE0_TX_C_DN<0>
  C836     1      1  Q_CAP_DIFFBUS  I395
  J89    B83    B83  SCONN280_ME1028040102011  I239

P5E_CPU1_PE0_TX_C_DN<1>   @S9S_MB_2U_LIB.S9S_MB_2U(SCH_1):P5E_CPU1_PE0_TX_C_DN<1>
  C834     1      1  Q_CAP_DIFFBUS  I393
  J89    B80    B80  SCONN280_ME1028040102011  I239

P5E_CPU1_PE0_TX_C_DN<2>   @S9S_MB_2U_LIB.S9S_MB_2U(SCH_1):P5E_CPU1_PE0_TX_C_DN<2>
  C832     1      1  Q_CAP_DIFFBUS  I392
  J89    B77    B77  SCONN280_ME1028040102011  I239

P5E_CPU1_PE0_TX_C_DN<3>   @S9S_MB_2U_LIB.S9S_MB_2U(SCH_1):P5E_CPU1_PE0_TX_C_DN<3>
  C830     1      1  Q_CAP_DIFFBUS  I390
  J89    B74    B74  SCONN280_ME1028040102011  I239

P5E_CPU1_PE0_TX_C_DN<4>   @S9S_MB_2U_LIB.S9S_MB_2U(SCH_1):P5E_CPU1_PE0_TX_C_DN<4>
  C828     1      1  Q_CAP_DIFFBUS  I388
  J89    B71    B71  SCONN280_ME1028040102011  I239

P5E_CPU1_PE0_TX_C_DN<5>   @S9S_MB_2U_LIB.S9S_MB_2U(SCH_1):P5E_CPU1_PE0_TX_C_DN<5>
  C826     1      1  Q_CAP_DIFFBUS  I386
  J89    B68    B68  SCONN280_ME1028040102011  I239

P5E_CPU1_PE0_TX_C_DN<6>   @S9S_MB_2U_LIB.S9S_MB_2U(SCH_1):P5E_CPU1_PE0_TX_C_DN<6>
  C824     1      1  Q_CAP_DIFFBUS  I385
  J89    B65    B65  SCONN280_ME1028040102011  I239

P5E_CPU1_PE0_TX_C_DN<7>   @S9S_MB_2U_LIB.S9S_MB_2U(SCH_1):P5E_CPU1_PE0_TX_C_DN<7>
  C822     1      1  Q_CAP_DIFFBUS  I382
  J89    B62    B62  SCONN280_ME1028040102011  I239

P5E_CPU1_PE0_TX_C_DN<8>   @S9S_MB_2U_LIB.S9S_MB_2U(SCH_1):P5E_CPU1_PE0_TX_C_DN<8>
  C820     1      1  Q_CAP_DIFFBUS  I364
  J89    B59    B59  SCONN280_ME1028040102011  I239

P5E_CPU1_PE0_TX_C_DN<9>   @S9S_MB_2U_LIB.S9S_MB_2U(SCH_1):P5E_CPU1_PE0_TX_C_DN<9>
  C818     1      1  Q_CAP_DIFFBUS  I313
  J89    B55    B55  SCONN280_ME1028040102011  I239

P5E_CPU1_PE0_TX_C_DN<10>   @S9S_MB_2U_LIB.S9S_MB_2U(SCH_1):P5E_CPU1_PE0_TX_C_DN<10>
  C816     1      1  Q_CAP_DIFFBUS  I361
  J89    B52    B52  SCONN280_ME1028040102011  I239

P5E_CPU1_PE0_TX_C_DN<11>   @S9S_MB_2U_LIB.S9S_MB_2U(SCH_1):P5E_CPU1_PE0_TX_C_DN<11>
  C814     1      1  Q_CAP_DIFFBUS  I359
  J89    B49    B49  SCONN280_ME1028040102011  I239

P5E_CPU1_PE0_TX_C_DN<12>   @S9S_MB_2U_LIB.S9S_MB_2U(SCH_1):P5E_CPU1_PE0_TX_C_DN<12>
  C812     1      1  Q_CAP_DIFFBUS  I357
  J89    B46    B46  SCONN280_ME1028040102011  I239

P5E_CPU1_PE0_TX_C_DN<13>   @S9S_MB_2U_LIB.S9S_MB_2U(SCH_1):P5E_CPU1_PE0_TX_C_DN<13>
  C810     1      1  Q_CAP_DIFFBUS  I355
  J89    B43    B43  SCONN280_ME1028040102011  I239

P5E_CPU1_PE0_TX_C_DN<14>   @S9S_MB_2U_LIB.S9S_MB_2U(SCH_1):P5E_CPU1_PE0_TX_C_DN<14>
  C808     1      1  Q_CAP_DIFFBUS  I353
  J89    B40    B40  SCONN280_ME1028040102011  I239

P5E_CPU1_PE0_TX_C_DN<15>   @S9S_MB_2U_LIB.S9S_MB_2U(SCH_1):P5E_CPU1_PE0_TX_C_DN<15>
  C806     1      1  Q_CAP_DIFFBUS  I352
  J89    B37    B37  SCONN280_ME1028040102011  I239

P5E_CPU1_PE0_TX_C_DP<0>   @S9S_MB_2U_LIB.S9S_MB_2U(SCH_1):P5E_CPU1_PE0_TX_C_DP<0>
  C837     1      1  Q_CAP_DIFFBUS  I396
  J89    B82    B82  SCONN280_ME1028040102011  I239

P5E_CPU1_PE0_TX_C_DP<1>   @S9S_MB_2U_LIB.S9S_MB_2U(SCH_1):P5E_CPU1_PE0_TX_C_DP<1>
  C835     1      1  Q_CAP_DIFFBUS  I394
  J89    B79    B79  SCONN280_ME1028040102011  I239

P5E_CPU1_PE0_TX_C_DP<2>   @S9S_MB_2U_LIB.S9S_MB_2U(SCH_1):P5E_CPU1_PE0_TX_C_DP<2>
  C833     1      1  Q_CAP_DIFFBUS  I391
  J89    B76    B76  SCONN280_ME1028040102011  I239

P5E_CPU1_PE0_TX_C_DP<3>   @S9S_MB_2U_LIB.S9S_MB_2U(SCH_1):P5E_CPU1_PE0_TX_C_DP<3>
  C831     1      1  Q_CAP_DIFFBUS  I314
  J89    B73    B73  SCONN280_ME1028040102011  I239

P5E_CPU1_PE0_TX_C_DP<4>   @S9S_MB_2U_LIB.S9S_MB_2U(SCH_1):P5E_CPU1_PE0_TX_C_DP<4>
  C829     1      1  Q_CAP_DIFFBUS  I389
  J89    B70    B70  SCONN280_ME1028040102011  I239

P5E_CPU1_PE0_TX_C_DP<5>   @S9S_MB_2U_LIB.S9S_MB_2U(SCH_1):P5E_CPU1_PE0_TX_C_DP<5>
  C827     1      1  Q_CAP_DIFFBUS  I387
  J89    B67    B67  SCONN280_ME1028040102011  I239

P5E_CPU1_PE0_TX_C_DP<6>   @S9S_MB_2U_LIB.S9S_MB_2U(SCH_1):P5E_CPU1_PE0_TX_C_DP<6>
  C825     1      1  Q_CAP_DIFFBUS  I384
  J89    B64    B64  SCONN280_ME1028040102011  I239

P5E_CPU1_PE0_TX_C_DP<7>   @S9S_MB_2U_LIB.S9S_MB_2U(SCH_1):P5E_CPU1_PE0_TX_C_DP<7>
  C823     1      1  Q_CAP_DIFFBUS  I383
  J89    B61    B61  SCONN280_ME1028040102011  I239

P5E_CPU1_PE0_TX_C_DP<8>   @S9S_MB_2U_LIB.S9S_MB_2U(SCH_1):P5E_CPU1_PE0_TX_C_DP<8>
  C821     1      1  Q_CAP_DIFFBUS  I365
  J89    B58    B58  SCONN280_ME1028040102011  I239

P5E_CPU1_PE0_TX_C_DP<9>   @S9S_MB_2U_LIB.S9S_MB_2U(SCH_1):P5E_CPU1_PE0_TX_C_DP<9>
  C819     1      1  Q_CAP_DIFFBUS  I363
  J89    B54    B54  SCONN280_ME1028040102011  I239

P5E_CPU1_PE0_TX_C_DP<10>   @S9S_MB_2U_LIB.S9S_MB_2U(SCH_1):P5E_CPU1_PE0_TX_C_DP<10>
  C817     1      1  Q_CAP_DIFFBUS  I362
  J89    B51    B51  SCONN280_ME1028040102011  I239

P5E_CPU1_PE0_TX_C_DP<11>   @S9S_MB_2U_LIB.S9S_MB_2U(SCH_1):P5E_CPU1_PE0_TX_C_DP<11>
  C815     1      1  Q_CAP_DIFFBUS  I360
  J89    B48    B48  SCONN280_ME1028040102011  I239

P5E_CPU1_PE0_TX_C_DP<12>   @S9S_MB_2U_LIB.S9S_MB_2U(SCH_1):P5E_CPU1_PE0_TX_C_DP<12>
  C813     1      1  Q_CAP_DIFFBUS  I358
  J89    B45    B45  SCONN280_ME1028040102011  I239

P5E_CPU1_PE0_TX_C_DP<13>   @S9S_MB_2U_LIB.S9S_MB_2U(SCH_1):P5E_CPU1_PE0_TX_C_DP<13>
  C811     1      1  Q_CAP_DIFFBUS  I356
  J89    B42    B42  SCONN280_ME1028040102011  I239

P5E_CPU1_PE0_TX_C_DP<14>   @S9S_MB_2U_LIB.S9S_MB_2U(SCH_1):P5E_CPU1_PE0_TX_C_DP<14>
  C809     1      1  Q_CAP_DIFFBUS  I354
  J89    B39    B39  SCONN280_ME1028040102011  I239

P5E_CPU1_PE0_TX_C_DP<15>   @S9S_MB_2U_LIB.S9S_MB_2U(SCH_1):P5E_CPU1_PE0_TX_C_DP<15>
  C807     1      1  Q_CAP_DIFFBUS  I351
  J89    B36    B36  SCONN280_ME1028040102011  I239

P5E_CPU1_PE0_TX_DN<0>   @S9S_MB_2U_LIB.S9S_MB_2U(SCH_1):P5E_CPU1_PE0_TX_DN<0>
  C836     2      2  Q_CAP_DIFFBUS  I395
  U1     BB14  PE0_TX_DN15  SOCKET4677_AZIFS054P001C01  I80

P5E_CPU1_PE0_TX_DN<1>   @S9S_MB_2U_LIB.S9S_MB_2U(SCH_1):P5E_CPU1_PE0_TX_DN<1>
  C834     2      2  Q_CAP_DIFFBUS  I393
  U1     BA13  PE0_TX_DN14  SOCKET4677_AZIFS054P001C01  I80

P5E_CPU1_PE0_TX_DN<2>   @S9S_MB_2U_LIB.S9S_MB_2U(SCH_1):P5E_CPU1_PE0_TX_DN<2>
  C832     2      2  Q_CAP_DIFFBUS  I392
  U1     AV14  PE0_TX_DN13  SOCKET4677_AZIFS054P001C01  I80

P5E_CPU1_PE0_TX_DN<3>   @S9S_MB_2U_LIB.S9S_MB_2U(SCH_1):P5E_CPU1_PE0_TX_DN<3>
  C830     2      2  Q_CAP_DIFFBUS  I390
  U1     AU13  PE0_TX_DN12  SOCKET4677_AZIFS054P001C01  I80

P5E_CPU1_PE0_TX_DN<4>   @S9S_MB_2U_LIB.S9S_MB_2U(SCH_1):P5E_CPU1_PE0_TX_DN<4>
  C828     2      2  Q_CAP_DIFFBUS  I388
  U1     AP14  PE0_TX_DN11  SOCKET4677_AZIFS054P001C01  I80

P5E_CPU1_PE0_TX_DN<5>   @S9S_MB_2U_LIB.S9S_MB_2U(SCH_1):P5E_CPU1_PE0_TX_DN<5>
  C826     2      2  Q_CAP_DIFFBUS  I386
  U1     AN13  PE0_TX_DN10  SOCKET4677_AZIFS054P001C01  I80

P5E_CPU1_PE0_TX_DN<6>   @S9S_MB_2U_LIB.S9S_MB_2U(SCH_1):P5E_CPU1_PE0_TX_DN<6>
  C824     2      2  Q_CAP_DIFFBUS  I385
  U1     AK14  PE0_TX_DN9  SOCKET4677_AZIFS054P001C01  I80

P5E_CPU1_PE0_TX_DN<7>   @S9S_MB_2U_LIB.S9S_MB_2U(SCH_1):P5E_CPU1_PE0_TX_DN<7>
  C822     2      2  Q_CAP_DIFFBUS  I382
  U1     AJ13  PE0_TX_DN8  SOCKET4677_AZIFS054P001C01  I80

P5E_CPU1_PE0_TX_DN<8>   @S9S_MB_2U_LIB.S9S_MB_2U(SCH_1):P5E_CPU1_PE0_TX_DN<8>
  C820     2      2  Q_CAP_DIFFBUS  I364
  U1     AF14  PE0_TX_DN7  SOCKET4677_AZIFS054P001C01  I80

P5E_CPU1_PE0_TX_DN<9>   @S9S_MB_2U_LIB.S9S_MB_2U(SCH_1):P5E_CPU1_PE0_TX_DN<9>
  C818     2      2  Q_CAP_DIFFBUS  I313
  U1     AE13  PE0_TX_DN6  SOCKET4677_AZIFS054P001C01  I80

P5E_CPU1_PE0_TX_DN<10>   @S9S_MB_2U_LIB.S9S_MB_2U(SCH_1):P5E_CPU1_PE0_TX_DN<10>
  C816     2      2  Q_CAP_DIFFBUS  I361
  U1     AB14  PE0_TX_DN5  SOCKET4677_AZIFS054P001C01  I80

P5E_CPU1_PE0_TX_DN<11>   @S9S_MB_2U_LIB.S9S_MB_2U(SCH_1):P5E_CPU1_PE0_TX_DN<11>
  C814     2      2  Q_CAP_DIFFBUS  I359
  U1     AA13  PE0_TX_DN4  SOCKET4677_AZIFS054P001C01  I80

P5E_CPU1_PE0_TX_DN<12>   @S9S_MB_2U_LIB.S9S_MB_2U(SCH_1):P5E_CPU1_PE0_TX_DN<12>
  C812     2      2  Q_CAP_DIFFBUS  I357
  U1     V14  PE0_TX_DN3  SOCKET4677_AZIFS054P001C01  I80

P5E_CPU1_PE0_TX_DN<13>   @S9S_MB_2U_LIB.S9S_MB_2U(SCH_1):P5E_CPU1_PE0_TX_DN<13>
  C810     2      2  Q_CAP_DIFFBUS  I355
  U1     U13  PE0_TX_DN2  SOCKET4677_AZIFS054P001C01  I80

P5E_CPU1_PE0_TX_DN<14>   @S9S_MB_2U_LIB.S9S_MB_2U(SCH_1):P5E_CPU1_PE0_TX_DN<14>
  C808     2      2  Q_CAP_DIFFBUS  I353
  U1     P14  PE0_TX_DN1  SOCKET4677_AZIFS054P001C01  I80

P5E_CPU1_PE0_TX_DN<15>   @S9S_MB_2U_LIB.S9S_MB_2U(SCH_1):P5E_CPU1_PE0_TX_DN<15>
  C806     2      2  Q_CAP_DIFFBUS  I352
  U1     N13  PE0_TX_DN0  SOCKET4677_AZIFS054P001C01  I80

P5E_CPU1_PE0_TX_DP<0>   @S9S_MB_2U_LIB.S9S_MB_2U(SCH_1):P5E_CPU1_PE0_TX_DP<0>
  C837     2      2  Q_CAP_DIFFBUS  I396
  U1     BC15  PE0_TX_DP15  SOCKET4677_AZIFS054P001C01  I80

P5E_CPU1_PE0_TX_DP<1>   @S9S_MB_2U_LIB.S9S_MB_2U(SCH_1):P5E_CPU1_PE0_TX_DP<1>
  C835     2      2  Q_CAP_DIFFBUS  I394
  U1     AY14  PE0_TX_DP14  SOCKET4677_AZIFS054P001C01  I80

P5E_CPU1_PE0_TX_DP<2>   @S9S_MB_2U_LIB.S9S_MB_2U(SCH_1):P5E_CPU1_PE0_TX_DP<2>
  C833     2      2  Q_CAP_DIFFBUS  I391
  U1     AW15  PE0_TX_DP13  SOCKET4677_AZIFS054P001C01  I80

P5E_CPU1_PE0_TX_DP<3>   @S9S_MB_2U_LIB.S9S_MB_2U(SCH_1):P5E_CPU1_PE0_TX_DP<3>
  C831     2      2  Q_CAP_DIFFBUS  I314
  U1     AT14  PE0_TX_DP12  SOCKET4677_AZIFS054P001C01  I80

P5E_CPU1_PE0_TX_DP<4>   @S9S_MB_2U_LIB.S9S_MB_2U(SCH_1):P5E_CPU1_PE0_TX_DP<4>
  C829     2      2  Q_CAP_DIFFBUS  I389
  U1     AR15  PE0_TX_DP11  SOCKET4677_AZIFS054P001C01  I80

P5E_CPU1_PE0_TX_DP<5>   @S9S_MB_2U_LIB.S9S_MB_2U(SCH_1):P5E_CPU1_PE0_TX_DP<5>
  C827     2      2  Q_CAP_DIFFBUS  I387
  U1     AM14  PE0_TX_DP10  SOCKET4677_AZIFS054P001C01  I80

P5E_CPU1_PE0_TX_DP<6>   @S9S_MB_2U_LIB.S9S_MB_2U(SCH_1):P5E_CPU1_PE0_TX_DP<6>
  C825     2      2  Q_CAP_DIFFBUS  I384
  U1     AL15  PE0_TX_DP9  SOCKET4677_AZIFS054P001C01  I80

P5E_CPU1_PE0_TX_DP<7>   @S9S_MB_2U_LIB.S9S_MB_2U(SCH_1):P5E_CPU1_PE0_TX_DP<7>
  C823     2      2  Q_CAP_DIFFBUS  I383
  U1     AH14  PE0_TX_DP8  SOCKET4677_AZIFS054P001C01  I80

P5E_CPU1_PE0_TX_DP<8>   @S9S_MB_2U_LIB.S9S_MB_2U(SCH_1):P5E_CPU1_PE0_TX_DP<8>
  C821     2      2  Q_CAP_DIFFBUS  I365
  U1     AG15  PE0_TX_DP7  SOCKET4677_AZIFS054P001C01  I80

P5E_CPU1_PE0_TX_DP<9>   @S9S_MB_2U_LIB.S9S_MB_2U(SCH_1):P5E_CPU1_PE0_TX_DP<9>
  C819     2      2  Q_CAP_DIFFBUS  I363
  U1     AD14  PE0_TX_DP6  SOCKET4677_AZIFS054P001C01  I80

P5E_CPU1_PE0_TX_DP<10>   @S9S_MB_2U_LIB.S9S_MB_2U(SCH_1):P5E_CPU1_PE0_TX_DP<10>
  C817     2      2  Q_CAP_DIFFBUS  I362
  U1     AC15  PE0_TX_DP5  SOCKET4677_AZIFS054P001C01  I80

P5E_CPU1_PE0_TX_DP<11>   @S9S_MB_2U_LIB.S9S_MB_2U(SCH_1):P5E_CPU1_PE0_TX_DP<11>
  C815     2      2  Q_CAP_DIFFBUS  I360
  U1     Y14  PE0_TX_DP4  SOCKET4677_AZIFS054P001C01  I80

P5E_CPU1_PE0_TX_DP<12>   @S9S_MB_2U_LIB.S9S_MB_2U(SCH_1):P5E_CPU1_PE0_TX_DP<12>
  C813     2      2  Q_CAP_DIFFBUS  I358
  U1     W15  PE0_TX_DP3  SOCKET4677_AZIFS054P001C01  I80

P5E_CPU1_PE0_TX_DP<13>   @S9S_MB_2U_LIB.S9S_MB_2U(SCH_1):P5E_CPU1_PE0_TX_DP<13>
  C811     2      2  Q_CAP_DIFFBUS  I356
  U1     T14  PE0_TX_DP2  SOCKET4677_AZIFS054P001C01  I80

P5E_CPU1_PE0_TX_DP<14>   @S9S_MB_2U_LIB.S9S_MB_2U(SCH_1):P5E_CPU1_PE0_TX_DP<14>
  C809     2      2  Q_CAP_DIFFBUS  I354
  U1     R15  PE0_TX_DP1  SOCKET4677_AZIFS054P001C01  I80

P5E_CPU1_PE0_TX_DP<15>   @S9S_MB_2U_LIB.S9S_MB_2U(SCH_1):P5E_CPU1_PE0_TX_DP<15>
  C807     2      2  Q_CAP_DIFFBUS  I351
  U1     M14  PE0_TX_DP0  SOCKET4677_AZIFS054P001C01  I80

P5E_CPU1_PE1_RX_DN<0>   @S9S_MB_2U_LIB.S9S_MB_2U(SCH_1):P5E_CPU1_PE1_RX_DN<0>
  J57    B66  SIGNAL_B66  SCONN140_G64V3431BHR  I242
  U1     BC11  PE1_RX_DN15  SOCKET4677_AZIFS054P001C01  I69

P5E_CPU1_PE1_RX_DN<1>   @S9S_MB_2U_LIB.S9S_MB_2U(SCH_1):P5E_CPU1_PE1_RX_DN<1>
  J57    B63  SIGNAL_B63  SCONN140_G64V3431BHR  I242
  U1     BF10  PE1_RX_DN14  SOCKET4677_AZIFS054P001C01  I69

P5E_CPU1_PE1_RX_DN<2>   @S9S_MB_2U_LIB.S9S_MB_2U(SCH_1):P5E_CPU1_PE1_RX_DN<2>
  J57    B60  SIGNAL_B60  SCONN140_G64V3431BHR  I242
  U1     BG11  PE1_RX_DN13  SOCKET4677_AZIFS054P001C01  I69

P5E_CPU1_PE1_RX_DN<3>   @S9S_MB_2U_LIB.S9S_MB_2U(SCH_1):P5E_CPU1_PE1_RX_DN<3>
  J57    B57  SIGNAL_B57  SCONN140_G64V3431BHR  I242
  U1     BK10  PE1_RX_DN12  SOCKET4677_AZIFS054P001C01  I69

P5E_CPU1_PE1_RX_DN<4>   @S9S_MB_2U_LIB.S9S_MB_2U(SCH_1):P5E_CPU1_PE1_RX_DN<4>
  J57    B54  SIGNAL_B54  SCONN140_G64V3431BHR  I242
  U1     BL11  PE1_RX_DN11  SOCKET4677_AZIFS054P001C01  I69

P5E_CPU1_PE1_RX_DN<5>   @S9S_MB_2U_LIB.S9S_MB_2U(SCH_1):P5E_CPU1_PE1_RX_DN<5>
  J57    B51  SIGNAL_B51  SCONN140_G64V3431BHR  I242
  U1     BP10  PE1_RX_DN10  SOCKET4677_AZIFS054P001C01  I69

P5E_CPU1_PE1_RX_DN<6>   @S9S_MB_2U_LIB.S9S_MB_2U(SCH_1):P5E_CPU1_PE1_RX_DN<6>
  J57    B48  SIGNAL_B48  SCONN140_G64V3431BHR  I242
  U1     BR11  PE1_RX_DN9  SOCKET4677_AZIFS054P001C01  I69

P5E_CPU1_PE1_RX_DN<7>   @S9S_MB_2U_LIB.S9S_MB_2U(SCH_1):P5E_CPU1_PE1_RX_DN<7>
  J57    B45  SIGNAL_B45  SCONN140_G64V3431BHR  I242
  U1     BV10  PE1_RX_DN8  SOCKET4677_AZIFS054P001C01  I69

P5E_CPU1_PE1_RX_DN<8>   @S9S_MB_2U_LIB.S9S_MB_2U(SCH_1):P5E_CPU1_PE1_RX_DN<8>
  J57    B40  SIGNAL_B40  SCONN140_G64V3431BHR  I242
  U1     BW11  PE1_RX_DN7  SOCKET4677_AZIFS054P001C01  I69

P5E_CPU1_PE1_RX_DN<9>   @S9S_MB_2U_LIB.S9S_MB_2U(SCH_1):P5E_CPU1_PE1_RX_DN<9>
  J57    B37  SIGNAL_B37  SCONN140_G64V3431BHR  I242
  U1     CB10  PE1_RX_DN6  SOCKET4677_AZIFS054P001C01  I69

P5E_CPU1_PE1_RX_DN<10>   @S9S_MB_2U_LIB.S9S_MB_2U(SCH_1):P5E_CPU1_PE1_RX_DN<10>
  J57    B34  SIGNAL_B34  SCONN140_G64V3431BHR  I242
  U1     CC11  PE1_RX_DN5  SOCKET4677_AZIFS054P001C01  I69

P5E_CPU1_PE1_RX_DN<11>   @S9S_MB_2U_LIB.S9S_MB_2U(SCH_1):P5E_CPU1_PE1_RX_DN<11>
  J57    B31  SIGNAL_B31  SCONN140_G64V3431BHR  I242
  U1     CF10  PE1_RX_DN4  SOCKET4677_AZIFS054P001C01  I69

P5E_CPU1_PE1_RX_DN<12>   @S9S_MB_2U_LIB.S9S_MB_2U(SCH_1):P5E_CPU1_PE1_RX_DN<12>
  J57    B27  SIGNAL_B27  SCONN140_G64V3431BHR  I242
  U1     CG11  PE1_RX_DN3  SOCKET4677_AZIFS054P001C01  I69

P5E_CPU1_PE1_RX_DN<13>   @S9S_MB_2U_LIB.S9S_MB_2U(SCH_1):P5E_CPU1_PE1_RX_DN<13>
  J57    B24  SIGNAL_B24  SCONN140_G64V3431BHR  I242
  U1     CK10  PE1_RX_DN2  SOCKET4677_AZIFS054P001C01  I69

P5E_CPU1_PE1_RX_DN<14>   @S9S_MB_2U_LIB.S9S_MB_2U(SCH_1):P5E_CPU1_PE1_RX_DN<14>
  J57    B21  SIGNAL_B21  SCONN140_G64V3431BHR  I242
  U1     CL11  PE1_RX_DN1  SOCKET4677_AZIFS054P001C01  I69

P5E_CPU1_PE1_RX_DN<15>   @S9S_MB_2U_LIB.S9S_MB_2U(SCH_1):P5E_CPU1_PE1_RX_DN<15>
  J57    B18  SIGNAL_B18  SCONN140_G64V3431BHR  I242
  U1     CP10  PE1_RX_DN0  SOCKET4677_AZIFS054P001C01  I69

P5E_CPU1_PE1_RX_DP<0>   @S9S_MB_2U_LIB.S9S_MB_2U(SCH_1):P5E_CPU1_PE1_RX_DP<0>
  J57    B65  SIGNAL_B65  SCONN140_G64V3431BHR  I242
  U1     BD10  PE1_RX_DP15  SOCKET4677_AZIFS054P001C01  I69

P5E_CPU1_PE1_RX_DP<1>   @S9S_MB_2U_LIB.S9S_MB_2U(SCH_1):P5E_CPU1_PE1_RX_DP<1>
  J57    B62  SIGNAL_B62  SCONN140_G64V3431BHR  I242
  U1     BE9  PE1_RX_DP14  SOCKET4677_AZIFS054P001C01  I69

P5E_CPU1_PE1_RX_DP<2>   @S9S_MB_2U_LIB.S9S_MB_2U(SCH_1):P5E_CPU1_PE1_RX_DP<2>
  J57    B59  SIGNAL_B59  SCONN140_G64V3431BHR  I242
  U1     BH10  PE1_RX_DP13  SOCKET4677_AZIFS054P001C01  I69

P5E_CPU1_PE1_RX_DP<3>   @S9S_MB_2U_LIB.S9S_MB_2U(SCH_1):P5E_CPU1_PE1_RX_DP<3>
  J57    B56  SIGNAL_B56  SCONN140_G64V3431BHR  I242
  U1     BJ9  PE1_RX_DP12  SOCKET4677_AZIFS054P001C01  I69

P5E_CPU1_PE1_RX_DP<4>   @S9S_MB_2U_LIB.S9S_MB_2U(SCH_1):P5E_CPU1_PE1_RX_DP<4>
  J57    B53  SIGNAL_B53  SCONN140_G64V3431BHR  I242
  U1     BM10  PE1_RX_DP11  SOCKET4677_AZIFS054P001C01  I69

P5E_CPU1_PE1_RX_DP<5>   @S9S_MB_2U_LIB.S9S_MB_2U(SCH_1):P5E_CPU1_PE1_RX_DP<5>
  J57    B50  SIGNAL_B50  SCONN140_G64V3431BHR  I242
  U1     BN9  PE1_RX_DP10  SOCKET4677_AZIFS054P001C01  I69

P5E_CPU1_PE1_RX_DP<6>   @S9S_MB_2U_LIB.S9S_MB_2U(SCH_1):P5E_CPU1_PE1_RX_DP<6>
  J57    B47  SIGNAL_B47  SCONN140_G64V3431BHR  I242
  U1     BT10  PE1_RX_DP9  SOCKET4677_AZIFS054P001C01  I69

P5E_CPU1_PE1_RX_DP<7>   @S9S_MB_2U_LIB.S9S_MB_2U(SCH_1):P5E_CPU1_PE1_RX_DP<7>
  J57    B44  SIGNAL_B44  SCONN140_G64V3431BHR  I242
  U1     BU9  PE1_RX_DP8  SOCKET4677_AZIFS054P001C01  I69

P5E_CPU1_PE1_RX_DP<8>   @S9S_MB_2U_LIB.S9S_MB_2U(SCH_1):P5E_CPU1_PE1_RX_DP<8>
  J57    B39  SIGNAL_B39  SCONN140_G64V3431BHR  I242
  U1     BY10  PE1_RX_DP7  SOCKET4677_AZIFS054P001C01  I69

P5E_CPU1_PE1_RX_DP<9>   @S9S_MB_2U_LIB.S9S_MB_2U(SCH_1):P5E_CPU1_PE1_RX_DP<9>
  J57    B36  SIGNAL_B36  SCONN140_G64V3431BHR  I242
  U1     CA9  PE1_RX_DP6  SOCKET4677_AZIFS054P001C01  I69

P5E_CPU1_PE1_RX_DP<10>   @S9S_MB_2U_LIB.S9S_MB_2U(SCH_1):P5E_CPU1_PE1_RX_DP<10>
  J57    B33  SIGNAL_B33  SCONN140_G64V3431BHR  I242
  U1     CD10  PE1_RX_DP5  SOCKET4677_AZIFS054P001C01  I69

P5E_CPU1_PE1_RX_DP<11>   @S9S_MB_2U_LIB.S9S_MB_2U(SCH_1):P5E_CPU1_PE1_RX_DP<11>
  J57    B30  SIGNAL_B30  SCONN140_G64V3431BHR  I242
  U1     CE9  PE1_RX_DP4  SOCKET4677_AZIFS054P001C01  I69

P5E_CPU1_PE1_RX_DP<12>   @S9S_MB_2U_LIB.S9S_MB_2U(SCH_1):P5E_CPU1_PE1_RX_DP<12>
  J57    B26  SIGNAL_B26  SCONN140_G64V3431BHR  I242
  U1     CH10  PE1_RX_DP3  SOCKET4677_AZIFS054P001C01  I69

P5E_CPU1_PE1_RX_DP<13>   @S9S_MB_2U_LIB.S9S_MB_2U(SCH_1):P5E_CPU1_PE1_RX_DP<13>
  J57    B23  SIGNAL_B23  SCONN140_G64V3431BHR  I242
  U1     CJ9  PE1_RX_DP2  SOCKET4677_AZIFS054P001C01  I69

P5E_CPU1_PE1_RX_DP<14>   @S9S_MB_2U_LIB.S9S_MB_2U(SCH_1):P5E_CPU1_PE1_RX_DP<14>
  J57    B20  SIGNAL_B20  SCONN140_G64V3431BHR  I242
  U1     CM10  PE1_RX_DP1  SOCKET4677_AZIFS054P001C01  I69

P5E_CPU1_PE1_RX_DP<15>   @S9S_MB_2U_LIB.S9S_MB_2U(SCH_1):P5E_CPU1_PE1_RX_DP<15>
  J57    B17  SIGNAL_B17  SCONN140_G64V3431BHR  I242
  U1     CN9  PE1_RX_DP0  SOCKET4677_AZIFS054P001C01  I69

P5E_CPU1_PE1_TX_C_DN<0>   @S9S_MB_2U_LIB.S9S_MB_2U(SCH_1):P5E_CPU1_PE1_TX_C_DN<0>
  C740     1      1  Q_CAP_DIFFBUS  I22
  J57    A66  SIGNAL_A66  SCONN140_G64V3431BHR  I242

P5E_CPU1_PE1_TX_C_DN<1>   @S9S_MB_2U_LIB.S9S_MB_2U(SCH_1):P5E_CPU1_PE1_TX_C_DN<1>
  C738     1      1  Q_CAP_DIFFBUS  I23
  J57    A63  SIGNAL_A63  SCONN140_G64V3431BHR  I242

P5E_CPU1_PE1_TX_C_DN<2>   @S9S_MB_2U_LIB.S9S_MB_2U(SCH_1):P5E_CPU1_PE1_TX_C_DN<2>
  C736     1      1  Q_CAP_DIFFBUS  I27
  J57    A60  SIGNAL_A60  SCONN140_G64V3431BHR  I242

P5E_CPU1_PE1_TX_C_DN<3>   @S9S_MB_2U_LIB.S9S_MB_2U(SCH_1):P5E_CPU1_PE1_TX_C_DN<3>
  C734     1      1  Q_CAP_DIFFBUS  I30
  J57    A57  SIGNAL_A57  SCONN140_G64V3431BHR  I242

P5E_CPU1_PE1_TX_C_DN<4>   @S9S_MB_2U_LIB.S9S_MB_2U(SCH_1):P5E_CPU1_PE1_TX_C_DN<4>
  C732     1      1  Q_CAP_DIFFBUS  I28
  J57    A54  SIGNAL_A54  SCONN140_G64V3431BHR  I242

P5E_CPU1_PE1_TX_C_DN<5>   @S9S_MB_2U_LIB.S9S_MB_2U(SCH_1):P5E_CPU1_PE1_TX_C_DN<5>
  C730     1      1  Q_CAP_DIFFBUS  I36
  J57    A51  SIGNAL_A51  SCONN140_G64V3431BHR  I242

P5E_CPU1_PE1_TX_C_DN<6>   @S9S_MB_2U_LIB.S9S_MB_2U(SCH_1):P5E_CPU1_PE1_TX_C_DN<6>
  C728     1      1  Q_CAP_DIFFBUS  I38
  J57    A48  SIGNAL_A48  SCONN140_G64V3431BHR  I242

P5E_CPU1_PE1_TX_C_DN<7>   @S9S_MB_2U_LIB.S9S_MB_2U(SCH_1):P5E_CPU1_PE1_TX_C_DN<7>
  C726     1      1  Q_CAP_DIFFBUS  I41
  J57    A45  SIGNAL_A45  SCONN140_G64V3431BHR  I242

P5E_CPU1_PE1_TX_C_DN<8>   @S9S_MB_2U_LIB.S9S_MB_2U(SCH_1):P5E_CPU1_PE1_TX_C_DN<8>
  C724     1      1  Q_CAP_DIFFBUS  I62
  J57    A40  SIGNAL_A40  SCONN140_G64V3431BHR  I242

P5E_CPU1_PE1_TX_C_DN<9>   @S9S_MB_2U_LIB.S9S_MB_2U(SCH_1):P5E_CPU1_PE1_TX_C_DN<9>
  C722     1      1  Q_CAP_DIFFBUS  I65
  J57    A37  SIGNAL_A37  SCONN140_G64V3431BHR  I242

P5E_CPU1_PE1_TX_C_DN<10>   @S9S_MB_2U_LIB.S9S_MB_2U(SCH_1):P5E_CPU1_PE1_TX_C_DN<10>
  C720     1      1  Q_CAP_DIFFBUS  I66
  J57    A34  SIGNAL_A34  SCONN140_G64V3431BHR  I242

P5E_CPU1_PE1_TX_C_DN<11>   @S9S_MB_2U_LIB.S9S_MB_2U(SCH_1):P5E_CPU1_PE1_TX_C_DN<11>
  C718     1      1  Q_CAP_DIFFBUS  I67
  J57    A31  SIGNAL_A31  SCONN140_G64V3431BHR  I242

P5E_CPU1_PE1_TX_C_DN<12>   @S9S_MB_2U_LIB.S9S_MB_2U(SCH_1):P5E_CPU1_PE1_TX_C_DN<12>
  C716     1      1  Q_CAP_DIFFBUS  I69
  J57    A27  SIGNAL_A27  SCONN140_G64V3431BHR  I242

P5E_CPU1_PE1_TX_C_DN<13>   @S9S_MB_2U_LIB.S9S_MB_2U(SCH_1):P5E_CPU1_PE1_TX_C_DN<13>
  C714     1      1  Q_CAP_DIFFBUS  I78
  J57    A24  SIGNAL_A24  SCONN140_G64V3431BHR  I242

P5E_CPU1_PE1_TX_C_DN<14>   @S9S_MB_2U_LIB.S9S_MB_2U(SCH_1):P5E_CPU1_PE1_TX_C_DN<14>
  C712     1      1  Q_CAP_DIFFBUS  I81
  J57    A21  SIGNAL_A21  SCONN140_G64V3431BHR  I242

P5E_CPU1_PE1_TX_C_DN<15>   @S9S_MB_2U_LIB.S9S_MB_2U(SCH_1):P5E_CPU1_PE1_TX_C_DN<15>
  C710     1      1  Q_CAP_DIFFBUS  I80
  J57    A18  SIGNAL_A18  SCONN140_G64V3431BHR  I242

P5E_CPU1_PE1_TX_C_DP<0>   @S9S_MB_2U_LIB.S9S_MB_2U(SCH_1):P5E_CPU1_PE1_TX_C_DP<0>
  C741     1      1  Q_CAP_DIFFBUS  I21
  J57    A65  SIGNAL_A65  SCONN140_G64V3431BHR  I242

P5E_CPU1_PE1_TX_C_DP<1>   @S9S_MB_2U_LIB.S9S_MB_2U(SCH_1):P5E_CPU1_PE1_TX_C_DP<1>
  C739     1      1  Q_CAP_DIFFBUS  I24
  J57    A62  SIGNAL_A62  SCONN140_G64V3431BHR  I242

P5E_CPU1_PE1_TX_C_DP<2>   @S9S_MB_2U_LIB.S9S_MB_2U(SCH_1):P5E_CPU1_PE1_TX_C_DP<2>
  C737     1      1  Q_CAP_DIFFBUS  I25
  J57    A59  SIGNAL_A59  SCONN140_G64V3431BHR  I242

P5E_CPU1_PE1_TX_C_DP<3>   @S9S_MB_2U_LIB.S9S_MB_2U(SCH_1):P5E_CPU1_PE1_TX_C_DP<3>
  C735     1      1  Q_CAP_DIFFBUS  I26
  J57    A56  SIGNAL_A56  SCONN140_G64V3431BHR  I242

P5E_CPU1_PE1_TX_C_DP<4>   @S9S_MB_2U_LIB.S9S_MB_2U(SCH_1):P5E_CPU1_PE1_TX_C_DP<4>
  C733     1      1  Q_CAP_DIFFBUS  I29
  J57    A53  SIGNAL_A53  SCONN140_G64V3431BHR  I242

P5E_CPU1_PE1_TX_C_DP<5>   @S9S_MB_2U_LIB.S9S_MB_2U(SCH_1):P5E_CPU1_PE1_TX_C_DP<5>
  C731     1      1  Q_CAP_DIFFBUS  I37
  J57    A50  SIGNAL_A50  SCONN140_G64V3431BHR  I242

P5E_CPU1_PE1_TX_C_DP<6>   @S9S_MB_2U_LIB.S9S_MB_2U(SCH_1):P5E_CPU1_PE1_TX_C_DP<6>
  C729     1      1  Q_CAP_DIFFBUS  I39
  J57    A47  SIGNAL_A47  SCONN140_G64V3431BHR  I242

P5E_CPU1_PE1_TX_C_DP<7>   @S9S_MB_2U_LIB.S9S_MB_2U(SCH_1):P5E_CPU1_PE1_TX_C_DP<7>
  C727     1      1  Q_CAP_DIFFBUS  I40
  J57    A44  SIGNAL_A44  SCONN140_G64V3431BHR  I242

P5E_CPU1_PE1_TX_C_DP<8>   @S9S_MB_2U_LIB.S9S_MB_2U(SCH_1):P5E_CPU1_PE1_TX_C_DP<8>
  C725     1      1  Q_CAP_DIFFBUS  I61
  J57    A39  SIGNAL_A39  SCONN140_G64V3431BHR  I242

P5E_CPU1_PE1_TX_C_DP<9>   @S9S_MB_2U_LIB.S9S_MB_2U(SCH_1):P5E_CPU1_PE1_TX_C_DP<9>
  C723     1      1  Q_CAP_DIFFBUS  I63
  J57    A36  SIGNAL_A36  SCONN140_G64V3431BHR  I242

P5E_CPU1_PE1_TX_C_DP<10>   @S9S_MB_2U_LIB.S9S_MB_2U(SCH_1):P5E_CPU1_PE1_TX_C_DP<10>
  C721     1      1  Q_CAP_DIFFBUS  I64
  J57    A33  SIGNAL_A33  SCONN140_G64V3431BHR  I242

P5E_CPU1_PE1_TX_C_DP<11>   @S9S_MB_2U_LIB.S9S_MB_2U(SCH_1):P5E_CPU1_PE1_TX_C_DP<11>
  C719     1      1  Q_CAP_DIFFBUS  I68
  J57    A30  SIGNAL_A30  SCONN140_G64V3431BHR  I242

P5E_CPU1_PE1_TX_C_DP<12>   @S9S_MB_2U_LIB.S9S_MB_2U(SCH_1):P5E_CPU1_PE1_TX_C_DP<12>
  C717     1      1  Q_CAP_DIFFBUS  I70
  J57    A26  SIGNAL_A26  SCONN140_G64V3431BHR  I242

P5E_CPU1_PE1_TX_C_DP<13>   @S9S_MB_2U_LIB.S9S_MB_2U(SCH_1):P5E_CPU1_PE1_TX_C_DP<13>
  C715     1      1  Q_CAP_DIFFBUS  I76
  J57    A23  SIGNAL_A23  SCONN140_G64V3431BHR  I242

P5E_CPU1_PE1_TX_C_DP<14>   @S9S_MB_2U_LIB.S9S_MB_2U(SCH_1):P5E_CPU1_PE1_TX_C_DP<14>
  C713     1      1  Q_CAP_DIFFBUS  I77
  J57    A20  SIGNAL_A20  SCONN140_G64V3431BHR  I242

P5E_CPU1_PE1_TX_C_DP<15>   @S9S_MB_2U_LIB.S9S_MB_2U(SCH_1):P5E_CPU1_PE1_TX_C_DP<15>
  C711     1      1  Q_CAP_DIFFBUS  I79
  J57    A17  SIGNAL_A17  SCONN140_G64V3431BHR  I242

P5E_CPU1_PE1_TX_DN<0>   @S9S_MB_2U_LIB.S9S_MB_2U(SCH_1):P5E_CPU1_PE1_TX_DN<0>
  C740     2      2  Q_CAP_DIFFBUS  I22
  U1     BE13  PE1_TX_DN15  SOCKET4677_AZIFS054P001C01  I69

P5E_CPU1_PE1_TX_DN<1>   @S9S_MB_2U_LIB.S9S_MB_2U(SCH_1):P5E_CPU1_PE1_TX_DN<1>
  C738     2      2  Q_CAP_DIFFBUS  I23
  U1     BF14  PE1_TX_DN14  SOCKET4677_AZIFS054P001C01  I69

P5E_CPU1_PE1_TX_DN<2>   @S9S_MB_2U_LIB.S9S_MB_2U(SCH_1):P5E_CPU1_PE1_TX_DN<2>
  C736     2      2  Q_CAP_DIFFBUS  I27
  U1     BJ13  PE1_TX_DN13  SOCKET4677_AZIFS054P001C01  I69

P5E_CPU1_PE1_TX_DN<3>   @S9S_MB_2U_LIB.S9S_MB_2U(SCH_1):P5E_CPU1_PE1_TX_DN<3>
  C734     2      2  Q_CAP_DIFFBUS  I30
  U1     BK14  PE1_TX_DN12  SOCKET4677_AZIFS054P001C01  I69

P5E_CPU1_PE1_TX_DN<4>   @S9S_MB_2U_LIB.S9S_MB_2U(SCH_1):P5E_CPU1_PE1_TX_DN<4>
  C732     2      2  Q_CAP_DIFFBUS  I28
  U1     BN13  PE1_TX_DN11  SOCKET4677_AZIFS054P001C01  I69

P5E_CPU1_PE1_TX_DN<5>   @S9S_MB_2U_LIB.S9S_MB_2U(SCH_1):P5E_CPU1_PE1_TX_DN<5>
  C730     2      2  Q_CAP_DIFFBUS  I36
  U1     BP14  PE1_TX_DN10  SOCKET4677_AZIFS054P001C01  I69

P5E_CPU1_PE1_TX_DN<6>   @S9S_MB_2U_LIB.S9S_MB_2U(SCH_1):P5E_CPU1_PE1_TX_DN<6>
  C728     2      2  Q_CAP_DIFFBUS  I38
  U1     BU13  PE1_TX_DN9  SOCKET4677_AZIFS054P001C01  I69

P5E_CPU1_PE1_TX_DN<7>   @S9S_MB_2U_LIB.S9S_MB_2U(SCH_1):P5E_CPU1_PE1_TX_DN<7>
  C726     2      2  Q_CAP_DIFFBUS  I41
  U1     BV14  PE1_TX_DN8  SOCKET4677_AZIFS054P001C01  I69

P5E_CPU1_PE1_TX_DN<8>   @S9S_MB_2U_LIB.S9S_MB_2U(SCH_1):P5E_CPU1_PE1_TX_DN<8>
  C724     2      2  Q_CAP_DIFFBUS  I62
  U1     CA13  PE1_TX_DN7  SOCKET4677_AZIFS054P001C01  I69

P5E_CPU1_PE1_TX_DN<9>   @S9S_MB_2U_LIB.S9S_MB_2U(SCH_1):P5E_CPU1_PE1_TX_DN<9>
  C722     2      2  Q_CAP_DIFFBUS  I65
  U1     CB14  PE1_TX_DN6  SOCKET4677_AZIFS054P001C01  I69

P5E_CPU1_PE1_TX_DN<10>   @S9S_MB_2U_LIB.S9S_MB_2U(SCH_1):P5E_CPU1_PE1_TX_DN<10>
  C720     2      2  Q_CAP_DIFFBUS  I66
  U1     CE13  PE1_TX_DN5  SOCKET4677_AZIFS054P001C01  I69

P5E_CPU1_PE1_TX_DN<11>   @S9S_MB_2U_LIB.S9S_MB_2U(SCH_1):P5E_CPU1_PE1_TX_DN<11>
  C718     2      2  Q_CAP_DIFFBUS  I67
  U1     CF14  PE1_TX_DN4  SOCKET4677_AZIFS054P001C01  I69

P5E_CPU1_PE1_TX_DN<12>   @S9S_MB_2U_LIB.S9S_MB_2U(SCH_1):P5E_CPU1_PE1_TX_DN<12>
  C716     2      2  Q_CAP_DIFFBUS  I69
  U1     CJ13  PE1_TX_DN3  SOCKET4677_AZIFS054P001C01  I69

P5E_CPU1_PE1_TX_DN<13>   @S9S_MB_2U_LIB.S9S_MB_2U(SCH_1):P5E_CPU1_PE1_TX_DN<13>
  C714     2      2  Q_CAP_DIFFBUS  I78
  U1     CK14  PE1_TX_DN2  SOCKET4677_AZIFS054P001C01  I69

P5E_CPU1_PE1_TX_DN<14>   @S9S_MB_2U_LIB.S9S_MB_2U(SCH_1):P5E_CPU1_PE1_TX_DN<14>
  C712     2      2  Q_CAP_DIFFBUS  I81
  U1     CN13  PE1_TX_DN1  SOCKET4677_AZIFS054P001C01  I69

P5E_CPU1_PE1_TX_DN<15>   @S9S_MB_2U_LIB.S9S_MB_2U(SCH_1):P5E_CPU1_PE1_TX_DN<15>
  C710     2      2  Q_CAP_DIFFBUS  I80
  U1     CP14  PE1_TX_DN0  SOCKET4677_AZIFS054P001C01  I69

P5E_CPU1_PE1_TX_DP<0>   @S9S_MB_2U_LIB.S9S_MB_2U(SCH_1):P5E_CPU1_PE1_TX_DP<0>
  C741     2      2  Q_CAP_DIFFBUS  I21
  U1     BD14  PE1_TX_DP15  SOCKET4677_AZIFS054P001C01  I69

P5E_CPU1_PE1_TX_DP<1>   @S9S_MB_2U_LIB.S9S_MB_2U(SCH_1):P5E_CPU1_PE1_TX_DP<1>
  C739     2      2  Q_CAP_DIFFBUS  I24
  U1     BG15  PE1_TX_DP14  SOCKET4677_AZIFS054P001C01  I69

P5E_CPU1_PE1_TX_DP<2>   @S9S_MB_2U_LIB.S9S_MB_2U(SCH_1):P5E_CPU1_PE1_TX_DP<2>
  C737     2      2  Q_CAP_DIFFBUS  I25
  U1     BH14  PE1_TX_DP13  SOCKET4677_AZIFS054P001C01  I69

P5E_CPU1_PE1_TX_DP<3>   @S9S_MB_2U_LIB.S9S_MB_2U(SCH_1):P5E_CPU1_PE1_TX_DP<3>
  C735     2      2  Q_CAP_DIFFBUS  I26
  U1     BL15  PE1_TX_DP12  SOCKET4677_AZIFS054P001C01  I69

P5E_CPU1_PE1_TX_DP<4>   @S9S_MB_2U_LIB.S9S_MB_2U(SCH_1):P5E_CPU1_PE1_TX_DP<4>
  C733     2      2  Q_CAP_DIFFBUS  I29
  U1     BM14  PE1_TX_DP11  SOCKET4677_AZIFS054P001C01  I69

P5E_CPU1_PE1_TX_DP<5>   @S9S_MB_2U_LIB.S9S_MB_2U(SCH_1):P5E_CPU1_PE1_TX_DP<5>
  C731     2      2  Q_CAP_DIFFBUS  I37
  U1     BR15  PE1_TX_DP10  SOCKET4677_AZIFS054P001C01  I69

P5E_CPU1_PE1_TX_DP<6>   @S9S_MB_2U_LIB.S9S_MB_2U(SCH_1):P5E_CPU1_PE1_TX_DP<6>
  C729     2      2  Q_CAP_DIFFBUS  I39
  U1     BT14  PE1_TX_DP9  SOCKET4677_AZIFS054P001C01  I69

P5E_CPU1_PE1_TX_DP<7>   @S9S_MB_2U_LIB.S9S_MB_2U(SCH_1):P5E_CPU1_PE1_TX_DP<7>
  C727     2      2  Q_CAP_DIFFBUS  I40
  U1     BW15  PE1_TX_DP8  SOCKET4677_AZIFS054P001C01  I69

P5E_CPU1_PE1_TX_DP<8>   @S9S_MB_2U_LIB.S9S_MB_2U(SCH_1):P5E_CPU1_PE1_TX_DP<8>
  C725     2      2  Q_CAP_DIFFBUS  I61
  U1     BY14  PE1_TX_DP7  SOCKET4677_AZIFS054P001C01  I69

P5E_CPU1_PE1_TX_DP<9>   @S9S_MB_2U_LIB.S9S_MB_2U(SCH_1):P5E_CPU1_PE1_TX_DP<9>
  C723     2      2  Q_CAP_DIFFBUS  I63
  U1     CC15  PE1_TX_DP6  SOCKET4677_AZIFS054P001C01  I69

P5E_CPU1_PE1_TX_DP<10>   @S9S_MB_2U_LIB.S9S_MB_2U(SCH_1):P5E_CPU1_PE1_TX_DP<10>
  C721     2      2  Q_CAP_DIFFBUS  I64
  U1     CD14  PE1_TX_DP5  SOCKET4677_AZIFS054P001C01  I69

P5E_CPU1_PE1_TX_DP<11>   @S9S_MB_2U_LIB.S9S_MB_2U(SCH_1):P5E_CPU1_PE1_TX_DP<11>
  C719     2      2  Q_CAP_DIFFBUS  I68
  U1     CG15  PE1_TX_DP4  SOCKET4677_AZIFS054P001C01  I69

P5E_CPU1_PE1_TX_DP<12>   @S9S_MB_2U_LIB.S9S_MB_2U(SCH_1):P5E_CPU1_PE1_TX_DP<12>
  C717     2      2  Q_CAP_DIFFBUS  I70
  U1     CH14  PE1_TX_DP3  SOCKET4677_AZIFS054P001C01  I69

P5E_CPU1_PE1_TX_DP<13>   @S9S_MB_2U_LIB.S9S_MB_2U(SCH_1):P5E_CPU1_PE1_TX_DP<13>
  C715     2      2  Q_CAP_DIFFBUS  I76
  U1     CL15  PE1_TX_DP2  SOCKET4677_AZIFS054P001C01  I69

P5E_CPU1_PE1_TX_DP<14>   @S9S_MB_2U_LIB.S9S_MB_2U(SCH_1):P5E_CPU1_PE1_TX_DP<14>
  C713     2      2  Q_CAP_DIFFBUS  I77
  U1     CM14  PE1_TX_DP1  SOCKET4677_AZIFS054P001C01  I69

P5E_CPU1_PE1_TX_DP<15>   @S9S_MB_2U_LIB.S9S_MB_2U(SCH_1):P5E_CPU1_PE1_TX_DP<15>
  C711     2      2  Q_CAP_DIFFBUS  I79
  U1     CR15  PE1_TX_DP0  SOCKET4677_AZIFS054P001C01  I69

P5E_CPU1_PE2_RX_DN<0>   @S9S_MB_2U_LIB.S9S_MB_2U(SCH_1):P5E_CPU1_PE2_RX_DN<0>
  J89    A133   A133  SCONN280_ME1028040102011  I282
  U1     CU9  PE2_RX_DN0  SOCKET4677_AZIFS054P001C01  I54

P5E_CPU1_PE2_RX_DN<1>   @S9S_MB_2U_LIB.S9S_MB_2U(SCH_1):P5E_CPU1_PE2_RX_DN<1>
  J89    A130   A130  SCONN280_ME1028040102011  I282
  U1     CY10  PE2_RX_DN1  SOCKET4677_AZIFS054P001C01  I54

P5E_CPU1_PE2_RX_DN<2>   @S9S_MB_2U_LIB.S9S_MB_2U(SCH_1):P5E_CPU1_PE2_RX_DN<2>
  J89    A127   A127  SCONN280_ME1028040102011  I282
  U1     DA9  PE2_RX_DN2  SOCKET4677_AZIFS054P001C01  I54

P5E_CPU1_PE2_RX_DN<3>   @S9S_MB_2U_LIB.S9S_MB_2U(SCH_1):P5E_CPU1_PE2_RX_DN<3>
  J89    A124   A124  SCONN280_ME1028040102011  I282
  U1     DD10  PE2_RX_DN3  SOCKET4677_AZIFS054P001C01  I54

P5E_CPU1_PE2_RX_DN<4>   @S9S_MB_2U_LIB.S9S_MB_2U(SCH_1):P5E_CPU1_PE2_RX_DN<4>
  J89    A121   A121  SCONN280_ME1028040102011  I282
  U1     DE9  PE2_RX_DN4  SOCKET4677_AZIFS054P001C01  I54

P5E_CPU1_PE2_RX_DN<5>   @S9S_MB_2U_LIB.S9S_MB_2U(SCH_1):P5E_CPU1_PE2_RX_DN<5>
  J89    A118   A118  SCONN280_ME1028040102011  I282
  U1     DH10  PE2_RX_DN5  SOCKET4677_AZIFS054P001C01  I54

P5E_CPU1_PE2_RX_DN<6>   @S9S_MB_2U_LIB.S9S_MB_2U(SCH_1):P5E_CPU1_PE2_RX_DN<6>
  J89    A115   A115  SCONN280_ME1028040102011  I282
  U1     DJ9  PE2_RX_DN6  SOCKET4677_AZIFS054P001C01  I54

P5E_CPU1_PE2_RX_DN<7>   @S9S_MB_2U_LIB.S9S_MB_2U(SCH_1):P5E_CPU1_PE2_RX_DN<7>
  J89    A111   A111  SCONN280_ME1028040102011  I282
  U1     DM10  PE2_RX_DN7  SOCKET4677_AZIFS054P001C01  I54

P5E_CPU1_PE2_RX_DN<8>   @S9S_MB_2U_LIB.S9S_MB_2U(SCH_1):P5E_CPU1_PE2_RX_DN<8>
  J89    A108   A108  SCONN280_ME1028040102011  I282
  U1     DN9  PE2_RX_DN8  SOCKET4677_AZIFS054P001C01  I54

P5E_CPU1_PE2_RX_DN<9>   @S9S_MB_2U_LIB.S9S_MB_2U(SCH_1):P5E_CPU1_PE2_RX_DN<9>
  J89    A105   A105  SCONN280_ME1028040102011  I282
  U1     DT10  PE2_RX_DN9  SOCKET4677_AZIFS054P001C01  I54

P5E_CPU1_PE2_RX_DN<10>   @S9S_MB_2U_LIB.S9S_MB_2U(SCH_1):P5E_CPU1_PE2_RX_DN<10>
  J89    A102   A102  SCONN280_ME1028040102011  I282
  U1     DU9  PE2_RX_DN10  SOCKET4677_AZIFS054P001C01  I54

P5E_CPU1_PE2_RX_DN<11>   @S9S_MB_2U_LIB.S9S_MB_2U(SCH_1):P5E_CPU1_PE2_RX_DN<11>
  J89    A99    A99  SCONN280_ME1028040102011  I282
  U1     DY10  PE2_RX_DN11  SOCKET4677_AZIFS054P001C01  I54

P5E_CPU1_PE2_RX_DN<12>   @S9S_MB_2U_LIB.S9S_MB_2U(SCH_1):P5E_CPU1_PE2_RX_DN<12>
  J89    A96    A96  SCONN280_ME1028040102011  I282
  U1     EA9  PE2_RX_DN12  SOCKET4677_AZIFS054P001C01  I54

P5E_CPU1_PE2_RX_DN<13>   @S9S_MB_2U_LIB.S9S_MB_2U(SCH_1):P5E_CPU1_PE2_RX_DN<13>
  J89    A93    A93  SCONN280_ME1028040102011  I282
  U1     ED10  PE2_RX_DN13  SOCKET4677_AZIFS054P001C01  I54

P5E_CPU1_PE2_RX_DN<14>   @S9S_MB_2U_LIB.S9S_MB_2U(SCH_1):P5E_CPU1_PE2_RX_DN<14>
  J89    A90    A90  SCONN280_ME1028040102011  I282
  U1     EE9  PE2_RX_DN14  SOCKET4677_AZIFS054P001C01  I54

P5E_CPU1_PE2_RX_DN<15>   @S9S_MB_2U_LIB.S9S_MB_2U(SCH_1):P5E_CPU1_PE2_RX_DN<15>
  J89    A87    A87  SCONN280_ME1028040102011  I282
  U1     EH10  PE2_RX_DN15  SOCKET4677_AZIFS054P001C01  I54

P5E_CPU1_PE2_RX_DP<0>   @S9S_MB_2U_LIB.S9S_MB_2U(SCH_1):P5E_CPU1_PE2_RX_DP<0>
  J89    A132   A132  SCONN280_ME1028040102011  I282
  U1     CV10  PE2_RX_DP0  SOCKET4677_AZIFS054P001C01  I54

P5E_CPU1_PE2_RX_DP<1>   @S9S_MB_2U_LIB.S9S_MB_2U(SCH_1):P5E_CPU1_PE2_RX_DP<1>
  J89    A129   A129  SCONN280_ME1028040102011  I282
  U1     CW11  PE2_RX_DP1  SOCKET4677_AZIFS054P001C01  I54

P5E_CPU1_PE2_RX_DP<2>   @S9S_MB_2U_LIB.S9S_MB_2U(SCH_1):P5E_CPU1_PE2_RX_DP<2>
  J89    A126   A126  SCONN280_ME1028040102011  I282
  U1     DB10  PE2_RX_DP2  SOCKET4677_AZIFS054P001C01  I54

P5E_CPU1_PE2_RX_DP<3>   @S9S_MB_2U_LIB.S9S_MB_2U(SCH_1):P5E_CPU1_PE2_RX_DP<3>
  J89    A123   A123  SCONN280_ME1028040102011  I282
  U1     DC11  PE2_RX_DP3  SOCKET4677_AZIFS054P001C01  I54

P5E_CPU1_PE2_RX_DP<4>   @S9S_MB_2U_LIB.S9S_MB_2U(SCH_1):P5E_CPU1_PE2_RX_DP<4>
  J89    A120   A120  SCONN280_ME1028040102011  I282
  U1     DF10  PE2_RX_DP4  SOCKET4677_AZIFS054P001C01  I54

P5E_CPU1_PE2_RX_DP<5>   @S9S_MB_2U_LIB.S9S_MB_2U(SCH_1):P5E_CPU1_PE2_RX_DP<5>
  J89    A117   A117  SCONN280_ME1028040102011  I282
  U1     DG11  PE2_RX_DP5  SOCKET4677_AZIFS054P001C01  I54

P5E_CPU1_PE2_RX_DP<6>   @S9S_MB_2U_LIB.S9S_MB_2U(SCH_1):P5E_CPU1_PE2_RX_DP<6>
  J89    A114   A114  SCONN280_ME1028040102011  I282
  U1     DK10  PE2_RX_DP6  SOCKET4677_AZIFS054P001C01  I54

P5E_CPU1_PE2_RX_DP<7>   @S9S_MB_2U_LIB.S9S_MB_2U(SCH_1):P5E_CPU1_PE2_RX_DP<7>
  J89    A110   A110  SCONN280_ME1028040102011  I282
  U1     DL11  PE2_RX_DP7  SOCKET4677_AZIFS054P001C01  I54

P5E_CPU1_PE2_RX_DP<8>   @S9S_MB_2U_LIB.S9S_MB_2U(SCH_1):P5E_CPU1_PE2_RX_DP<8>
  J89    A107   A107  SCONN280_ME1028040102011  I282
  U1     DP10  PE2_RX_DP8  SOCKET4677_AZIFS054P001C01  I54

P5E_CPU1_PE2_RX_DP<9>   @S9S_MB_2U_LIB.S9S_MB_2U(SCH_1):P5E_CPU1_PE2_RX_DP<9>
  J89    A104   A104  SCONN280_ME1028040102011  I282
  U1     DR11  PE2_RX_DP9  SOCKET4677_AZIFS054P001C01  I54

P5E_CPU1_PE2_RX_DP<10>   @S9S_MB_2U_LIB.S9S_MB_2U(SCH_1):P5E_CPU1_PE2_RX_DP<10>
  J89    A101   A101  SCONN280_ME1028040102011  I282
  U1     DV10  PE2_RX_DP10  SOCKET4677_AZIFS054P001C01  I54

P5E_CPU1_PE2_RX_DP<11>   @S9S_MB_2U_LIB.S9S_MB_2U(SCH_1):P5E_CPU1_PE2_RX_DP<11>
  J89    A98    A98  SCONN280_ME1028040102011  I282
  U1     DW11  PE2_RX_DP11  SOCKET4677_AZIFS054P001C01  I54

P5E_CPU1_PE2_RX_DP<12>   @S9S_MB_2U_LIB.S9S_MB_2U(SCH_1):P5E_CPU1_PE2_RX_DP<12>
  J89    A95    A95  SCONN280_ME1028040102011  I282
  U1     EB10  PE2_RX_DP12  SOCKET4677_AZIFS054P001C01  I54

P5E_CPU1_PE2_RX_DP<13>   @S9S_MB_2U_LIB.S9S_MB_2U(SCH_1):P5E_CPU1_PE2_RX_DP<13>
  J89    A92    A92  SCONN280_ME1028040102011  I282
  U1     EC11  PE2_RX_DP13  SOCKET4677_AZIFS054P001C01  I54

P5E_CPU1_PE2_RX_DP<14>   @S9S_MB_2U_LIB.S9S_MB_2U(SCH_1):P5E_CPU1_PE2_RX_DP<14>
  J89    A89    A89  SCONN280_ME1028040102011  I282
  U1     EF10  PE2_RX_DP14  SOCKET4677_AZIFS054P001C01  I54

P5E_CPU1_PE2_RX_DP<15>   @S9S_MB_2U_LIB.S9S_MB_2U(SCH_1):P5E_CPU1_PE2_RX_DP<15>
  J89    A86    A86  SCONN280_ME1028040102011  I282
  U1     EG11  PE2_RX_DP15  SOCKET4677_AZIFS054P001C01  I54

P5E_CPU1_PE2_TX_C_DN<0>   @S9S_MB_2U_LIB.S9S_MB_2U(SCH_1):P5E_CPU1_PE2_TX_C_DN<0>
  C772     1      1  Q_CAP_DIFFBUS  I123
  J89    B133   B133  SCONN280_ME1028040102011  I282

P5E_CPU1_PE2_TX_C_DN<1>   @S9S_MB_2U_LIB.S9S_MB_2U(SCH_1):P5E_CPU1_PE2_TX_C_DN<1>
  C770     1      1  Q_CAP_DIFFBUS  I125
  J89    B130   B130  SCONN280_ME1028040102011  I282

P5E_CPU1_PE2_TX_C_DN<2>   @S9S_MB_2U_LIB.S9S_MB_2U(SCH_1):P5E_CPU1_PE2_TX_C_DN<2>
  C768     1      1  Q_CAP_DIFFBUS  I127
  J89    B127   B127  SCONN280_ME1028040102011  I282

P5E_CPU1_PE2_TX_C_DN<3>   @S9S_MB_2U_LIB.S9S_MB_2U(SCH_1):P5E_CPU1_PE2_TX_C_DN<3>
  C766     1      1  Q_CAP_DIFFBUS  I129
  J89    B124   B124  SCONN280_ME1028040102011  I282

P5E_CPU1_PE2_TX_C_DN<4>   @S9S_MB_2U_LIB.S9S_MB_2U(SCH_1):P5E_CPU1_PE2_TX_C_DN<4>
  C764     1      1  Q_CAP_DIFFBUS  I130
  J89    B121   B121  SCONN280_ME1028040102011  I282

P5E_CPU1_PE2_TX_C_DN<5>   @S9S_MB_2U_LIB.S9S_MB_2U(SCH_1):P5E_CPU1_PE2_TX_C_DN<5>
  C762     1      1  Q_CAP_DIFFBUS  I136
  J89    B118   B118  SCONN280_ME1028040102011  I282

P5E_CPU1_PE2_TX_C_DN<6>   @S9S_MB_2U_LIB.S9S_MB_2U(SCH_1):P5E_CPU1_PE2_TX_C_DN<6>
  C760     1      1  Q_CAP_DIFFBUS  I138
  J89    B115   B115  SCONN280_ME1028040102011  I282

P5E_CPU1_PE2_TX_C_DN<7>   @S9S_MB_2U_LIB.S9S_MB_2U(SCH_1):P5E_CPU1_PE2_TX_C_DN<7>
  C758     1      1  Q_CAP_DIFFBUS  I140
  J89    B111   B111  SCONN280_ME1028040102011  I282

P5E_CPU1_PE2_TX_C_DN<8>   @S9S_MB_2U_LIB.S9S_MB_2U(SCH_1):P5E_CPU1_PE2_TX_C_DN<8>
  C756     1      1  Q_CAP_DIFFBUS  I154
  J89    B108   B108  SCONN280_ME1028040102011  I282

P5E_CPU1_PE2_TX_C_DN<9>   @S9S_MB_2U_LIB.S9S_MB_2U(SCH_1):P5E_CPU1_PE2_TX_C_DN<9>
  C754     1      1  Q_CAP_DIFFBUS  I157
  J89    B105   B105  SCONN280_ME1028040102011  I282

P5E_CPU1_PE2_TX_C_DN<10>   @S9S_MB_2U_LIB.S9S_MB_2U(SCH_1):P5E_CPU1_PE2_TX_C_DN<10>
  C752     1      1  Q_CAP_DIFFBUS  I159
  J89    B102   B102  SCONN280_ME1028040102011  I282

P5E_CPU1_PE2_TX_C_DN<11>   @S9S_MB_2U_LIB.S9S_MB_2U(SCH_1):P5E_CPU1_PE2_TX_C_DN<11>
  C750     1      1  Q_CAP_DIFFBUS  I160
  J89    B99    B99  SCONN280_ME1028040102011  I282

P5E_CPU1_PE2_TX_C_DN<12>   @S9S_MB_2U_LIB.S9S_MB_2U(SCH_1):P5E_CPU1_PE2_TX_C_DN<12>
  C748     1      1  Q_CAP_DIFFBUS  I163
  J89    B96    B96  SCONN280_ME1028040102011  I282

P5E_CPU1_PE2_TX_C_DN<13>   @S9S_MB_2U_LIB.S9S_MB_2U(SCH_1):P5E_CPU1_PE2_TX_C_DN<13>
  C746     1      1  Q_CAP_DIFFBUS  I168
  J89    B93    B93  SCONN280_ME1028040102011  I282

P5E_CPU1_PE2_TX_C_DN<14>   @S9S_MB_2U_LIB.S9S_MB_2U(SCH_1):P5E_CPU1_PE2_TX_C_DN<14>
  C744     1      1  Q_CAP_DIFFBUS  I170
  J89    B90    B90  SCONN280_ME1028040102011  I282

P5E_CPU1_PE2_TX_C_DN<15>   @S9S_MB_2U_LIB.S9S_MB_2U(SCH_1):P5E_CPU1_PE2_TX_C_DN<15>
  C742     1      1  Q_CAP_DIFFBUS  I172
  J89    B87    B87  SCONN280_ME1028040102011  I282

P5E_CPU1_PE2_TX_C_DP<0>   @S9S_MB_2U_LIB.S9S_MB_2U(SCH_1):P5E_CPU1_PE2_TX_C_DP<0>
  C773     1      1  Q_CAP_DIFFBUS  I122
  J89    B132   B132  SCONN280_ME1028040102011  I282

P5E_CPU1_PE2_TX_C_DP<1>   @S9S_MB_2U_LIB.S9S_MB_2U(SCH_1):P5E_CPU1_PE2_TX_C_DP<1>
  C771     1      1  Q_CAP_DIFFBUS  I124
  J89    B129   B129  SCONN280_ME1028040102011  I282

P5E_CPU1_PE2_TX_C_DP<2>   @S9S_MB_2U_LIB.S9S_MB_2U(SCH_1):P5E_CPU1_PE2_TX_C_DP<2>
  C769     1      1  Q_CAP_DIFFBUS  I126
  J89    B126   B126  SCONN280_ME1028040102011  I282

P5E_CPU1_PE2_TX_C_DP<3>   @S9S_MB_2U_LIB.S9S_MB_2U(SCH_1):P5E_CPU1_PE2_TX_C_DP<3>
  C767     1      1  Q_CAP_DIFFBUS  I128
  J89    B123   B123  SCONN280_ME1028040102011  I282

P5E_CPU1_PE2_TX_C_DP<4>   @S9S_MB_2U_LIB.S9S_MB_2U(SCH_1):P5E_CPU1_PE2_TX_C_DP<4>
  C765     1      1  Q_CAP_DIFFBUS  I131
  J89    B120   B120  SCONN280_ME1028040102011  I282

P5E_CPU1_PE2_TX_C_DP<5>   @S9S_MB_2U_LIB.S9S_MB_2U(SCH_1):P5E_CPU1_PE2_TX_C_DP<5>
  C763     1      1  Q_CAP_DIFFBUS  I135
  J89    B117   B117  SCONN280_ME1028040102011  I282

P5E_CPU1_PE2_TX_C_DP<6>   @S9S_MB_2U_LIB.S9S_MB_2U(SCH_1):P5E_CPU1_PE2_TX_C_DP<6>
  C761     1      1  Q_CAP_DIFFBUS  I137
  J89    B114   B114  SCONN280_ME1028040102011  I282

P5E_CPU1_PE2_TX_C_DP<7>   @S9S_MB_2U_LIB.S9S_MB_2U(SCH_1):P5E_CPU1_PE2_TX_C_DP<7>
  C759     1      1  Q_CAP_DIFFBUS  I139
  J89    B110   B110  SCONN280_ME1028040102011  I282

P5E_CPU1_PE2_TX_C_DP<8>   @S9S_MB_2U_LIB.S9S_MB_2U(SCH_1):P5E_CPU1_PE2_TX_C_DP<8>
  C757     1      1  Q_CAP_DIFFBUS  I155
  J89    B107   B107  SCONN280_ME1028040102011  I282

P5E_CPU1_PE2_TX_C_DP<9>   @S9S_MB_2U_LIB.S9S_MB_2U(SCH_1):P5E_CPU1_PE2_TX_C_DP<9>
  C755     1      1  Q_CAP_DIFFBUS  I156
  J89    B104   B104  SCONN280_ME1028040102011  I282

P5E_CPU1_PE2_TX_C_DP<10>   @S9S_MB_2U_LIB.S9S_MB_2U(SCH_1):P5E_CPU1_PE2_TX_C_DP<10>
  C753     1      1  Q_CAP_DIFFBUS  I158
  J89    B101   B101  SCONN280_ME1028040102011  I282

P5E_CPU1_PE2_TX_C_DP<11>   @S9S_MB_2U_LIB.S9S_MB_2U(SCH_1):P5E_CPU1_PE2_TX_C_DP<11>
  C751     1      1  Q_CAP_DIFFBUS  I161
  J89    B98    B98  SCONN280_ME1028040102011  I282

P5E_CPU1_PE2_TX_C_DP<12>   @S9S_MB_2U_LIB.S9S_MB_2U(SCH_1):P5E_CPU1_PE2_TX_C_DP<12>
  C749     1      1  Q_CAP_DIFFBUS  I162
  J89    B95    B95  SCONN280_ME1028040102011  I282

P5E_CPU1_PE2_TX_C_DP<13>   @S9S_MB_2U_LIB.S9S_MB_2U(SCH_1):P5E_CPU1_PE2_TX_C_DP<13>
  C747     1      1  Q_CAP_DIFFBUS  I167
  J89    B92    B92  SCONN280_ME1028040102011  I282

P5E_CPU1_PE2_TX_C_DP<14>   @S9S_MB_2U_LIB.S9S_MB_2U(SCH_1):P5E_CPU1_PE2_TX_C_DP<14>
  C745     1      1  Q_CAP_DIFFBUS  I169
  J89    B89    B89  SCONN280_ME1028040102011  I282

P5E_CPU1_PE2_TX_C_DP<15>   @S9S_MB_2U_LIB.S9S_MB_2U(SCH_1):P5E_CPU1_PE2_TX_C_DP<15>
  C743     1      1  Q_CAP_DIFFBUS  I171
  J89    B86    B86  SCONN280_ME1028040102011  I282

P5E_CPU1_PE2_TX_DN<0>   @S9S_MB_2U_LIB.S9S_MB_2U(SCH_1):P5E_CPU1_PE2_TX_DN<0>
  C772     2      2  Q_CAP_DIFFBUS  I123
  U1     CU13  PE2_TX_DN0  SOCKET4677_AZIFS054P001C01  I54

P5E_CPU1_PE2_TX_DN<1>   @S9S_MB_2U_LIB.S9S_MB_2U(SCH_1):P5E_CPU1_PE2_TX_DN<1>
  C770     2      2  Q_CAP_DIFFBUS  I125
  U1     CV14  PE2_TX_DN1  SOCKET4677_AZIFS054P001C01  I54

P5E_CPU1_PE2_TX_DN<2>   @S9S_MB_2U_LIB.S9S_MB_2U(SCH_1):P5E_CPU1_PE2_TX_DN<2>
  C768     2      2  Q_CAP_DIFFBUS  I127
  U1     DA13  PE2_TX_DN2  SOCKET4677_AZIFS054P001C01  I54

P5E_CPU1_PE2_TX_DN<3>   @S9S_MB_2U_LIB.S9S_MB_2U(SCH_1):P5E_CPU1_PE2_TX_DN<3>
  C766     2      2  Q_CAP_DIFFBUS  I129
  U1     DB14  PE2_TX_DN3  SOCKET4677_AZIFS054P001C01  I54

P5E_CPU1_PE2_TX_DN<4>   @S9S_MB_2U_LIB.S9S_MB_2U(SCH_1):P5E_CPU1_PE2_TX_DN<4>
  C764     2      2  Q_CAP_DIFFBUS  I130
  U1     DE13  PE2_TX_DN4  SOCKET4677_AZIFS054P001C01  I54

P5E_CPU1_PE2_TX_DN<5>   @S9S_MB_2U_LIB.S9S_MB_2U(SCH_1):P5E_CPU1_PE2_TX_DN<5>
  C762     2      2  Q_CAP_DIFFBUS  I136
  U1     DF14  PE2_TX_DN5  SOCKET4677_AZIFS054P001C01  I54

P5E_CPU1_PE2_TX_DN<6>   @S9S_MB_2U_LIB.S9S_MB_2U(SCH_1):P5E_CPU1_PE2_TX_DN<6>
  C760     2      2  Q_CAP_DIFFBUS  I138
  U1     DJ13  PE2_TX_DN6  SOCKET4677_AZIFS054P001C01  I54

P5E_CPU1_PE2_TX_DN<7>   @S9S_MB_2U_LIB.S9S_MB_2U(SCH_1):P5E_CPU1_PE2_TX_DN<7>
  C758     2      2  Q_CAP_DIFFBUS  I140
  U1     DK14  PE2_TX_DN7  SOCKET4677_AZIFS054P001C01  I54

P5E_CPU1_PE2_TX_DN<8>   @S9S_MB_2U_LIB.S9S_MB_2U(SCH_1):P5E_CPU1_PE2_TX_DN<8>
  C756     2      2  Q_CAP_DIFFBUS  I154
  U1     DN13  PE2_TX_DN8  SOCKET4677_AZIFS054P001C01  I54

P5E_CPU1_PE2_TX_DN<9>   @S9S_MB_2U_LIB.S9S_MB_2U(SCH_1):P5E_CPU1_PE2_TX_DN<9>
  C754     2      2  Q_CAP_DIFFBUS  I157
  U1     DP14  PE2_TX_DN9  SOCKET4677_AZIFS054P001C01  I54

P5E_CPU1_PE2_TX_DN<10>   @S9S_MB_2U_LIB.S9S_MB_2U(SCH_1):P5E_CPU1_PE2_TX_DN<10>
  C752     2      2  Q_CAP_DIFFBUS  I159
  U1     DU13  PE2_TX_DN10  SOCKET4677_AZIFS054P001C01  I54

P5E_CPU1_PE2_TX_DN<11>   @S9S_MB_2U_LIB.S9S_MB_2U(SCH_1):P5E_CPU1_PE2_TX_DN<11>
  C750     2      2  Q_CAP_DIFFBUS  I160
  U1     DV14  PE2_TX_DN11  SOCKET4677_AZIFS054P001C01  I54

P5E_CPU1_PE2_TX_DN<12>   @S9S_MB_2U_LIB.S9S_MB_2U(SCH_1):P5E_CPU1_PE2_TX_DN<12>
  C748     2      2  Q_CAP_DIFFBUS  I163
  U1     EA13  PE2_TX_DN12  SOCKET4677_AZIFS054P001C01  I54

P5E_CPU1_PE2_TX_DN<13>   @S9S_MB_2U_LIB.S9S_MB_2U(SCH_1):P5E_CPU1_PE2_TX_DN<13>
  C746     2      2  Q_CAP_DIFFBUS  I168
  U1     EB14  PE2_TX_DN13  SOCKET4677_AZIFS054P001C01  I54

P5E_CPU1_PE2_TX_DN<14>   @S9S_MB_2U_LIB.S9S_MB_2U(SCH_1):P5E_CPU1_PE2_TX_DN<14>
  C744     2      2  Q_CAP_DIFFBUS  I170
  U1     EE13  PE2_TX_DN14  SOCKET4677_AZIFS054P001C01  I54

P5E_CPU1_PE2_TX_DN<15>   @S9S_MB_2U_LIB.S9S_MB_2U(SCH_1):P5E_CPU1_PE2_TX_DN<15>
  C742     2      2  Q_CAP_DIFFBUS  I172
  U1     EF14  PE2_TX_DN15  SOCKET4677_AZIFS054P001C01  I54

P5E_CPU1_PE2_TX_DP<0>   @S9S_MB_2U_LIB.S9S_MB_2U(SCH_1):P5E_CPU1_PE2_TX_DP<0>
  C773     2      2  Q_CAP_DIFFBUS  I122
  U1     CT14  PE2_TX_DP0  SOCKET4677_AZIFS054P001C01  I54

P5E_CPU1_PE2_TX_DP<1>   @S9S_MB_2U_LIB.S9S_MB_2U(SCH_1):P5E_CPU1_PE2_TX_DP<1>
  C771     2      2  Q_CAP_DIFFBUS  I124
  U1     CW15  PE2_TX_DP1  SOCKET4677_AZIFS054P001C01  I54

P5E_CPU1_PE2_TX_DP<2>   @S9S_MB_2U_LIB.S9S_MB_2U(SCH_1):P5E_CPU1_PE2_TX_DP<2>
  C769     2      2  Q_CAP_DIFFBUS  I126
  U1     CY14  PE2_TX_DP2  SOCKET4677_AZIFS054P001C01  I54

P5E_CPU1_PE2_TX_DP<3>   @S9S_MB_2U_LIB.S9S_MB_2U(SCH_1):P5E_CPU1_PE2_TX_DP<3>
  C767     2      2  Q_CAP_DIFFBUS  I128
  U1     DC15  PE2_TX_DP3  SOCKET4677_AZIFS054P001C01  I54

P5E_CPU1_PE2_TX_DP<4>   @S9S_MB_2U_LIB.S9S_MB_2U(SCH_1):P5E_CPU1_PE2_TX_DP<4>
  C765     2      2  Q_CAP_DIFFBUS  I131
  U1     DD14  PE2_TX_DP4  SOCKET4677_AZIFS054P001C01  I54

P5E_CPU1_PE2_TX_DP<5>   @S9S_MB_2U_LIB.S9S_MB_2U(SCH_1):P5E_CPU1_PE2_TX_DP<5>
  C763     2      2  Q_CAP_DIFFBUS  I135
  U1     DG15  PE2_TX_DP5  SOCKET4677_AZIFS054P001C01  I54

P5E_CPU1_PE2_TX_DP<6>   @S9S_MB_2U_LIB.S9S_MB_2U(SCH_1):P5E_CPU1_PE2_TX_DP<6>
  C761     2      2  Q_CAP_DIFFBUS  I137
  U1     DH14  PE2_TX_DP6  SOCKET4677_AZIFS054P001C01  I54

P5E_CPU1_PE2_TX_DP<7>   @S9S_MB_2U_LIB.S9S_MB_2U(SCH_1):P5E_CPU1_PE2_TX_DP<7>
  C759     2      2  Q_CAP_DIFFBUS  I139
  U1     DL15  PE2_TX_DP7  SOCKET4677_AZIFS054P001C01  I54

P5E_CPU1_PE2_TX_DP<8>   @S9S_MB_2U_LIB.S9S_MB_2U(SCH_1):P5E_CPU1_PE2_TX_DP<8>
  C757     2      2  Q_CAP_DIFFBUS  I155
  U1     DM14  PE2_TX_DP8  SOCKET4677_AZIFS054P001C01  I54

P5E_CPU1_PE2_TX_DP<9>   @S9S_MB_2U_LIB.S9S_MB_2U(SCH_1):P5E_CPU1_PE2_TX_DP<9>
  C755     2      2  Q_CAP_DIFFBUS  I156
  U1     DR15  PE2_TX_DP9  SOCKET4677_AZIFS054P001C01  I54

P5E_CPU1_PE2_TX_DP<10>   @S9S_MB_2U_LIB.S9S_MB_2U(SCH_1):P5E_CPU1_PE2_TX_DP<10>
  C753     2      2  Q_CAP_DIFFBUS  I158
  U1     DT14  PE2_TX_DP10  SOCKET4677_AZIFS054P001C01  I54

P5E_CPU1_PE2_TX_DP<11>   @S9S_MB_2U_LIB.S9S_MB_2U(SCH_1):P5E_CPU1_PE2_TX_DP<11>
  C751     2      2  Q_CAP_DIFFBUS  I161
  U1     DW15  PE2_TX_DP11  SOCKET4677_AZIFS054P001C01  I54

P5E_CPU1_PE2_TX_DP<12>   @S9S_MB_2U_LIB.S9S_MB_2U(SCH_1):P5E_CPU1_PE2_TX_DP<12>
  C749     2      2  Q_CAP_DIFFBUS  I162
  U1     DY14  PE2_TX_DP12  SOCKET4677_AZIFS054P001C01  I54

P5E_CPU1_PE2_TX_DP<13>   @S9S_MB_2U_LIB.S9S_MB_2U(SCH_1):P5E_CPU1_PE2_TX_DP<13>
  C747     2      2  Q_CAP_DIFFBUS  I167
  U1     EC15  PE2_TX_DP13  SOCKET4677_AZIFS054P001C01  I54

P5E_CPU1_PE2_TX_DP<14>   @S9S_MB_2U_LIB.S9S_MB_2U(SCH_1):P5E_CPU1_PE2_TX_DP<14>
  C745     2      2  Q_CAP_DIFFBUS  I169
  U1     ED14  PE2_TX_DP14  SOCKET4677_AZIFS054P001C01  I54

P5E_CPU1_PE2_TX_DP<15>   @S9S_MB_2U_LIB.S9S_MB_2U(SCH_1):P5E_CPU1_PE2_TX_DP<15>
  C743     2      2  Q_CAP_DIFFBUS  I171
  U1     EG15  PE2_TX_DP15  SOCKET4677_AZIFS054P001C01  I54

P5E_CPU1_PE3_RX_DN<0>   @S9S_MB_2U_LIB.S9S_MB_2U(SCH_1):P5E_CPU1_PE3_RX_DN<0>
  J35    A21  SIGNAL_A21  SCONN140_G64V3431BHR  I64
  U1     EH89  PE3_RX_DN0  SOCKET4677_AZIFS054P001C01  I12

P5E_CPU1_PE3_RX_DN<1>   @S9S_MB_2U_LIB.S9S_MB_2U(SCH_1):P5E_CPU1_PE3_RX_DN<1>
  J35    A24  SIGNAL_A24  SCONN140_G64V3431BHR  I64
  U1     ED91  PE3_RX_DN1  SOCKET4677_AZIFS054P001C01  I12

P5E_CPU1_PE3_RX_DN<2>   @S9S_MB_2U_LIB.S9S_MB_2U(SCH_1):P5E_CPU1_PE3_RX_DN<2>
  J35    A26  SIGNAL_A26  SCONN140_G64V3431BHR  I64
  U1     EC90  PE3_RX_DN2  SOCKET4677_AZIFS054P001C01  I12

P5E_CPU1_PE3_RX_DN<3>   @S9S_MB_2U_LIB.S9S_MB_2U(SCH_1):P5E_CPU1_PE3_RX_DN<3>
  J35    A31  SIGNAL_A31  SCONN140_G64V3431BHR  I64
  U1     DY91  PE3_RX_DN3  SOCKET4677_AZIFS054P001C01  I12

P5E_CPU1_PE3_RX_DN<4>   @S9S_MB_2U_LIB.S9S_MB_2U(SCH_1):P5E_CPU1_PE3_RX_DN<4>
  J35    A34  SIGNAL_A34  SCONN140_G64V3431BHR  I64
  U1     DV89  PE3_RX_DN4  SOCKET4677_AZIFS054P001C01  I12

P5E_CPU1_PE3_RX_DN<5>   @S9S_MB_2U_LIB.S9S_MB_2U(SCH_1):P5E_CPU1_PE3_RX_DN<5>
  J35    A36  SIGNAL_A36  SCONN140_G64V3431BHR  I64
  U1     DU90  PE3_RX_DN5  SOCKET4677_AZIFS054P001C01  I12

P5E_CPU1_PE3_RX_DN<6>   @S9S_MB_2U_LIB.S9S_MB_2U(SCH_1):P5E_CPU1_PE3_RX_DN<6>
  J35    A40  SIGNAL_A40  SCONN140_G64V3431BHR  I64
  U1     DP89  PE3_RX_DN6  SOCKET4677_AZIFS054P001C01  I12

P5E_CPU1_PE3_RX_DN<7>   @S9S_MB_2U_LIB.S9S_MB_2U(SCH_1):P5E_CPU1_PE3_RX_DN<7>
  J35    A44  SIGNAL_A44  SCONN140_G64V3431BHR  I64
  U1     DN90  PE3_RX_DN7  SOCKET4677_AZIFS054P001C01  I12

P5E_CPU1_PE3_RX_DN<8>   @S9S_MB_2U_LIB.S9S_MB_2U(SCH_1):P5E_CPU1_PE3_RX_DN<8>
  J35    A47  SIGNAL_A47  SCONN140_G64V3431BHR  I64
  U1     DL90  PE3_RX_DN8  SOCKET4677_AZIFS054P001C01  I12

P5E_CPU1_PE3_RX_DN<9>   @S9S_MB_2U_LIB.S9S_MB_2U(SCH_1):P5E_CPU1_PE3_RX_DN<9>
  J35    A51  SIGNAL_A51  SCONN140_G64V3431BHR  I64
  U1     DH91  PE3_RX_DN9  SOCKET4677_AZIFS054P001C01  I12

P5E_CPU1_PE3_RX_DN<10>   @S9S_MB_2U_LIB.S9S_MB_2U(SCH_1):P5E_CPU1_PE3_RX_DN<10>
  J35    A53  SIGNAL_A53  SCONN140_G64V3431BHR  I64
  U1     DG90  PE3_RX_DN10  SOCKET4677_AZIFS054P001C01  I12

P5E_CPU1_PE3_RX_DN<11>   @S9S_MB_2U_LIB.S9S_MB_2U(SCH_1):P5E_CPU1_PE3_RX_DN<11>
  J35    A57  SIGNAL_A57  SCONN140_G64V3431BHR  I64
  U1     DD91  PE3_RX_DN11  SOCKET4677_AZIFS054P001C01  I12

P5E_CPU1_PE3_RX_DN<12>   @S9S_MB_2U_LIB.S9S_MB_2U(SCH_1):P5E_CPU1_PE3_RX_DN<12>
  J35    A60  SIGNAL_A60  SCONN140_G64V3431BHR  I64
  U1     DB89  PE3_RX_DN12  SOCKET4677_AZIFS054P001C01  I12

P5E_CPU1_PE3_RX_DN<13>   @S9S_MB_2U_LIB.S9S_MB_2U(SCH_1):P5E_CPU1_PE3_RX_DN<13>
  J35    A62  SIGNAL_A62  SCONN140_G64V3431BHR  I64
  U1     DA90  PE3_RX_DN13  SOCKET4677_AZIFS054P001C01  I12

P5E_CPU1_PE3_RX_DN<14>   @S9S_MB_2U_LIB.S9S_MB_2U(SCH_1):P5E_CPU1_PE3_RX_DN<14>
  J35    A66  SIGNAL_A66  SCONN140_G64V3431BHR  I64
  U1     CV89  PE3_RX_DN14  SOCKET4677_AZIFS054P001C01  I12

P5E_CPU1_PE3_RX_DN<15>   @S9S_MB_2U_LIB.S9S_MB_2U(SCH_1):P5E_CPU1_PE3_RX_DN<15>
  J35    A68  SIGNAL_A68  SCONN140_G64V3431BHR  I64
  U1     CU90  PE3_RX_DN15  SOCKET4677_AZIFS054P001C01  I12

P5E_CPU1_PE3_RX_DP<0>   @S9S_MB_2U_LIB.S9S_MB_2U(SCH_1):P5E_CPU1_PE3_RX_DP<0>
  J35    A20  SIGNAL_A20  SCONN140_G64V3431BHR  I64
  U1     EJ90  PE3_RX_DP0  SOCKET4677_AZIFS054P001C01  I12

P5E_CPU1_PE3_RX_DP<1>   @S9S_MB_2U_LIB.S9S_MB_2U(SCH_1):P5E_CPU1_PE3_RX_DP<1>
  J35    A23  SIGNAL_A23  SCONN140_G64V3431BHR  I64
  U1     EE90  PE3_RX_DP1  SOCKET4677_AZIFS054P001C01  I12

P5E_CPU1_PE3_RX_DP<2>   @S9S_MB_2U_LIB.S9S_MB_2U(SCH_1):P5E_CPU1_PE3_RX_DP<2>
  J35    A27  SIGNAL_A27  SCONN140_G64V3431BHR  I64
  U1     EB89  PE3_RX_DP2  SOCKET4677_AZIFS054P001C01  I12

P5E_CPU1_PE3_RX_DP<3>   @S9S_MB_2U_LIB.S9S_MB_2U(SCH_1):P5E_CPU1_PE3_RX_DP<3>
  J35    A30  SIGNAL_A30  SCONN140_G64V3431BHR  I64
  U1     EA90  PE3_RX_DP3  SOCKET4677_AZIFS054P001C01  I12

P5E_CPU1_PE3_RX_DP<4>   @S9S_MB_2U_LIB.S9S_MB_2U(SCH_1):P5E_CPU1_PE3_RX_DP<4>
  J35    A33  SIGNAL_A33  SCONN140_G64V3431BHR  I64
  U1     DW90  PE3_RX_DP4  SOCKET4677_AZIFS054P001C01  I12

P5E_CPU1_PE3_RX_DP<5>   @S9S_MB_2U_LIB.S9S_MB_2U(SCH_1):P5E_CPU1_PE3_RX_DP<5>
  J35    A37  SIGNAL_A37  SCONN140_G64V3431BHR  I64
  U1     DT91  PE3_RX_DP5  SOCKET4677_AZIFS054P001C01  I12

P5E_CPU1_PE3_RX_DP<6>   @S9S_MB_2U_LIB.S9S_MB_2U(SCH_1):P5E_CPU1_PE3_RX_DP<6>
  J35    A39  SIGNAL_A39  SCONN140_G64V3431BHR  I64
  U1     DR90  PE3_RX_DP6  SOCKET4677_AZIFS054P001C01  I12

P5E_CPU1_PE3_RX_DP<7>   @S9S_MB_2U_LIB.S9S_MB_2U(SCH_1):P5E_CPU1_PE3_RX_DP<7>
  J35    A45  SIGNAL_A45  SCONN140_G64V3431BHR  I64
  U1     DM91  PE3_RX_DP7  SOCKET4677_AZIFS054P001C01  I12

P5E_CPU1_PE3_RX_DP<8>   @S9S_MB_2U_LIB.S9S_MB_2U(SCH_1):P5E_CPU1_PE3_RX_DP<8>
  J35    A48  SIGNAL_A48  SCONN140_G64V3431BHR  I64
  U1     DK89  PE3_RX_DP8  SOCKET4677_AZIFS054P001C01  I12

P5E_CPU1_PE3_RX_DP<9>   @S9S_MB_2U_LIB.S9S_MB_2U(SCH_1):P5E_CPU1_PE3_RX_DP<9>
  J35    A50  SIGNAL_A50  SCONN140_G64V3431BHR  I64
  U1     DJ90  PE3_RX_DP9  SOCKET4677_AZIFS054P001C01  I12

P5E_CPU1_PE3_RX_DP<10>   @S9S_MB_2U_LIB.S9S_MB_2U(SCH_1):P5E_CPU1_PE3_RX_DP<10>
  J35    A54  SIGNAL_A54  SCONN140_G64V3431BHR  I64
  U1     DF89  PE3_RX_DP10  SOCKET4677_AZIFS054P001C01  I12

P5E_CPU1_PE3_RX_DP<11>   @S9S_MB_2U_LIB.S9S_MB_2U(SCH_1):P5E_CPU1_PE3_RX_DP<11>
  J35    A56  SIGNAL_A56  SCONN140_G64V3431BHR  I64
  U1     DE90  PE3_RX_DP11  SOCKET4677_AZIFS054P001C01  I12

P5E_CPU1_PE3_RX_DP<12>   @S9S_MB_2U_LIB.S9S_MB_2U(SCH_1):P5E_CPU1_PE3_RX_DP<12>
  J35    A59  SIGNAL_A59  SCONN140_G64V3431BHR  I64
  U1     DC90  PE3_RX_DP12  SOCKET4677_AZIFS054P001C01  I12

P5E_CPU1_PE3_RX_DP<13>   @S9S_MB_2U_LIB.S9S_MB_2U(SCH_1):P5E_CPU1_PE3_RX_DP<13>
  J35    A63  SIGNAL_A63  SCONN140_G64V3431BHR  I64
  U1     CY91  PE3_RX_DP13  SOCKET4677_AZIFS054P001C01  I12

P5E_CPU1_PE3_RX_DP<14>   @S9S_MB_2U_LIB.S9S_MB_2U(SCH_1):P5E_CPU1_PE3_RX_DP<14>
  J35    A65  SIGNAL_A65  SCONN140_G64V3431BHR  I64
  U1     CW90  PE3_RX_DP14  SOCKET4677_AZIFS054P001C01  I12

P5E_CPU1_PE3_RX_DP<15>   @S9S_MB_2U_LIB.S9S_MB_2U(SCH_1):P5E_CPU1_PE3_RX_DP<15>
  J35    A69  SIGNAL_A69  SCONN140_G64V3431BHR  I64
  U1     CT91  PE3_RX_DP15  SOCKET4677_AZIFS054P001C01  I12

P5E_CPU1_PE3_TX_C_DN<0>   @S9S_MB_2U_LIB.S9S_MB_2U(SCH_1):P5E_CPU1_PE3_TX_C_DN<0>
  C1546    1      1  Q_CAP_DIFFBUS  I230
  J35    B20  SIGNAL_B20  SCONN140_G64V3431BHR  I64

P5E_CPU1_PE3_TX_C_DN<1>   @S9S_MB_2U_LIB.S9S_MB_2U(SCH_1):P5E_CPU1_PE3_TX_C_DN<1>
  C1544    1      1  Q_CAP_DIFFBUS  I232
  J35    B24  SIGNAL_B24  SCONN140_G64V3431BHR  I64

P5E_CPU1_PE3_TX_C_DN<2>   @S9S_MB_2U_LIB.S9S_MB_2U(SCH_1):P5E_CPU1_PE3_TX_C_DN<2>
  C1542    1      1  Q_CAP_DIFFBUS  I233
  J35    B27  SIGNAL_B27  SCONN140_G64V3431BHR  I64

P5E_CPU1_PE3_TX_C_DN<3>   @S9S_MB_2U_LIB.S9S_MB_2U(SCH_1):P5E_CPU1_PE3_TX_C_DN<3>
  C1540    1      1  Q_CAP_DIFFBUS  I236
  J35    B31  SIGNAL_B31  SCONN140_G64V3431BHR  I64

P5E_CPU1_PE3_TX_C_DN<4>   @S9S_MB_2U_LIB.S9S_MB_2U(SCH_1):P5E_CPU1_PE3_TX_C_DN<4>
  C1538    1      1  Q_CAP_DIFFBUS  I238
  J35    B34  SIGNAL_B34  SCONN140_G64V3431BHR  I64

P5E_CPU1_PE3_TX_C_DN<5>   @S9S_MB_2U_LIB.S9S_MB_2U(SCH_1):P5E_CPU1_PE3_TX_C_DN<5>
  C1536    1      1  Q_CAP_DIFFBUS  I250
  J35    B37  SIGNAL_B37  SCONN140_G64V3431BHR  I64

P5E_CPU1_PE3_TX_C_DN<6>   @S9S_MB_2U_LIB.S9S_MB_2U(SCH_1):P5E_CPU1_PE3_TX_C_DN<6>
  C1534    1      1  Q_CAP_DIFFBUS  I251
  J35    B40  SIGNAL_B40  SCONN140_G64V3431BHR  I64

P5E_CPU1_PE3_TX_C_DN<7>   @S9S_MB_2U_LIB.S9S_MB_2U(SCH_1):P5E_CPU1_PE3_TX_C_DN<7>
  C1532    1      1  Q_CAP_DIFFBUS  I254
  J35    B45  SIGNAL_B45  SCONN140_G64V3431BHR  I64

P5E_CPU1_PE3_TX_C_DN<8>   @S9S_MB_2U_LIB.S9S_MB_2U(SCH_1):P5E_CPU1_PE3_TX_C_DN<8>
  C1530    1      1  Q_CAP_DIFFBUS  I277
  J35    B48  SIGNAL_B48  SCONN140_G64V3431BHR  I64

P5E_CPU1_PE3_TX_C_DN<9>   @S9S_MB_2U_LIB.S9S_MB_2U(SCH_1):P5E_CPU1_PE3_TX_C_DN<9>
  C1528    1      1  Q_CAP_DIFFBUS  I280
  J35    B51  SIGNAL_B51  SCONN140_G64V3431BHR  I64

P5E_CPU1_PE3_TX_C_DN<10>   @S9S_MB_2U_LIB.S9S_MB_2U(SCH_1):P5E_CPU1_PE3_TX_C_DN<10>
  C1526    1      1  Q_CAP_DIFFBUS  I282
  J35    B54  SIGNAL_B54  SCONN140_G64V3431BHR  I64

P5E_CPU1_PE3_TX_C_DN<11>   @S9S_MB_2U_LIB.S9S_MB_2U(SCH_1):P5E_CPU1_PE3_TX_C_DN<11>
  C1524    1      1  Q_CAP_DIFFBUS  I284
  J35    B57  SIGNAL_B57  SCONN140_G64V3431BHR  I64

P5E_CPU1_PE3_TX_C_DN<12>   @S9S_MB_2U_LIB.S9S_MB_2U(SCH_1):P5E_CPU1_PE3_TX_C_DN<12>
  C1522    1      1  Q_CAP_DIFFBUS  I286
  J35    B60  SIGNAL_B60  SCONN140_G64V3431BHR  I64

P5E_CPU1_PE3_TX_C_DN<13>   @S9S_MB_2U_LIB.S9S_MB_2U(SCH_1):P5E_CPU1_PE3_TX_C_DN<13>
  C1520    1      1  Q_CAP_DIFFBUS  I297
  J35    B63  SIGNAL_B63  SCONN140_G64V3431BHR  I64

P5E_CPU1_PE3_TX_C_DN<14>   @S9S_MB_2U_LIB.S9S_MB_2U(SCH_1):P5E_CPU1_PE3_TX_C_DN<14>
  C1518    1      1  Q_CAP_DIFFBUS  I300
  J35    B66  SIGNAL_B66  SCONN140_G64V3431BHR  I64

P5E_CPU1_PE3_TX_C_DN<15>   @S9S_MB_2U_LIB.S9S_MB_2U(SCH_1):P5E_CPU1_PE3_TX_C_DN<15>
  C1516    1      1  Q_CAP_DIFFBUS  I302
  J35    B69  SIGNAL_B69  SCONN140_G64V3431BHR  I64

P5E_CPU1_PE3_TX_C_DP<0>   @S9S_MB_2U_LIB.S9S_MB_2U(SCH_1):P5E_CPU1_PE3_TX_C_DP<0>
  C1547    1      1  Q_CAP_DIFFBUS  I229
  J35    B21  SIGNAL_B21  SCONN140_G64V3431BHR  I64

P5E_CPU1_PE3_TX_C_DP<1>   @S9S_MB_2U_LIB.S9S_MB_2U(SCH_1):P5E_CPU1_PE3_TX_C_DP<1>
  C1545    1      1  Q_CAP_DIFFBUS  I231
  J35    B23  SIGNAL_B23  SCONN140_G64V3431BHR  I64

P5E_CPU1_PE3_TX_C_DP<2>   @S9S_MB_2U_LIB.S9S_MB_2U(SCH_1):P5E_CPU1_PE3_TX_C_DP<2>
  C1543    1      1  Q_CAP_DIFFBUS  I234
  J35    B26  SIGNAL_B26  SCONN140_G64V3431BHR  I64

P5E_CPU1_PE3_TX_C_DP<3>   @S9S_MB_2U_LIB.S9S_MB_2U(SCH_1):P5E_CPU1_PE3_TX_C_DP<3>
  C1541    1      1  Q_CAP_DIFFBUS  I235
  J35    B30  SIGNAL_B30  SCONN140_G64V3431BHR  I64

P5E_CPU1_PE3_TX_C_DP<4>   @S9S_MB_2U_LIB.S9S_MB_2U(SCH_1):P5E_CPU1_PE3_TX_C_DP<4>
  C1539    1      1  Q_CAP_DIFFBUS  I237
  J35    B33  SIGNAL_B33  SCONN140_G64V3431BHR  I64

P5E_CPU1_PE3_TX_C_DP<5>   @S9S_MB_2U_LIB.S9S_MB_2U(SCH_1):P5E_CPU1_PE3_TX_C_DP<5>
  C1537    1      1  Q_CAP_DIFFBUS  I249
  J35    B36  SIGNAL_B36  SCONN140_G64V3431BHR  I64

P5E_CPU1_PE3_TX_C_DP<6>   @S9S_MB_2U_LIB.S9S_MB_2U(SCH_1):P5E_CPU1_PE3_TX_C_DP<6>
  C1535    1      1  Q_CAP_DIFFBUS  I252
  J35    B39  SIGNAL_B39  SCONN140_G64V3431BHR  I64

P5E_CPU1_PE3_TX_C_DP<7>   @S9S_MB_2U_LIB.S9S_MB_2U(SCH_1):P5E_CPU1_PE3_TX_C_DP<7>
  C1533    1      1  Q_CAP_DIFFBUS  I253
  J35    B44  SIGNAL_B44  SCONN140_G64V3431BHR  I64

P5E_CPU1_PE3_TX_C_DP<8>   @S9S_MB_2U_LIB.S9S_MB_2U(SCH_1):P5E_CPU1_PE3_TX_C_DP<8>
  C1531    1      1  Q_CAP_DIFFBUS  I278
  J35    B47  SIGNAL_B47  SCONN140_G64V3431BHR  I64

P5E_CPU1_PE3_TX_C_DP<9>   @S9S_MB_2U_LIB.S9S_MB_2U(SCH_1):P5E_CPU1_PE3_TX_C_DP<9>
  C1529    1      1  Q_CAP_DIFFBUS  I279
  J35    B50  SIGNAL_B50  SCONN140_G64V3431BHR  I64

P5E_CPU1_PE3_TX_C_DP<10>   @S9S_MB_2U_LIB.S9S_MB_2U(SCH_1):P5E_CPU1_PE3_TX_C_DP<10>
  C1527    1      1  Q_CAP_DIFFBUS  I281
  J35    B53  SIGNAL_B53  SCONN140_G64V3431BHR  I64

P5E_CPU1_PE3_TX_C_DP<11>   @S9S_MB_2U_LIB.S9S_MB_2U(SCH_1):P5E_CPU1_PE3_TX_C_DP<11>
  C1525    1      1  Q_CAP_DIFFBUS  I283
  J35    B56  SIGNAL_B56  SCONN140_G64V3431BHR  I64

P5E_CPU1_PE3_TX_C_DP<12>   @S9S_MB_2U_LIB.S9S_MB_2U(SCH_1):P5E_CPU1_PE3_TX_C_DP<12>
  C1523    1      1  Q_CAP_DIFFBUS  I285
  J35    B59  SIGNAL_B59  SCONN140_G64V3431BHR  I64

P5E_CPU1_PE3_TX_C_DP<13>   @S9S_MB_2U_LIB.S9S_MB_2U(SCH_1):P5E_CPU1_PE3_TX_C_DP<13>
  C1521    1      1  Q_CAP_DIFFBUS  I298
  J35    B62  SIGNAL_B62  SCONN140_G64V3431BHR  I64

P5E_CPU1_PE3_TX_C_DP<14>   @S9S_MB_2U_LIB.S9S_MB_2U(SCH_1):P5E_CPU1_PE3_TX_C_DP<14>
  C1519    1      1  Q_CAP_DIFFBUS  I299
  J35    B65  SIGNAL_B65  SCONN140_G64V3431BHR  I64

P5E_CPU1_PE3_TX_C_DP<15>   @S9S_MB_2U_LIB.S9S_MB_2U(SCH_1):P5E_CPU1_PE3_TX_C_DP<15>
  C1517    1      1  Q_CAP_DIFFBUS  I301
  J35    B68  SIGNAL_B68  SCONN140_G64V3431BHR  I64

P5E_CPU1_PE3_TX_DN<0>   @S9S_MB_2U_LIB.S9S_MB_2U(SCH_1):P5E_CPU1_PE3_TX_DN<0>
  C1546    2      2  Q_CAP_DIFFBUS  I230
  U1     EE86  PE3_TX_DN0  SOCKET4677_AZIFS054P001C01  I12

P5E_CPU1_PE3_TX_DN<1>   @S9S_MB_2U_LIB.S9S_MB_2U(SCH_1):P5E_CPU1_PE3_TX_DN<1>
  C1544    2      2  Q_CAP_DIFFBUS  I232
  U1     EB85  PE3_TX_DN1  SOCKET4677_AZIFS054P001C01  I12

P5E_CPU1_PE3_TX_DN<2>   @S9S_MB_2U_LIB.S9S_MB_2U(SCH_1):P5E_CPU1_PE3_TX_DN<2>
  C1542    2      2  Q_CAP_DIFFBUS  I233
  U1     DY87  PE3_TX_DN2  SOCKET4677_AZIFS054P001C01  I12

P5E_CPU1_PE3_TX_DN<3>   @S9S_MB_2U_LIB.S9S_MB_2U(SCH_1):P5E_CPU1_PE3_TX_DN<3>
  C1540    2      2  Q_CAP_DIFFBUS  I236
  U1     DV85  PE3_TX_DN3  SOCKET4677_AZIFS054P001C01  I12

P5E_CPU1_PE3_TX_DN<4>   @S9S_MB_2U_LIB.S9S_MB_2U(SCH_1):P5E_CPU1_PE3_TX_DN<4>
  C1538    2      2  Q_CAP_DIFFBUS  I238
  U1     DT87  PE3_TX_DN4  SOCKET4677_AZIFS054P001C01  I12

P5E_CPU1_PE3_TX_DN<5>   @S9S_MB_2U_LIB.S9S_MB_2U(SCH_1):P5E_CPU1_PE3_TX_DN<5>
  C1536    2      2  Q_CAP_DIFFBUS  I250
  U1     DP85  PE3_TX_DN5  SOCKET4677_AZIFS054P001C01  I12

P5E_CPU1_PE3_TX_DN<6>   @S9S_MB_2U_LIB.S9S_MB_2U(SCH_1):P5E_CPU1_PE3_TX_DN<6>
  C1534    2      2  Q_CAP_DIFFBUS  I251
  U1     DM87  PE3_TX_DN6  SOCKET4677_AZIFS054P001C01  I12

P5E_CPU1_PE3_TX_DN<7>   @S9S_MB_2U_LIB.S9S_MB_2U(SCH_1):P5E_CPU1_PE3_TX_DN<7>
  C1532    2      2  Q_CAP_DIFFBUS  I254
  U1     DK85  PE3_TX_DN7  SOCKET4677_AZIFS054P001C01  I12

P5E_CPU1_PE3_TX_DN<8>   @S9S_MB_2U_LIB.S9S_MB_2U(SCH_1):P5E_CPU1_PE3_TX_DN<8>
  C1530    2      2  Q_CAP_DIFFBUS  I277
  U1     DH87  PE3_TX_DN8  SOCKET4677_AZIFS054P001C01  I12

P5E_CPU1_PE3_TX_DN<9>   @S9S_MB_2U_LIB.S9S_MB_2U(SCH_1):P5E_CPU1_PE3_TX_DN<9>
  C1528    2      2  Q_CAP_DIFFBUS  I280
  U1     DF85  PE3_TX_DN9  SOCKET4677_AZIFS054P001C01  I12

P5E_CPU1_PE3_TX_DN<10>   @S9S_MB_2U_LIB.S9S_MB_2U(SCH_1):P5E_CPU1_PE3_TX_DN<10>
  C1526    2      2  Q_CAP_DIFFBUS  I282
  U1     DD87  PE3_TX_DN10  SOCKET4677_AZIFS054P001C01  I12

P5E_CPU1_PE3_TX_DN<11>   @S9S_MB_2U_LIB.S9S_MB_2U(SCH_1):P5E_CPU1_PE3_TX_DN<11>
  C1524    2      2  Q_CAP_DIFFBUS  I284
  U1     DB85  PE3_TX_DN11  SOCKET4677_AZIFS054P001C01  I12

P5E_CPU1_PE3_TX_DN<12>   @S9S_MB_2U_LIB.S9S_MB_2U(SCH_1):P5E_CPU1_PE3_TX_DN<12>
  C1522    2      2  Q_CAP_DIFFBUS  I286
  U1     CY87  PE3_TX_DN12  SOCKET4677_AZIFS054P001C01  I12

P5E_CPU1_PE3_TX_DN<13>   @S9S_MB_2U_LIB.S9S_MB_2U(SCH_1):P5E_CPU1_PE3_TX_DN<13>
  C1520    2      2  Q_CAP_DIFFBUS  I297
  U1     CV85  PE3_TX_DN13  SOCKET4677_AZIFS054P001C01  I12

P5E_CPU1_PE3_TX_DN<14>   @S9S_MB_2U_LIB.S9S_MB_2U(SCH_1):P5E_CPU1_PE3_TX_DN<14>
  C1518    2      2  Q_CAP_DIFFBUS  I300
  U1     CT87  PE3_TX_DN14  SOCKET4677_AZIFS054P001C01  I12

P5E_CPU1_PE3_TX_DN<15>   @S9S_MB_2U_LIB.S9S_MB_2U(SCH_1):P5E_CPU1_PE3_TX_DN<15>
  C1516    2      2  Q_CAP_DIFFBUS  I302
  U1     CP85  PE3_TX_DN15  SOCKET4677_AZIFS054P001C01  I12

P5E_CPU1_PE3_TX_DP<0>   @S9S_MB_2U_LIB.S9S_MB_2U(SCH_1):P5E_CPU1_PE3_TX_DP<0>
  C1547    2      2  Q_CAP_DIFFBUS  I229
  U1     ED87  PE3_TX_DP0  SOCKET4677_AZIFS054P001C01  I12

P5E_CPU1_PE3_TX_DP<1>   @S9S_MB_2U_LIB.S9S_MB_2U(SCH_1):P5E_CPU1_PE3_TX_DP<1>
  C1545    2      2  Q_CAP_DIFFBUS  I231
  U1     EC86  PE3_TX_DP1  SOCKET4677_AZIFS054P001C01  I12

P5E_CPU1_PE3_TX_DP<2>   @S9S_MB_2U_LIB.S9S_MB_2U(SCH_1):P5E_CPU1_PE3_TX_DP<2>
  C1543    2      2  Q_CAP_DIFFBUS  I234
  U1     EA86  PE3_TX_DP2  SOCKET4677_AZIFS054P001C01  I12

P5E_CPU1_PE3_TX_DP<3>   @S9S_MB_2U_LIB.S9S_MB_2U(SCH_1):P5E_CPU1_PE3_TX_DP<3>
  C1541    2      2  Q_CAP_DIFFBUS  I235
  U1     DW86  PE3_TX_DP3  SOCKET4677_AZIFS054P001C01  I12

P5E_CPU1_PE3_TX_DP<4>   @S9S_MB_2U_LIB.S9S_MB_2U(SCH_1):P5E_CPU1_PE3_TX_DP<4>
  C1539    2      2  Q_CAP_DIFFBUS  I237
  U1     DU86  PE3_TX_DP4  SOCKET4677_AZIFS054P001C01  I12

P5E_CPU1_PE3_TX_DP<5>   @S9S_MB_2U_LIB.S9S_MB_2U(SCH_1):P5E_CPU1_PE3_TX_DP<5>
  C1537    2      2  Q_CAP_DIFFBUS  I249
  U1     DR86  PE3_TX_DP5  SOCKET4677_AZIFS054P001C01  I12

P5E_CPU1_PE3_TX_DP<6>   @S9S_MB_2U_LIB.S9S_MB_2U(SCH_1):P5E_CPU1_PE3_TX_DP<6>
  C1535    2      2  Q_CAP_DIFFBUS  I252
  U1     DN86  PE3_TX_DP6  SOCKET4677_AZIFS054P001C01  I12

P5E_CPU1_PE3_TX_DP<7>   @S9S_MB_2U_LIB.S9S_MB_2U(SCH_1):P5E_CPU1_PE3_TX_DP<7>
  C1533    2      2  Q_CAP_DIFFBUS  I253
  U1     DL86  PE3_TX_DP7  SOCKET4677_AZIFS054P001C01  I12

P5E_CPU1_PE3_TX_DP<8>   @S9S_MB_2U_LIB.S9S_MB_2U(SCH_1):P5E_CPU1_PE3_TX_DP<8>
  C1531    2      2  Q_CAP_DIFFBUS  I278
  U1     DJ86  PE3_TX_DP8  SOCKET4677_AZIFS054P001C01  I12

P5E_CPU1_PE3_TX_DP<9>   @S9S_MB_2U_LIB.S9S_MB_2U(SCH_1):P5E_CPU1_PE3_TX_DP<9>
  C1529    2      2  Q_CAP_DIFFBUS  I279
  U1     DG86  PE3_TX_DP9  SOCKET4677_AZIFS054P001C01  I12

P5E_CPU1_PE3_TX_DP<10>   @S9S_MB_2U_LIB.S9S_MB_2U(SCH_1):P5E_CPU1_PE3_TX_DP<10>
  C1527    2      2  Q_CAP_DIFFBUS  I281
  U1     DE86  PE3_TX_DP10  SOCKET4677_AZIFS054P001C01  I12

P5E_CPU1_PE3_TX_DP<11>   @S9S_MB_2U_LIB.S9S_MB_2U(SCH_1):P5E_CPU1_PE3_TX_DP<11>
  C1525    2      2  Q_CAP_DIFFBUS  I283
  U1     DC86  PE3_TX_DP11  SOCKET4677_AZIFS054P001C01  I12

P5E_CPU1_PE3_TX_DP<12>   @S9S_MB_2U_LIB.S9S_MB_2U(SCH_1):P5E_CPU1_PE3_TX_DP<12>
  C1523    2      2  Q_CAP_DIFFBUS  I285
  U1     DA86  PE3_TX_DP12  SOCKET4677_AZIFS054P001C01  I12

P5E_CPU1_PE3_TX_DP<13>   @S9S_MB_2U_LIB.S9S_MB_2U(SCH_1):P5E_CPU1_PE3_TX_DP<13>
  C1521    2      2  Q_CAP_DIFFBUS  I298
  U1     CW86  PE3_TX_DP13  SOCKET4677_AZIFS054P001C01  I12

P5E_CPU1_PE3_TX_DP<14>   @S9S_MB_2U_LIB.S9S_MB_2U(SCH_1):P5E_CPU1_PE3_TX_DP<14>
  C1519    2      2  Q_CAP_DIFFBUS  I299
  U1     CU86  PE3_TX_DP14  SOCKET4677_AZIFS054P001C01  I12

P5E_CPU1_PE3_TX_DP<15>   @S9S_MB_2U_LIB.S9S_MB_2U(SCH_1):P5E_CPU1_PE3_TX_DP<15>
  C1517    2      2  Q_CAP_DIFFBUS  I301
  U1     CR86  PE3_TX_DP15  SOCKET4677_AZIFS054P001C01  I12

P5E_CPU1_PE4_RX_DN<0>   @S9S_MB_2U_LIB.S9S_MB_2U(SCH_1):P5E_CPU1_PE4_RX_DN<0>
  J88    A18  PETP0  SCONN84_123318136  I16
  U1     BB89  PE4_RX_DN15  SOCKET4677_AZIFS054P001C01  I18

P5E_CPU1_PE4_RX_DN<1>   @S9S_MB_2U_LIB.S9S_MB_2U(SCH_1):P5E_CPU1_PE4_RX_DN<1>
  J88    A21  PETP1  SCONN84_123318136  I16
  U1     AY91  PE4_RX_DN14  SOCKET4677_AZIFS054P001C01  I18

P5E_CPU1_PE4_RX_DN<2>   @S9S_MB_2U_LIB.S9S_MB_2U(SCH_1):P5E_CPU1_PE4_RX_DN<2>
  J88    A23  PETN2  SCONN84_123318136  I16
  U1     AV89  PE4_RX_DN13  SOCKET4677_AZIFS054P001C01  I18

P5E_CPU1_PE4_RX_DN<3>   @S9S_MB_2U_LIB.S9S_MB_2U(SCH_1):P5E_CPU1_PE4_RX_DN<3>
  J88    A27  PETP3  SCONN84_123318136  I16
  U1     AT91  PE4_RX_DN12  SOCKET4677_AZIFS054P001C01  I18

P5E_CPU1_PE4_RX_DN<4>   @S9S_MB_2U_LIB.S9S_MB_2U(SCH_1):P5E_CPU1_PE4_RX_DN<4>
  J88    A31  PETP4  SCONN84_123318136  I16
  U1     AP89  PE4_RX_DN11  SOCKET4677_AZIFS054P001C01  I18

P5E_CPU1_PE4_RX_DN<5>   @S9S_MB_2U_LIB.S9S_MB_2U(SCH_1):P5E_CPU1_PE4_RX_DN<5>
  J88    A33  PETN5  SCONN84_123318136  I16
  U1     AM91  PE4_RX_DN10  SOCKET4677_AZIFS054P001C01  I18

P5E_CPU1_PE4_RX_DN<6>   @S9S_MB_2U_LIB.S9S_MB_2U(SCH_1):P5E_CPU1_PE4_RX_DN<6>
  J88    A37  PETP6  SCONN84_123318136  I16
  U1     AK89  PE4_RX_DN9  SOCKET4677_AZIFS054P001C01  I18

P5E_CPU1_PE4_RX_DN<7>   @S9S_MB_2U_LIB.S9S_MB_2U(SCH_1):P5E_CPU1_PE4_RX_DN<7>
  J88    A39  PETN7  SCONN84_123318136  I16
  U1     AH91  PE4_RX_DN8  SOCKET4677_AZIFS054P001C01  I18

P5E_CPU1_PE4_RX_DN<8>   @S9S_MB_2U_LIB.S9S_MB_2U(SCH_1):P5E_CPU1_PE4_RX_DN<8>
  J61    A17  PETN0  SCONN84_123318136  I49
  U1     AF89  PE4_RX_DN7  SOCKET4677_AZIFS054P001C01  I18

P5E_CPU1_PE4_RX_DN<9>   @S9S_MB_2U_LIB.S9S_MB_2U(SCH_1):P5E_CPU1_PE4_RX_DN<9>
  J61    A21  PETP1  SCONN84_123318136  I49
  U1     AD91  PE4_RX_DN6  SOCKET4677_AZIFS054P001C01  I18

P5E_CPU1_PE4_RX_DN<10>   @S9S_MB_2U_LIB.S9S_MB_2U(SCH_1):P5E_CPU1_PE4_RX_DN<10>
  J61    A23  PETN2  SCONN84_123318136  I49
  U1     AB89  PE4_RX_DN5  SOCKET4677_AZIFS054P001C01  I18

P5E_CPU1_PE4_RX_DN<11>   @S9S_MB_2U_LIB.S9S_MB_2U(SCH_1):P5E_CPU1_PE4_RX_DN<11>
  J61    A27  PETP3  SCONN84_123318136  I49
  U1     Y91  PE4_RX_DN4  SOCKET4677_AZIFS054P001C01  I18

P5E_CPU1_PE4_RX_DN<12>   @S9S_MB_2U_LIB.S9S_MB_2U(SCH_1):P5E_CPU1_PE4_RX_DN<12>
  J61    A31  PETP4  SCONN84_123318136  I49
  U1     V89  PE4_RX_DN3  SOCKET4677_AZIFS054P001C01  I18

P5E_CPU1_PE4_RX_DN<13>   @S9S_MB_2U_LIB.S9S_MB_2U(SCH_1):P5E_CPU1_PE4_RX_DN<13>
  J61    A33  PETN5  SCONN84_123318136  I49
  U1     T91  PE4_RX_DN2  SOCKET4677_AZIFS054P001C01  I18

P5E_CPU1_PE4_RX_DN<14>   @S9S_MB_2U_LIB.S9S_MB_2U(SCH_1):P5E_CPU1_PE4_RX_DN<14>
  J61    A37  PETP6  SCONN84_123318136  I49
  U1     P89  PE4_RX_DN1  SOCKET4677_AZIFS054P001C01  I18

P5E_CPU1_PE4_RX_DN<15>   @S9S_MB_2U_LIB.S9S_MB_2U(SCH_1):P5E_CPU1_PE4_RX_DN<15>
  J61    A39  PETN7  SCONN84_123318136  I49
  U1     J90  PE4_RX_DN0  SOCKET4677_AZIFS054P001C01  I18

P5E_CPU1_PE4_RX_DP<0>   @S9S_MB_2U_LIB.S9S_MB_2U(SCH_1):P5E_CPU1_PE4_RX_DP<0>
  J88    A17  PETN0  SCONN84_123318136  I16
  U1     BA90  PE4_RX_DP15  SOCKET4677_AZIFS054P001C01  I18

P5E_CPU1_PE4_RX_DP<1>   @S9S_MB_2U_LIB.S9S_MB_2U(SCH_1):P5E_CPU1_PE4_RX_DP<1>
  J88    A20  PETN1  SCONN84_123318136  I16
  U1     AW90  PE4_RX_DP14  SOCKET4677_AZIFS054P001C01  I18

P5E_CPU1_PE4_RX_DP<2>   @S9S_MB_2U_LIB.S9S_MB_2U(SCH_1):P5E_CPU1_PE4_RX_DP<2>
  J88    A24  PETP2  SCONN84_123318136  I16
  U1     AU90  PE4_RX_DP13  SOCKET4677_AZIFS054P001C01  I18

P5E_CPU1_PE4_RX_DP<3>   @S9S_MB_2U_LIB.S9S_MB_2U(SCH_1):P5E_CPU1_PE4_RX_DP<3>
  J88    A26  PETN3  SCONN84_123318136  I16
  U1     AR90  PE4_RX_DP12  SOCKET4677_AZIFS054P001C01  I18

P5E_CPU1_PE4_RX_DP<4>   @S9S_MB_2U_LIB.S9S_MB_2U(SCH_1):P5E_CPU1_PE4_RX_DP<4>
  J88    A30  PETN4  SCONN84_123318136  I16
  U1     AN90  PE4_RX_DP11  SOCKET4677_AZIFS054P001C01  I18

P5E_CPU1_PE4_RX_DP<5>   @S9S_MB_2U_LIB.S9S_MB_2U(SCH_1):P5E_CPU1_PE4_RX_DP<5>
  J88    A34  PETP5  SCONN84_123318136  I16
  U1     AL90  PE4_RX_DP10  SOCKET4677_AZIFS054P001C01  I18

P5E_CPU1_PE4_RX_DP<6>   @S9S_MB_2U_LIB.S9S_MB_2U(SCH_1):P5E_CPU1_PE4_RX_DP<6>
  J88    A36  PETN6  SCONN84_123318136  I16
  U1     AJ90  PE4_RX_DP9  SOCKET4677_AZIFS054P001C01  I18

P5E_CPU1_PE4_RX_DP<7>   @S9S_MB_2U_LIB.S9S_MB_2U(SCH_1):P5E_CPU1_PE4_RX_DP<7>
  J88    A40  PETP7  SCONN84_123318136  I16
  U1     AG90  PE4_RX_DP8  SOCKET4677_AZIFS054P001C01  I18

P5E_CPU1_PE4_RX_DP<8>   @S9S_MB_2U_LIB.S9S_MB_2U(SCH_1):P5E_CPU1_PE4_RX_DP<8>
  J61    A18  PETP0  SCONN84_123318136  I49
  U1     AE90  PE4_RX_DP7  SOCKET4677_AZIFS054P001C01  I18

P5E_CPU1_PE4_RX_DP<9>   @S9S_MB_2U_LIB.S9S_MB_2U(SCH_1):P5E_CPU1_PE4_RX_DP<9>
  J61    A20  PETN1  SCONN84_123318136  I49
  U1     AC90  PE4_RX_DP6  SOCKET4677_AZIFS054P001C01  I18

P5E_CPU1_PE4_RX_DP<10>   @S9S_MB_2U_LIB.S9S_MB_2U(SCH_1):P5E_CPU1_PE4_RX_DP<10>
  J61    A24  PETP2  SCONN84_123318136  I49
  U1     AA90  PE4_RX_DP5  SOCKET4677_AZIFS054P001C01  I18

P5E_CPU1_PE4_RX_DP<11>   @S9S_MB_2U_LIB.S9S_MB_2U(SCH_1):P5E_CPU1_PE4_RX_DP<11>
  J61    A26  PETN3  SCONN84_123318136  I49
  U1     W90  PE4_RX_DP4  SOCKET4677_AZIFS054P001C01  I18

P5E_CPU1_PE4_RX_DP<12>   @S9S_MB_2U_LIB.S9S_MB_2U(SCH_1):P5E_CPU1_PE4_RX_DP<12>
  J61    A30  PETN4  SCONN84_123318136  I49
  U1     U90  PE4_RX_DP3  SOCKET4677_AZIFS054P001C01  I18

P5E_CPU1_PE4_RX_DP<13>   @S9S_MB_2U_LIB.S9S_MB_2U(SCH_1):P5E_CPU1_PE4_RX_DP<13>
  J61    A34  PETP5  SCONN84_123318136  I49
  U1     R90  PE4_RX_DP2  SOCKET4677_AZIFS054P001C01  I18

P5E_CPU1_PE4_RX_DP<14>   @S9S_MB_2U_LIB.S9S_MB_2U(SCH_1):P5E_CPU1_PE4_RX_DP<14>
  J61    A36  PETN6  SCONN84_123318136  I49
  U1     N90  PE4_RX_DP1  SOCKET4677_AZIFS054P001C01  I18

P5E_CPU1_PE4_RX_DP<15>   @S9S_MB_2U_LIB.S9S_MB_2U(SCH_1):P5E_CPU1_PE4_RX_DP<15>
  J61    A40  PETP7  SCONN84_123318136  I49
  U1     K89  PE4_RX_DP0  SOCKET4677_AZIFS054P001C01  I18

P5E_CPU1_PE4_TX_C_DN<0>   @S9S_MB_2U_LIB.S9S_MB_2U(SCH_1):P5E_CPU1_PE4_TX_C_DN<0>
  C708     1      1  Q_CAP_DIFFBUS  I125
  J88    B17  PERN0  SCONN84_123318136  I16

P5E_CPU1_PE4_TX_C_DN<1>   @S9S_MB_2U_LIB.S9S_MB_2U(SCH_1):P5E_CPU1_PE4_TX_C_DN<1>
  C706     1      1  Q_CAP_DIFFBUS  I127
  J88    B21  PERP1  SCONN84_123318136  I16

P5E_CPU1_PE4_TX_C_DN<2>   @S9S_MB_2U_LIB.S9S_MB_2U(SCH_1):P5E_CPU1_PE4_TX_C_DN<2>
  C704     1      1  Q_CAP_DIFFBUS  I129
  J88    B24  PERP2  SCONN84_123318136  I16

P5E_CPU1_PE4_TX_C_DN<3>   @S9S_MB_2U_LIB.S9S_MB_2U(SCH_1):P5E_CPU1_PE4_TX_C_DN<3>
  C702     1      1  Q_CAP_DIFFBUS  I132
  J88    B27  PERP3  SCONN84_123318136  I16

P5E_CPU1_PE4_TX_C_DN<4>   @S9S_MB_2U_LIB.S9S_MB_2U(SCH_1):P5E_CPU1_PE4_TX_C_DN<4>
  C700     1      1  Q_CAP_DIFFBUS  I134
  J88    B31  PERP4  SCONN84_123318136  I16

P5E_CPU1_PE4_TX_C_DN<5>   @S9S_MB_2U_LIB.S9S_MB_2U(SCH_1):P5E_CPU1_PE4_TX_C_DN<5>
  C698     1      1  Q_CAP_DIFFBUS  I135
  J88    B34  PERP5  SCONN84_123318136  I16

P5E_CPU1_PE4_TX_C_DN<6>   @S9S_MB_2U_LIB.S9S_MB_2U(SCH_1):P5E_CPU1_PE4_TX_C_DN<6>
  C696     1      1  Q_CAP_DIFFBUS  I137
  J88    B37  PERP6  SCONN84_123318136  I16

P5E_CPU1_PE4_TX_C_DN<7>   @S9S_MB_2U_LIB.S9S_MB_2U(SCH_1):P5E_CPU1_PE4_TX_C_DN<7>
  C694     1      1  Q_CAP_DIFFBUS  I140
  J88    B40  PERP7  SCONN84_123318136  I16

P5E_CPU1_PE4_TX_C_DN<8>   @S9S_MB_2U_LIB.S9S_MB_2U(SCH_1):P5E_CPU1_PE4_TX_C_DN<8>
  C692     1      1  Q_CAP_DIFFBUS  I158
  J61    B18  PERP0  SCONN84_123318136  I49

P5E_CPU1_PE4_TX_C_DN<9>   @S9S_MB_2U_LIB.S9S_MB_2U(SCH_1):P5E_CPU1_PE4_TX_C_DN<9>
  C690     1      1  Q_CAP_DIFFBUS  I159
  J61    B21  PERP1  SCONN84_123318136  I49

P5E_CPU1_PE4_TX_C_DN<10>   @S9S_MB_2U_LIB.S9S_MB_2U(SCH_1):P5E_CPU1_PE4_TX_C_DN<10>
  C688     1      1  Q_CAP_DIFFBUS  I162
  J61    B24  PERP2  SCONN84_123318136  I49

P5E_CPU1_PE4_TX_C_DN<11>   @S9S_MB_2U_LIB.S9S_MB_2U(SCH_1):P5E_CPU1_PE4_TX_C_DN<11>
  C686     1      1  Q_CAP_DIFFBUS  I164
  J61    B27  PERP3  SCONN84_123318136  I49

P5E_CPU1_PE4_TX_C_DN<12>   @S9S_MB_2U_LIB.S9S_MB_2U(SCH_1):P5E_CPU1_PE4_TX_C_DN<12>
  C684     1      1  Q_CAP_DIFFBUS  I166
  J61    B31  PERP4  SCONN84_123318136  I49

P5E_CPU1_PE4_TX_C_DN<13>   @S9S_MB_2U_LIB.S9S_MB_2U(SCH_1):P5E_CPU1_PE4_TX_C_DN<13>
  C682     1      1  Q_CAP_DIFFBUS  I167
  J61    B34  PERP5  SCONN84_123318136  I49

P5E_CPU1_PE4_TX_C_DN<14>   @S9S_MB_2U_LIB.S9S_MB_2U(SCH_1):P5E_CPU1_PE4_TX_C_DN<14>
  C680     1      1  Q_CAP_DIFFBUS  I170
  J61    B37  PERP6  SCONN84_123318136  I49

P5E_CPU1_PE4_TX_C_DN<15>   @S9S_MB_2U_LIB.S9S_MB_2U(SCH_1):P5E_CPU1_PE4_TX_C_DN<15>
  C678     1      1  Q_CAP_DIFFBUS  I172
  J61    B40  PERP7  SCONN84_123318136  I49

P5E_CPU1_PE4_TX_C_DP<0>   @S9S_MB_2U_LIB.S9S_MB_2U(SCH_1):P5E_CPU1_PE4_TX_C_DP<0>
  C709     1      1  Q_CAP_DIFFBUS  I126
  J88    B18  PERP0  SCONN84_123318136  I16

P5E_CPU1_PE4_TX_C_DP<1>   @S9S_MB_2U_LIB.S9S_MB_2U(SCH_1):P5E_CPU1_PE4_TX_C_DP<1>
  C707     1      1  Q_CAP_DIFFBUS  I128
  J88    B20  PERN1  SCONN84_123318136  I16

P5E_CPU1_PE4_TX_C_DP<2>   @S9S_MB_2U_LIB.S9S_MB_2U(SCH_1):P5E_CPU1_PE4_TX_C_DP<2>
  C705     1      1  Q_CAP_DIFFBUS  I130
  J88    B23  PERN2  SCONN84_123318136  I16

P5E_CPU1_PE4_TX_C_DP<3>   @S9S_MB_2U_LIB.S9S_MB_2U(SCH_1):P5E_CPU1_PE4_TX_C_DP<3>
  C703     1      1  Q_CAP_DIFFBUS  I133
  J88    B26  PERN3  SCONN84_123318136  I16

P5E_CPU1_PE4_TX_C_DP<4>   @S9S_MB_2U_LIB.S9S_MB_2U(SCH_1):P5E_CPU1_PE4_TX_C_DP<4>
  C701     1      1  Q_CAP_DIFFBUS  I131
  J88    B30  PERN4  SCONN84_123318136  I16

P5E_CPU1_PE4_TX_C_DP<5>   @S9S_MB_2U_LIB.S9S_MB_2U(SCH_1):P5E_CPU1_PE4_TX_C_DP<5>
  C699     1      1  Q_CAP_DIFFBUS  I136
  J88    B33  PERN5  SCONN84_123318136  I16

P5E_CPU1_PE4_TX_C_DP<6>   @S9S_MB_2U_LIB.S9S_MB_2U(SCH_1):P5E_CPU1_PE4_TX_C_DP<6>
  C697     1      1  Q_CAP_DIFFBUS  I138
  J88    B36  PERN6  SCONN84_123318136  I16

P5E_CPU1_PE4_TX_C_DP<7>   @S9S_MB_2U_LIB.S9S_MB_2U(SCH_1):P5E_CPU1_PE4_TX_C_DP<7>
  C695     1      1  Q_CAP_DIFFBUS  I139
  J88    B39  PERN7  SCONN84_123318136  I16

P5E_CPU1_PE4_TX_C_DP<8>   @S9S_MB_2U_LIB.S9S_MB_2U(SCH_1):P5E_CPU1_PE4_TX_C_DP<8>
  C693     1      1  Q_CAP_DIFFBUS  I157
  J61    B17  PERN0  SCONN84_123318136  I49

P5E_CPU1_PE4_TX_C_DP<9>   @S9S_MB_2U_LIB.S9S_MB_2U(SCH_1):P5E_CPU1_PE4_TX_C_DP<9>
  C691     1      1  Q_CAP_DIFFBUS  I160
  J61    B20  PERN1  SCONN84_123318136  I49

P5E_CPU1_PE4_TX_C_DP<10>   @S9S_MB_2U_LIB.S9S_MB_2U(SCH_1):P5E_CPU1_PE4_TX_C_DP<10>
  C689     1      1  Q_CAP_DIFFBUS  I163
  J61    B23  PERN2  SCONN84_123318136  I49

P5E_CPU1_PE4_TX_C_DP<11>   @S9S_MB_2U_LIB.S9S_MB_2U(SCH_1):P5E_CPU1_PE4_TX_C_DP<11>
  C687     1      1  Q_CAP_DIFFBUS  I161
  J61    B26  PERN3  SCONN84_123318136  I49

P5E_CPU1_PE4_TX_C_DP<12>   @S9S_MB_2U_LIB.S9S_MB_2U(SCH_1):P5E_CPU1_PE4_TX_C_DP<12>
  C685     1      1  Q_CAP_DIFFBUS  I165
  J61    B30  PERN4  SCONN84_123318136  I49

P5E_CPU1_PE4_TX_C_DP<13>   @S9S_MB_2U_LIB.S9S_MB_2U(SCH_1):P5E_CPU1_PE4_TX_C_DP<13>
  C683     1      1  Q_CAP_DIFFBUS  I168
  J61    B33  PERN5  SCONN84_123318136  I49

P5E_CPU1_PE4_TX_C_DP<14>   @S9S_MB_2U_LIB.S9S_MB_2U(SCH_1):P5E_CPU1_PE4_TX_C_DP<14>
  C681     1      1  Q_CAP_DIFFBUS  I171
  J61    B36  PERN6  SCONN84_123318136  I49

P5E_CPU1_PE4_TX_C_DP<15>   @S9S_MB_2U_LIB.S9S_MB_2U(SCH_1):P5E_CPU1_PE4_TX_C_DP<15>
  C679     1      1  Q_CAP_DIFFBUS  I169
  J61    B39  PERN7  SCONN84_123318136  I49

P5E_CPU1_PE4_TX_DN<0>   @S9S_MB_2U_LIB.S9S_MB_2U(SCH_1):P5E_CPU1_PE4_TX_DN<0>
  C708     2      2  Q_CAP_DIFFBUS  I125
  U1     BA86  PE4_TX_DN15  SOCKET4677_AZIFS054P001C01  I18

P5E_CPU1_PE4_TX_DN<1>   @S9S_MB_2U_LIB.S9S_MB_2U(SCH_1):P5E_CPU1_PE4_TX_DN<1>
  C706     2      2  Q_CAP_DIFFBUS  I127
  U1     AW86  PE4_TX_DN14  SOCKET4677_AZIFS054P001C01  I18

P5E_CPU1_PE4_TX_DN<2>   @S9S_MB_2U_LIB.S9S_MB_2U(SCH_1):P5E_CPU1_PE4_TX_DN<2>
  C704     2      2  Q_CAP_DIFFBUS  I129
  U1     AU86  PE4_TX_DN13  SOCKET4677_AZIFS054P001C01  I18

P5E_CPU1_PE4_TX_DN<3>   @S9S_MB_2U_LIB.S9S_MB_2U(SCH_1):P5E_CPU1_PE4_TX_DN<3>
  C702     2      2  Q_CAP_DIFFBUS  I132
  U1     AR86  PE4_TX_DN12  SOCKET4677_AZIFS054P001C01  I18

P5E_CPU1_PE4_TX_DN<4>   @S9S_MB_2U_LIB.S9S_MB_2U(SCH_1):P5E_CPU1_PE4_TX_DN<4>
  C700     2      2  Q_CAP_DIFFBUS  I134
  U1     AP85  PE4_TX_DN11  SOCKET4677_AZIFS054P001C01  I18

P5E_CPU1_PE4_TX_DN<5>   @S9S_MB_2U_LIB.S9S_MB_2U(SCH_1):P5E_CPU1_PE4_TX_DN<5>
  C698     2      2  Q_CAP_DIFFBUS  I135
  U1     AL86  PE4_TX_DN10  SOCKET4677_AZIFS054P001C01  I18

P5E_CPU1_PE4_TX_DN<6>   @S9S_MB_2U_LIB.S9S_MB_2U(SCH_1):P5E_CPU1_PE4_TX_DN<6>
  C696     2      2  Q_CAP_DIFFBUS  I137
  U1     AJ86  PE4_TX_DN9  SOCKET4677_AZIFS054P001C01  I18

P5E_CPU1_PE4_TX_DN<7>   @S9S_MB_2U_LIB.S9S_MB_2U(SCH_1):P5E_CPU1_PE4_TX_DN<7>
  C694     2      2  Q_CAP_DIFFBUS  I140
  U1     AG86  PE4_TX_DN8  SOCKET4677_AZIFS054P001C01  I18

P5E_CPU1_PE4_TX_DN<8>   @S9S_MB_2U_LIB.S9S_MB_2U(SCH_1):P5E_CPU1_PE4_TX_DN<8>
  C692     2      2  Q_CAP_DIFFBUS  I158
  U1     AE86  PE4_TX_DN7  SOCKET4677_AZIFS054P001C01  I18

P5E_CPU1_PE4_TX_DN<9>   @S9S_MB_2U_LIB.S9S_MB_2U(SCH_1):P5E_CPU1_PE4_TX_DN<9>
  C690     2      2  Q_CAP_DIFFBUS  I159
  U1     AC86  PE4_TX_DN6  SOCKET4677_AZIFS054P001C01  I18

P5E_CPU1_PE4_TX_DN<10>   @S9S_MB_2U_LIB.S9S_MB_2U(SCH_1):P5E_CPU1_PE4_TX_DN<10>
  C688     2      2  Q_CAP_DIFFBUS  I162
  U1     AA86  PE4_TX_DN5  SOCKET4677_AZIFS054P001C01  I18

P5E_CPU1_PE4_TX_DN<11>   @S9S_MB_2U_LIB.S9S_MB_2U(SCH_1):P5E_CPU1_PE4_TX_DN<11>
  C686     2      2  Q_CAP_DIFFBUS  I164
  U1     W86  PE4_TX_DN4  SOCKET4677_AZIFS054P001C01  I18

P5E_CPU1_PE4_TX_DN<12>   @S9S_MB_2U_LIB.S9S_MB_2U(SCH_1):P5E_CPU1_PE4_TX_DN<12>
  C684     2      2  Q_CAP_DIFFBUS  I166
  U1     U86  PE4_TX_DN3  SOCKET4677_AZIFS054P001C01  I18

P5E_CPU1_PE4_TX_DN<13>   @S9S_MB_2U_LIB.S9S_MB_2U(SCH_1):P5E_CPU1_PE4_TX_DN<13>
  C682     2      2  Q_CAP_DIFFBUS  I167
  U1     R86  PE4_TX_DN2  SOCKET4677_AZIFS054P001C01  I18

P5E_CPU1_PE4_TX_DN<14>   @S9S_MB_2U_LIB.S9S_MB_2U(SCH_1):P5E_CPU1_PE4_TX_DN<14>
  C680     2      2  Q_CAP_DIFFBUS  I170
  U1     P85  PE4_TX_DN1  SOCKET4677_AZIFS054P001C01  I18

P5E_CPU1_PE4_TX_DN<15>   @S9S_MB_2U_LIB.S9S_MB_2U(SCH_1):P5E_CPU1_PE4_TX_DN<15>
  C678     2      2  Q_CAP_DIFFBUS  I172
  U1     L86  PE4_TX_DN0  SOCKET4677_AZIFS054P001C01  I18

P5E_CPU1_PE4_TX_DP<0>   @S9S_MB_2U_LIB.S9S_MB_2U(SCH_1):P5E_CPU1_PE4_TX_DP<0>
  C709     2      2  Q_CAP_DIFFBUS  I126
  U1     BB85  PE4_TX_DP15  SOCKET4677_AZIFS054P001C01  I18

P5E_CPU1_PE4_TX_DP<1>   @S9S_MB_2U_LIB.S9S_MB_2U(SCH_1):P5E_CPU1_PE4_TX_DP<1>
  C707     2      2  Q_CAP_DIFFBUS  I128
  U1     AY87  PE4_TX_DP14  SOCKET4677_AZIFS054P001C01  I18

P5E_CPU1_PE4_TX_DP<2>   @S9S_MB_2U_LIB.S9S_MB_2U(SCH_1):P5E_CPU1_PE4_TX_DP<2>
  C705     2      2  Q_CAP_DIFFBUS  I130
  U1     AV85  PE4_TX_DP13  SOCKET4677_AZIFS054P001C01  I18

P5E_CPU1_PE4_TX_DP<3>   @S9S_MB_2U_LIB.S9S_MB_2U(SCH_1):P5E_CPU1_PE4_TX_DP<3>
  C703     2      2  Q_CAP_DIFFBUS  I133
  U1     AT87  PE4_TX_DP12  SOCKET4677_AZIFS054P001C01  I18

P5E_CPU1_PE4_TX_DP<4>   @S9S_MB_2U_LIB.S9S_MB_2U(SCH_1):P5E_CPU1_PE4_TX_DP<4>
  C701     2      2  Q_CAP_DIFFBUS  I131
  U1     AN86  PE4_TX_DP11  SOCKET4677_AZIFS054P001C01  I18

P5E_CPU1_PE4_TX_DP<5>   @S9S_MB_2U_LIB.S9S_MB_2U(SCH_1):P5E_CPU1_PE4_TX_DP<5>
  C699     2      2  Q_CAP_DIFFBUS  I136
  U1     AM87  PE4_TX_DP10  SOCKET4677_AZIFS054P001C01  I18

P5E_CPU1_PE4_TX_DP<6>   @S9S_MB_2U_LIB.S9S_MB_2U(SCH_1):P5E_CPU1_PE4_TX_DP<6>
  C697     2      2  Q_CAP_DIFFBUS  I138
  U1     AK85  PE4_TX_DP9  SOCKET4677_AZIFS054P001C01  I18

P5E_CPU1_PE4_TX_DP<7>   @S9S_MB_2U_LIB.S9S_MB_2U(SCH_1):P5E_CPU1_PE4_TX_DP<7>
  C695     2      2  Q_CAP_DIFFBUS  I139
  U1     AH87  PE4_TX_DP8  SOCKET4677_AZIFS054P001C01  I18

P5E_CPU1_PE4_TX_DP<8>   @S9S_MB_2U_LIB.S9S_MB_2U(SCH_1):P5E_CPU1_PE4_TX_DP<8>
  C693     2      2  Q_CAP_DIFFBUS  I157
  U1     AF85  PE4_TX_DP7  SOCKET4677_AZIFS054P001C01  I18

P5E_CPU1_PE4_TX_DP<9>   @S9S_MB_2U_LIB.S9S_MB_2U(SCH_1):P5E_CPU1_PE4_TX_DP<9>
  C691     2      2  Q_CAP_DIFFBUS  I160
  U1     AD87  PE4_TX_DP6  SOCKET4677_AZIFS054P001C01  I18

P5E_CPU1_PE4_TX_DP<10>   @S9S_MB_2U_LIB.S9S_MB_2U(SCH_1):P5E_CPU1_PE4_TX_DP<10>
  C689     2      2  Q_CAP_DIFFBUS  I163
  U1     AB85  PE4_TX_DP5  SOCKET4677_AZIFS054P001C01  I18

P5E_CPU1_PE4_TX_DP<11>   @S9S_MB_2U_LIB.S9S_MB_2U(SCH_1):P5E_CPU1_PE4_TX_DP<11>
  C687     2      2  Q_CAP_DIFFBUS  I161
  U1     Y87  PE4_TX_DP4  SOCKET4677_AZIFS054P001C01  I18

P5E_CPU1_PE4_TX_DP<12>   @S9S_MB_2U_LIB.S9S_MB_2U(SCH_1):P5E_CPU1_PE4_TX_DP<12>
  C685     2      2  Q_CAP_DIFFBUS  I165
  U1     V85  PE4_TX_DP3  SOCKET4677_AZIFS054P001C01  I18

P5E_CPU1_PE4_TX_DP<13>   @S9S_MB_2U_LIB.S9S_MB_2U(SCH_1):P5E_CPU1_PE4_TX_DP<13>
  C683     2      2  Q_CAP_DIFFBUS  I168
  U1     T87  PE4_TX_DP2  SOCKET4677_AZIFS054P001C01  I18

P5E_CPU1_PE4_TX_DP<14>   @S9S_MB_2U_LIB.S9S_MB_2U(SCH_1):P5E_CPU1_PE4_TX_DP<14>
  C681     2      2  Q_CAP_DIFFBUS  I171
  U1     N86  PE4_TX_DP1  SOCKET4677_AZIFS054P001C01  I18

P5E_CPU1_PE4_TX_DP<15>   @S9S_MB_2U_LIB.S9S_MB_2U(SCH_1):P5E_CPU1_PE4_TX_DP<15>
  C679     2      2  Q_CAP_DIFFBUS  I169
  U1     M87  PE4_TX_DP0  SOCKET4677_AZIFS054P001C01  I18

P5V             @S9S_MB_2U_LIB.S9S_MB_2U(SCH_1):P5V
  C633     1      A  Q_CAP       I61
  C638     1      A  Q_CAP       I63
  C1172    1      A  Q_CAP       I72
  C1227    1      A  Q_CAP       I82
  C1331    1      A  Q_CAP       I83
  C1337    1      A  Q_CAP       I13
  C1341    1      A  Q_CAP       I14
  D7       3      3  BAT547F     I69
  JP5      3      3  CONN3_HFK1030G000LAF  I58
  PQ1      1      1  MOSFET_NCH_1D3S  I91
  PQ1      2      2  MOSFET_NCH_1D3S  I91
  PQ1      3      3  MOSFET_NCH_1D3S  I91
  PR402    1      A  Q_RES       I31
  PR437    1      A  Q_RES       I170
  PR442    1      A  Q_RES       I13
  PR444    1      A  Q_RES       I24
  PR447    1      A  Q_RES       I11
  PR635    1      A  Q_RES       I335
  PR639    1      A  Q_RES       I25
  PR668    1      A  Q_RES       I20
  PR678    1      A  Q_RES       I11
  PR701    1      A  Q_RES       I277
  PR702    1      A  Q_RES       I210
  PR706    1      A  Q_RES       I11
  R461     1      A  Q_RES       I10
  R1655    1      A  Q_RES       I71
  U27      1     IN  TPS2553DBVR1  I24
  U99      3    VDD  RT9818C44GV  I70

P5V_AUX         @S9S_MB_2U_LIB.S9S_MB_2U(SCH_1):P5V_AUX
  C1042    1      A  Q_CAP       I79
  C1170    1      A  Q_CAP       I80
  C1171    1      A  Q_CAP       I81
  C1326    1      A  Q_CAP       I73
  PC581    1      A  Q_CAP        I7
  PC1845    1      A  Q_CAPP      I33
  PC1852    1      A  Q_CAP       I37
  PC1855    1      A  Q_CAP       I34
  PC1856    1      A  Q_CAP       I35
  PC1877    2      B  Q_CAP       I31
  PL65     2      2  Q_INDUCTOR  I29
  PQ1      5      5  MOSFET_NCH_1D3S  I91
  PR92     2      B  Q_RES       I32
  PR389    1      A  Q_RES       I16
  PR396    1      A  Q_RES        I2
  PU9      3    VIN  NCP3284MNTXG  I23
  PU9      5   VDRV  NCP3284MNTXG  I23
  U79      1    VCC  SLG55221120010VTR  I62

P5V_AUX_CS      @S9S_MB_2U_LIB.S9S_MB_2U(SCH_1):P5V_AUX_CS
  PR89     1      A  Q_RES       I16
  PU181    3     CS  MPQ8633BGLEC838Z  I19

P5V_AUX_EN      @S9S_MB_2U_LIB.S9S_MB_2U(SCH_1):P5V_AUX_EN
  PC1870    1      A  Q_CAP       I10
  PR1945    2      B  Q_RES        I3
  PR1948    1      A  Q_RES        I1
  PU181    8     EN  MPQ8633BGLEC838Z  I19

P5V_AUX_FB      @S9S_MB_2U_LIB.S9S_MB_2U(SCH_1):P5V_AUX_FB
  PC1877    1      A  Q_CAP       I31
  PR91     1      A  Q_RES       I25
  PR92     1      A  Q_RES       I32
  PU181    7     FB  MPQ8633BGLEC838Z  I19

P5V_AUX_REF     @S9S_MB_2U_LIB.S9S_MB_2U(SCH_1):P5V_AUX_REF
  PC1853    1      A  Q_CAP       I22
  PU181    5  TRK_REF  MPQ8633BGLEC838Z  I19

P5V_AUX_VCC     @S9S_MB_2U_LIB.S9S_MB_2U(SCH_1):P5V_AUX_VCC
  PC1848    1      A  Q_CAP        I8
  PR90     1      A  Q_RES       I27
  PU181    4   MODE  MPQ8633BGLEC838Z  I19
  PU181   19    VCC  MPQ8633BGLEC838Z  I19

P5V_USB_INT     @S9S_MB_2U_LIB.S9S_MB_2U(SCH_1):P5V_USB_INT
  C1342    1      A  Q_CAP       I50
  C1343    1      A  Q_CAP       I51
  J48      1   VBUS  CONN9_2UB3903013101F  I39
  U27      6    OUT  TPS2553DBVR1  I24

PCA9546_PCIE0_ADDR0   @S9S_MB_2U_LIB.S9S_MB_2U(SCH_1):PCA9546_PCIE0_ADDR0
  R540     2      B  Q_RES       I10
  R587     1      A  Q_RES        I6
  U36      1     A0  PCA9546APWR  I179

PCA9546_PCIE0_ADDR1   @S9S_MB_2U_LIB.S9S_MB_2U(SCH_1):PCA9546_PCIE0_ADDR1
  R538     2      B  Q_RES        I9
  R539     1      A  Q_RES        I4
  U36      2     A1  PCA9546APWR  I179

PCA9546_PCIE0_ADDR2   @S9S_MB_2U_LIB.S9S_MB_2U(SCH_1):PCA9546_PCIE0_ADDR2
  R536     2      B  Q_RES        I7
  R537     1      A  Q_RES        I2
  U36     13     A2  PCA9546APWR  I179

PCA9546_PCIE1_ADDR0   @S9S_MB_2U_LIB.S9S_MB_2U(SCH_1):PCA9546_PCIE1_ADDR0
  R645     2      B  Q_RES       I57
  R646     1      A  Q_RES       I56
  U10      1     A0  PCA9546APWR  I194

PCA9546_PCIE1_ADDR1   @S9S_MB_2U_LIB.S9S_MB_2U(SCH_1):PCA9546_PCIE1_ADDR1
  R643     2      B  Q_RES       I58
  R644     1      A  Q_RES       I55
  U10      2     A1  PCA9546APWR  I194

PCA9546_PCIE1_ADDR2   @S9S_MB_2U_LIB.S9S_MB_2U(SCH_1):PCA9546_PCIE1_ADDR2
  R641     2      B  Q_RES       I54
  R642     1      A  Q_RES       I53
  U10     13     A2  PCA9546APWR  I194

PCA9546_PCIE3_ADDR0   @S9S_MB_2U_LIB.S9S_MB_2U(SCH_1):PCA9546_PCIE3_ADDR0
  R2195    2      B  Q_RES       I114
  R2196    1      A  Q_RES       I118
  U141     1     A0  PCA9546APWR  I91

PCA9546_PCIE3_ADDR1   @S9S_MB_2U_LIB.S9S_MB_2U(SCH_1):PCA9546_PCIE3_ADDR1
  R2193    2      B  Q_RES       I115
  R2194    1      A  Q_RES       I117
  U141     2     A1  PCA9546APWR  I91

PCA9546_PCIE3_ADDR2   @S9S_MB_2U_LIB.S9S_MB_2U(SCH_1):PCA9546_PCIE3_ADDR2
  R2191    2      B  Q_RES       I113
  R2192    1      A  Q_RES       I116
  U141    13     A2  PCA9546APWR  I91

PCA9548_PCIE2_ADDR0   @S9S_MB_2U_LIB.S9S_MB_2U(SCH_1):PCA9548_PCIE2_ADDR0
  R785     2      B  Q_RES       I13
  R786     1      A  Q_RES       I12
  U24      1     A0  PCA9548APW  I60

PCA9548_PCIE2_ADDR1   @S9S_MB_2U_LIB.S9S_MB_2U(SCH_1):PCA9548_PCIE2_ADDR1
  R783     2      B  Q_RES       I10
  R784     1      A  Q_RES        I8
  U24      2     A1  PCA9548APW  I60

PCA9548_PCIE2_ADDR2   @S9S_MB_2U_LIB.S9S_MB_2U(SCH_1):PCA9548_PCIE2_ADDR2
  R781     2      B  Q_RES        I9
  R782     1      A  Q_RES        I6
  U24     21     A2  PCA9548APW  I60

PCA9555_1_ADD0   @S9S_MB_2U_LIB.S9S_MB_2U(SCH_1):PCA9555_1_ADD0
  R2097    2      B  Q_RES       I50
  R2098    1      A  Q_RES       I47
  U130    21     A0  PCA9555PW    I1

PCA9555_1_ADD1   @S9S_MB_2U_LIB.S9S_MB_2U(SCH_1):PCA9555_1_ADD1
  R2093    2      B  Q_RES       I49
  R2094    1      A  Q_RES       I46
  U130     2     A1  PCA9555PW    I1

PCA9555_1_ADD2   @S9S_MB_2U_LIB.S9S_MB_2U(SCH_1):PCA9555_1_ADD2
  R2089    2      B  Q_RES       I48
  R2090    1      A  Q_RES       I45
  U130     3     A2  PCA9555PW    I1

PCA9555_2_ADD0   @S9S_MB_2U_LIB.S9S_MB_2U(SCH_1):PCA9555_2_ADD0
  R2099    2      B  Q_RES       I66
  R2100    1      A  Q_RES       I67
  U131    21     A0  PCA9555PW   I51

PCA9555_2_ADD1   @S9S_MB_2U_LIB.S9S_MB_2U(SCH_1):PCA9555_2_ADD1
  R2095    2      B  Q_RES       I70
  R2096    1      A  Q_RES       I72
  U131     2     A1  PCA9555PW   I51

PCA9555_2_ADD2   @S9S_MB_2U_LIB.S9S_MB_2U(SCH_1):PCA9555_2_ADD2
  R2091    2      B  Q_RES       I71
  R2092    1      A  Q_RES       I74
  U131     3     A2  PCA9555PW   I51

PCH_PCIEUP_RCOMPN   @S9S_MB_2U_LIB.S9S_MB_2U(SCH_1):PCH_PCIEUP_RCOMPN
  R495     2      B  Q_RES       I118
  U4     AP31  PHY_PCIE3_RCOMPN  EMMITSBURG_REV0P9  I119

PCH_PCIEUP_RCOMPP   @S9S_MB_2U_LIB.S9S_MB_2U(SCH_1):PCH_PCIEUP_RCOMPP
  R495     1      A  Q_RES       I118
  U4     AR29  PHY_PCIE3_RCOMPP  EMMITSBURG_REV0P9  I119

PCIE_M2_SSD0_PRSNT_N   @S9S_MB_2U_LIB.S9S_MB_2U(SCH_1):PCIE_M2_SSD0_PRSNT_N
  J59      1   GND1  SCONN75K_APCI0155P004A  I178
  R478     2      B  Q_RES       I176
  U122   F10  DIFFIO_RX_T14P  10M04SAU324I7G  I155

PCIE_RISER1_PRSNT2_N   @S9S_MB_2U_LIB.S9S_MB_2U(SCH_1):PCIE_RISER1_PRSNT2_N
  J55    A70  GND_A70  SCONN140_G64V3431BHR  I150
  R2170    2      B  Q_RES       I132

PCIE_RISER2_PRSNT_N   @S9S_MB_2U_LIB.S9S_MB_2U(SCH_1):PCIE_RISER2_PRSNT_N
  J89    A140   A140  SCONN280_ME1028040102011  I282
  R2158    2      B  Q_RES       I402

PCIE_RISER3_PRSNT2_N   @S9S_MB_2U_LIB.S9S_MB_2U(SCH_1):PCIE_RISER3_PRSNT2_N
  J57    A70  GND_A70  SCONN140_G64V3431BHR  I242
  R392     2      B  Q_RES       I335
  U4      V8  GPP_M_5  EMMITSBURG_REV0P9  I22

PD_74CB_A9      @S9S_MB_2U_LIB.S9S_MB_2U(SCH_1):PD_74CB_A9
  R746     1      A  Q_RES       I90
  U17      9     3A  74CBTLV3126PW  I80

PD_BIOS_IMAGE_SWAP_N   @S9S_MB_2U_LIB.S9S_MB_2U(SCH_1):PD_BIOS_IMAGE_SWAP_N
  R1324    2      B  Q_RES       I26
  S1       4     A4  SW8S_DHNF04FTVTR   I4

PD_CHA_CPU0_DIMM1_SAA   @S9S_MB_2U_LIB.S9S_MB_2U(SCH_1):PD_CHA_CPU0_DIMM1_SAA
  J1     148    HAS  SCONN288_ADR50001P013C01  I198
  R26      1      A  Q_RES       I196

PD_CHA_CPU0_DIMM2_SAA   @S9S_MB_2U_LIB.S9S_MB_2U(SCH_1):PD_CHA_CPU0_DIMM2_SAA
  J2     148    HAS  SCONN288_ADR50001P003C01  I177
  R27      1      A  Q_RES       I10

PD_CHA_CPU1_DIMM1_SAA   @S9S_MB_2U_LIB.S9S_MB_2U(SCH_1):PD_CHA_CPU1_DIMM1_SAA
  J17    148    HAS  SCONN288_ADR50001P013C01  I12
  R42      1      A  Q_RES       I11

PD_CHA_CPU1_DIMM2_SAA   @S9S_MB_2U_LIB.S9S_MB_2U(SCH_1):PD_CHA_CPU1_DIMM2_SAA
  J18    148    HAS  SCONN288_ADR50001P003C01  I24
  R43      1      A  Q_RES        I2

PD_CHB_CPU0_DIMM1_SAA   @S9S_MB_2U_LIB.S9S_MB_2U(SCH_1):PD_CHB_CPU0_DIMM1_SAA
  J3     148    HAS  SCONN288_ADR50001P013C01  I11
  R28      1      A  Q_RES       I10

PD_CHB_CPU0_DIMM2_SAA   @S9S_MB_2U_LIB.S9S_MB_2U(SCH_1):PD_CHB_CPU0_DIMM2_SAA
  J4     148    HAS  SCONN288_ADR50001P003C01  I23
  R29      1      A  Q_RES        I1

PD_CHB_CPU1_DIMM1_SAA   @S9S_MB_2U_LIB.S9S_MB_2U(SCH_1):PD_CHB_CPU1_DIMM1_SAA
  J19    148    HAS  SCONN288_ADR50001P013C01  I25
  R44      1      A  Q_RES        I3

PD_CHB_CPU1_DIMM2_SAA   @S9S_MB_2U_LIB.S9S_MB_2U(SCH_1):PD_CHB_CPU1_DIMM2_SAA
  J20    148    HAS  SCONN288_ADR50001P003C01  I47
  R45      1      A  Q_RES       I46

PD_CHC_CPU0_DIMM1_SAA   @S9S_MB_2U_LIB.S9S_MB_2U(SCH_1):PD_CHC_CPU0_DIMM1_SAA
  J5     148    HAS  SCONN288_ADR50001P013C01  I24
  R30      1      A  Q_RES        I3

PD_CHC_CPU0_DIMM2_SAA   @S9S_MB_2U_LIB.S9S_MB_2U(SCH_1):PD_CHC_CPU0_DIMM2_SAA
  J6     148    HAS  SCONN288_ADR50001P003C01  I46
  R31      1      A  Q_RES       I45

PD_CHC_CPU1_DIMM1_SAA   @S9S_MB_2U_LIB.S9S_MB_2U(SCH_1):PD_CHC_CPU1_DIMM1_SAA
  J21    148    HAS  SCONN288_ADR50001P013C01  I13
  R46      1      A  Q_RES        I2

PD_CHC_CPU1_DIMM2_SAA   @S9S_MB_2U_LIB.S9S_MB_2U(SCH_1):PD_CHC_CPU1_DIMM2_SAA
  J22    148    HAS  SCONN288_ADR50001P003C01  I51
  R47      1      A  Q_RES        I2

PD_CHD_CPU0_DIMM1_SAA   @S9S_MB_2U_LIB.S9S_MB_2U(SCH_1):PD_CHD_CPU0_DIMM1_SAA
  J7     148    HAS  SCONN288_ADR50001P013C01  I12
  R32      1      A  Q_RES        I2

PD_CHD_CPU0_DIMM2_SAA   @S9S_MB_2U_LIB.S9S_MB_2U(SCH_1):PD_CHD_CPU0_DIMM2_SAA
  J8     148    HAS  SCONN288_ADR50001P003C01  I50
  R33      1      A  Q_RES        I2

PD_CHD_CPU1_DIMM1_SAA   @S9S_MB_2U_LIB.S9S_MB_2U(SCH_1):PD_CHD_CPU1_DIMM1_SAA
  J23    148    HAS  SCONN288_ADR50001P013C01  I25
  R48      1      A  Q_RES        I2

PD_CHD_CPU1_DIMM2_SAA   @S9S_MB_2U_LIB.S9S_MB_2U(SCH_1):PD_CHD_CPU1_DIMM2_SAA
  J24    148    HAS  SCONN288_ADR50001P003C01  I178
  R80      1      A  Q_RES        I2

PD_CHE_CPU0_DIMM1_SAA   @S9S_MB_2U_LIB.S9S_MB_2U(SCH_1):PD_CHE_CPU0_DIMM1_SAA
  J9     148    HAS  SCONN288_ADR50001P013C01  I12
  R34      1      A  Q_RES       I11

PD_CHE_CPU0_DIMM2_SAA   @S9S_MB_2U_LIB.S9S_MB_2U(SCH_1):PD_CHE_CPU0_DIMM2_SAA
  J10    148    HAS  SCONN288_ADR50001P003C01  I13
  R35      1      A  Q_RES        I2

PD_CHE_CPU1_DIMM1_SAA   @S9S_MB_2U_LIB.S9S_MB_2U(SCH_1):PD_CHE_CPU1_DIMM1_SAA
  J25    148    HAS  SCONN288_ADR50001P013C01  I180
  R79      1      A  Q_RES        I2

PD_CHE_CPU1_DIMM2_SAA   @S9S_MB_2U_LIB.S9S_MB_2U(SCH_1):PD_CHE_CPU1_DIMM2_SAA
  J26    148    HAS  SCONN288_ADR50001P003C01  I180
  R78      1      A  Q_RES        I2

PD_CHF_CPU0_DIMM1_SAA   @S9S_MB_2U_LIB.S9S_MB_2U(SCH_1):PD_CHF_CPU0_DIMM1_SAA
  J11    148    HAS  SCONN288_ADR50001P013C01  I25
  R36      1      A  Q_RES        I2

PD_CHF_CPU0_DIMM2_SAA   @S9S_MB_2U_LIB.S9S_MB_2U(SCH_1):PD_CHF_CPU0_DIMM2_SAA
  J12    148    HAS  SCONN288_ADR50001P003C01  I24
  R37      1      A  Q_RES        I2

PD_CHF_CPU1_DIMM1_SAA   @S9S_MB_2U_LIB.S9S_MB_2U(SCH_1):PD_CHF_CPU1_DIMM1_SAA
  J27    148    HAS  SCONN288_ADR50001P013C01  I179
  R77      1      A  Q_RES       I10

PD_CHF_CPU1_DIMM2_SAA   @S9S_MB_2U_LIB.S9S_MB_2U(SCH_1):PD_CHF_CPU1_DIMM2_SAA
  J28    148    HAS  SCONN288_ADR50001P003C01  I47
  R76      1      A  Q_RES       I46

PD_CHG_CPU0_DIMM1_SAA   @S9S_MB_2U_LIB.S9S_MB_2U(SCH_1):PD_CHG_CPU0_DIMM1_SAA
  J13    148    HAS  SCONN288_ADR50001P013C01  I11
  R38      1      A  Q_RES       I10

PD_CHG_CPU0_DIMM2_SAA   @S9S_MB_2U_LIB.S9S_MB_2U(SCH_1):PD_CHG_CPU0_DIMM2_SAA
  J14    148    HAS  SCONN288_ADR50001P003C01  I47
  R39      1      A  Q_RES       I46

PD_CHG_CPU1_DIMM1_SAA   @S9S_MB_2U_LIB.S9S_MB_2U(SCH_1):PD_CHG_CPU1_DIMM1_SAA
  J29    148    HAS  SCONN288_ADR50001P013C01  I179
  R75      1      A  Q_RES       I47

PD_CHG_CPU1_DIMM2_SAA   @S9S_MB_2U_LIB.S9S_MB_2U(SCH_1):PD_CHG_CPU1_DIMM2_SAA
  J30    148    HAS  SCONN288_ADR50001P003C01  I179
  R74      1      A  Q_RES        I5

PD_CHH_CPU0_DIMM1_SAA   @S9S_MB_2U_LIB.S9S_MB_2U(SCH_1):PD_CHH_CPU0_DIMM1_SAA
  J15    148    HAS  SCONN288_ADR50001P013C01  I48
  R40      1      A  Q_RES       I47

PD_CHH_CPU0_DIMM2_SAA   @S9S_MB_2U_LIB.S9S_MB_2U(SCH_1):PD_CHH_CPU0_DIMM2_SAA
  J16    148    HAS  SCONN288_ADR50001P003C01   I6
  R41      1      A  Q_RES        I5

PD_CHH_CPU1_DIMM1_SAA   @S9S_MB_2U_LIB.S9S_MB_2U(SCH_1):PD_CHH_CPU1_DIMM1_SAA
  J31    148    HAS  SCONN288_ADR50001P013C01  I180
  R73      1      A  Q_RES        I3

PD_CHH_CPU1_DIMM2_SAA   @S9S_MB_2U_LIB.S9S_MB_2U(SCH_1):PD_CHH_CPU1_DIMM2_SAA
  J32    148    HAS  SCONN288_ADR50001P003C01  I179
  R72      1      A  Q_RES        I2

PD_CK440_SBI_CLK   @S9S_MB_2U_LIB.S9S_MB_2U(SCH_1):PD_CK440_SBI_CLK
  R1462    1      A  Q_RES       I274
  U13    A54  SBI_CLK  9SQ440NQQI8  I180

PD_CK440_SBI_DATA_IN   @S9S_MB_2U_LIB.S9S_MB_2U(SCH_1):PD_CK440_SBI_DATA_IN
  R1500    1      A  Q_RES       I271
  U13    B43  SBI_IN  9SQ440NQQI8  I180

PD_CPU0_BIST_ENABLE   @S9S_MB_2U_LIB.S9S_MB_2U(SCH_1):PD_CPU0_BIST_ENABLE
  R293     2      B  Q_RES       I70
  U2     AT18  BIST_ENABLE  SOCKET4677_AZIFS054P001C01  I57

PD_CPU0_DMIMODE_OVERRIDE   @S9S_MB_2U_LIB.S9S_MB_2U(SCH_1):PD_CPU0_DMIMODE_OVERRIDE
  R294     2      B  Q_RES       I71
  U2     AW17  DMIMODE_OVERRIDE  SOCKET4677_AZIFS054P001C01  I57

PD_CPU0_ENH_MCECC_DIS   @S9S_MB_2U_LIB.S9S_MB_2U(SCH_1):PD_CPU0_ENH_MCECC_DIS
  R295     2      B  Q_RES       I72
  U2     CH22  ENH_MCECC_DIS  SOCKET4677_AZIFS054P001C01   I1

PD_CPU0_TXT_PLTEN   @S9S_MB_2U_LIB.S9S_MB_2U(SCH_1):PD_CPU0_TXT_PLTEN
  R292     2      B  Q_RES       I69
  U2     CT20  TXT_PLTEN  SOCKET4677_AZIFS054P001C01  I57

PD_CPU1_BIST_ENABLE   @S9S_MB_2U_LIB.S9S_MB_2U(SCH_1):PD_CPU1_BIST_ENABLE
  R289     2      B  Q_RES       I118
  U1     AT18  BIST_ENABLE  SOCKET4677_AZIFS054P001C01  I51

PD_CPU1_DMIMODE_OVERRIDE   @S9S_MB_2U_LIB.S9S_MB_2U(SCH_1):PD_CPU1_DMIMODE_OVERRIDE
  R290     2      B  Q_RES       I135
  U1     AW17  DMIMODE_OVERRIDE  SOCKET4677_AZIFS054P001C01  I51

PD_CPU1_ENH_MCECC_DIS   @S9S_MB_2U_LIB.S9S_MB_2U(SCH_1):PD_CPU1_ENH_MCECC_DIS
  R291     2      B  Q_RES       I116
  U1     CH22  ENH_MCECC_DIS  SOCKET4677_AZIFS054P001C01  I29

PD_CPU1_PROCDIS_COD_GTL_N   @S9S_MB_2U_LIB.S9S_MB_2U(SCH_1):PD_CPU1_PROCDIS_COD_GTL_N
  R1270    1      A  Q_RES       I55
  U1     DA52  PROCDIS_N  SOCKET4677_AZIFS054P001C01  I51

PD_CPU1_TXT_PLTEN   @S9S_MB_2U_LIB.S9S_MB_2U(SCH_1):PD_CPU1_TXT_PLTEN
  R288     2      B  Q_RES       I119
  U1     CT20  TXT_PLTEN  SOCKET4677_AZIFS054P001C01  I51

PD_DB2000_SMB_SA0   @S9S_MB_2U_LIB.S9S_MB_2U(SCH_1):PD_DB2000_SMB_SA0
  R569     2      B  Q_RES       I185
  R570     1      A  Q_RES       I187
  U38     B4  ^VSADR0_TRI  9QXL2001BNHGI8  I119

PD_DB2000_SMB_SA1   @S9S_MB_2U_LIB.S9S_MB_2U(SCH_1):PD_DB2000_SMB_SA1
  R567     2      B  Q_RES       I179
  R568     1      A  Q_RES       I178
  U38     B8  ^VSADR1_TRI  9QXL2001BNHGI8  I119

PD_EDSFF1A_PWRDIS   @S9S_MB_2U_LIB.S9S_MB_2U(SCH_1):PD_EDSFF1A_PWRDIS
  J62    B12  PWRDIS  SCONN84_123318136  I33
  R1970    1      A  Q_RES       I88

PD_EDSFF1B_PWRDIS   @S9S_MB_2U_LIB.S9S_MB_2U(SCH_1):PD_EDSFF1B_PWRDIS
  J87    B12  PWRDIS  SCONN84_123318136  I43
  R1980    1      A  Q_RES       I89

PD_EDSFF2A_PWRDIS   @S9S_MB_2U_LIB.S9S_MB_2U(SCH_1):PD_EDSFF2A_PWRDIS
  J33    B12  PWRDIS  SCONN84_123318136  I53
  R396     1      A  Q_RES       I78

PD_EDSFF2B_PWRDIS   @S9S_MB_2U_LIB.S9S_MB_2U(SCH_1):PD_EDSFF2B_PWRDIS
  J34    B12  PWRDIS  SCONN84_123318136  I43
  R400     1      A  Q_RES       I78

PD_EDSFF4A_PWRDIS   @S9S_MB_2U_LIB.S9S_MB_2U(SCH_1):PD_EDSFF4A_PWRDIS
  J88    B12  PWRDIS  SCONN84_123318136  I16
  R1990    1      A  Q_RES        I9

PD_EDSFF4B_PWRDIS   @S9S_MB_2U_LIB.S9S_MB_2U(SCH_1):PD_EDSFF4B_PWRDIS
  J61    B12  PWRDIS  SCONN84_123318136  I49
  R2002    1      A  Q_RES        I8

PD_EXT_CLK_SEL_CPU0   @S9S_MB_2U_LIB.S9S_MB_2U(SCH_1):PD_EXT_CLK_SEL_CPU0
  R1237    2      B  Q_RES       I160
  U2     BY24  EXT_CLK_SEL  SOCKET4677_AZIFS054P001C01  I57

PD_EXT_CLK_SEL_CPU1   @S9S_MB_2U_LIB.S9S_MB_2U(SCH_1):PD_EXT_CLK_SEL_CPU1
  R1234    2      B  Q_RES       I172
  U1     BY24  EXT_CLK_SEL  SOCKET4677_AZIFS054P001C01  I51

PD_GTL2014_BMC_JTAG_VREF_1   @S9S_MB_2U_LIB.S9S_MB_2U(SCH_1):PD_GTL2014_BMC_JTAG_VREF_1
  R1347    1      A  Q_RES       I10
  U84      4   VREF  GTL2014PW   I18

PD_GTL2014_BMC_JTAG_VREF_2   @S9S_MB_2U_LIB.S9S_MB_2U(SCH_1):PD_GTL2014_BMC_JTAG_VREF_2
  R1346    1      A  Q_RES       I34
  U83      4   VREF  GTL2014PW   I45

PD_I3C_SPD_DDR_CPU0_OE_N   @S9S_MB_2U_LIB.S9S_MB_2U(SCH_1):PD_I3C_SPD_DDR_CPU0_OE_N
  R678     1      A  Q_RES       I63
  U15     15     E*  IDTQS3VH257QG  I25

PD_I3C_SPD_DDR_CPU1_OE_N   @S9S_MB_2U_LIB.S9S_MB_2U(SCH_1):PD_I3C_SPD_DDR_CPU1_OE_N
  R661     1      A  Q_RES       I11
  U14     15     E*  IDTQS3VH257QG  I17

PD_JTAG_BMC_NTRST_N   @S9S_MB_2U_LIB.S9S_MB_2U(SCH_1):PD_JTAG_BMC_NTRST_N
  R1374    1      A  Q_RES       I103
  U86      1    1OE  74CBTLV3126PW  I84
  U86     13    4OE  74CBTLV3126PW  I84

PD_JTAG_CPU1_PLD_TCK   @S9S_MB_2U_LIB.S9S_MB_2U(SCH_1):PD_JTAG_CPU1_PLD_TCK
  R1227    1      A  Q_RES       I56
  U1     CY22  CPLD_TCK  SOCKET4677_AZIFS054P001C01   I5

PD_JTAG_DBP_B0   @S9S_MB_2U_LIB.S9S_MB_2U(SCH_1):PD_JTAG_DBP_B0
  R1369    1      A  Q_RES       I47
  U83      2     B0  GTL2014PW   I45

PD_JTAG_DBP_B2   @S9S_MB_2U_LIB.S9S_MB_2U(SCH_1):PD_JTAG_DBP_B2
  R1368    1      A  Q_RES       I48
  U83      5     B2  GTL2014PW   I45

PD_M2_1_DEVSLP   @S9S_MB_2U_LIB.S9S_MB_2U(SCH_1):PD_M2_1_DEVSLP
  J59     38  DEVSLP  SCONN75K_APCI0155P004A  I178
  R1605    1      A  Q_RES       I105

PD_MAIN_FPGA_CONFIG_SEL   @S9S_MB_2U_LIB.S9S_MB_2U(SCH_1):PD_MAIN_FPGA_CONFIG_SEL
  R1491    1      A  Q_RES       I282
  U122    G9  CONFIG_SEL  10M04SAU324I7G  I139

PD_MAIN_FPGA_F7   @S9S_MB_2U_LIB.S9S_MB_2U(SCH_1):PD_MAIN_FPGA_F7
  R1739    1      A  Q_RES       I202
  U122    F7   NC_2  10M04SAU324I7G  I139

PD_MAIN_FPGA_N13   @S9S_MB_2U_LIB.S9S_MB_2U(SCH_1):PD_MAIN_FPGA_N13
  R1738    1      A  Q_RES       I201
  U122   N13   NC_1  10M04SAU324I7G  I139

PD_MB_FRU_WP    @S9S_MB_2U_LIB.S9S_MB_2U(SCH_1):PD_MB_FRU_WP
  R710     1      A  Q_RES       I57
  U64      7    WC#  M24128BWDW6TP  I35

PD_MB_PRSNT     @S9S_MB_2U_LIB.S9S_MB_2U(SCH_1):PD_MB_PRSNT
  J44     23     23  CONN24_52SH90245BRD  I125
  R2156    1      A  Q_RES       I196

PD_ME_RCVR_N    @S9S_MB_2U_LIB.S9S_MB_2U(SCH_1):PD_ME_RCVR_N
  R1334    2      B  Q_RES       I54
  S2       3     A3  SW8S_DHNF04FTVTR  I35

PD_MP5981_0_MODE   @S9S_MB_2U_LIB.S9S_MB_2U(SCH_1):PD_MP5981_0_MODE
  R2074    1      A  Q_RES       I139
  U107     8   MODE  MP5981GLUZ  I113

PD_MP5981_1_MODE   @S9S_MB_2U_LIB.S9S_MB_2U(SCH_1):PD_MP5981_1_MODE
  R2086    1      A  Q_RES       I104
  U81      8   MODE  MP5981GLUZ  I66

PD_PASSWORD_CLEAR   @S9S_MB_2U_LIB.S9S_MB_2U(SCH_1):PD_PASSWORD_CLEAR
  R1335    2      B  Q_RES       I50
  S2       4     A4  SW8S_DHNF04FTVTR  I35

PD_PCH_USB2_COMP   @S9S_MB_2U_LIB.S9S_MB_2U(SCH_1):PD_PCH_USB2_COMP
  R496     1      A  Q_RES       I10
  U4     BB41  USB2_COMP  EMMITSBURG_REV0P9  I11

PD_PCH_XCLK_BIASREF   @S9S_MB_2U_LIB.S9S_MB_2U(SCH_1):PD_PCH_XCLK_BIASREF
  R477     1      A  Q_RES       I69
  U4     N29  XCLK_BIASREF  EMMITSBURG_REV0P9  I78

PD_PCIE_EDSFF1A_PRSNT_0_N   @S9S_MB_2U_LIB.S9S_MB_2U(SCH_1):PD_PCIE_EDSFF1A_PRSNT_0_N
  J62    A12  PRSNT0_N  SCONN84_123318136  I33
  R1972    1      A  Q_RES        I2

PD_PCIE_EDSFF1B_PRSNT_0_N   @S9S_MB_2U_LIB.S9S_MB_2U(SCH_1):PD_PCIE_EDSFF1B_PRSNT_0_N
  J87    A12  PRSNT0_N  SCONN84_123318136  I43
  R1982    1      A  Q_RES        I3

PD_PCIE_EDSFF2A_PRSNT_0_N   @S9S_MB_2U_LIB.S9S_MB_2U(SCH_1):PD_PCIE_EDSFF2A_PRSNT_0_N
  J33    A12  PRSNT0_N  SCONN84_123318136  I53
  R1614    1      A  Q_RES       I98

PD_PCIE_EDSFF2B_PRSNT_0_N   @S9S_MB_2U_LIB.S9S_MB_2U(SCH_1):PD_PCIE_EDSFF2B_PRSNT_0_N
  J34    A12  PRSNT0_N  SCONN84_123318136  I43
  R1616    1      A  Q_RES       I93

PD_PCIE_EDSFF4A_PRSNT_0_N   @S9S_MB_2U_LIB.S9S_MB_2U(SCH_1):PD_PCIE_EDSFF4A_PRSNT_0_N
  J88    A12  PRSNT0_N  SCONN84_123318136  I16
  R1992    1      A  Q_RES       I85

PD_PCIE_EDSFF4B_PRSNT_0_N   @S9S_MB_2U_LIB.S9S_MB_2U(SCH_1):PD_PCIE_EDSFF4B_PRSNT_0_N
  J61    A12  PRSNT0_N  SCONN84_123318136  I49
  R2004    1      A  Q_RES       I83

PD_PIROM_CPU0_ADDR0   @S9S_MB_2U_LIB.S9S_MB_2U(SCH_1):PD_PIROM_CPU0_ADDR0
  R335     2      B  Q_RES        I5
  R515     1      A  Q_RES        I7
  U2     CR70  I2C_PIROM_AD_0  SOCKET4677_AZIFS054P001C01   I1

PD_PIROM_CPU0_ADDR1   @S9S_MB_2U_LIB.S9S_MB_2U(SCH_1):PD_PIROM_CPU0_ADDR1
  R333     2      B  Q_RES        I6
  R334     1      A  Q_RES        I1
  U2     CT71  I2C_PIROM_AD_1  SOCKET4677_AZIFS054P001C01   I1

PD_PIROM_CPU0_ADDR2   @S9S_MB_2U_LIB.S9S_MB_2U(SCH_1):PD_PIROM_CPU0_ADDR2
  R331     2      B  Q_RES       I20
  R332     1      A  Q_RES       I21
  U2     CP71  I2C_PIROM_AD_2  SOCKET4677_AZIFS054P001C01   I1

PD_PIROM_CPU1_ADDR1   @S9S_MB_2U_LIB.S9S_MB_2U(SCH_1):PD_PIROM_CPU1_ADDR1
  R627     2      B  Q_RES       I14
  R628     1      A  Q_RES       I17
  U1     CT71  I2C_PIROM_AD_1  SOCKET4677_AZIFS054P001C01  I29

PD_PIROM_CPU1_ADDR2   @S9S_MB_2U_LIB.S9S_MB_2U(SCH_1):PD_PIROM_CPU1_ADDR2
  R625     2      B  Q_RES       I24
  R626     1      A  Q_RES       I26
  U1     CP71  I2C_PIROM_AD_2  SOCKET4677_AZIFS054P001C01  I29

PD_RCOMP_1P8_3P3   @S9S_MB_2U_LIB.S9S_MB_2U(SCH_1):PD_RCOMP_1P8_3P3
  R497     1      A  Q_RES        I2
  U4     AC13  GPIO_RCOMP_1P8_3P3  EMMITSBURG_REV0P9   I4

PD_RISER1_PRSNT1   @S9S_MB_2U_LIB.S9S_MB_2U(SCH_1):PD_RISER1_PRSNT1
  J55     B1  GND_B1  SCONN140_G64V3431BHR  I150
  R2172    1      A  Q_RES       I135

PD_RISER2_PRSNT1   @S9S_MB_2U_LIB.S9S_MB_2U(SCH_1):PD_RISER2_PRSNT1
  J89     A1     A1  SCONN280_ME1028040102011  I239
  R1574    1      A  Q_RES       I262

PD_RISER3_PRSNT1   @S9S_MB_2U_LIB.S9S_MB_2U(SCH_1):PD_RISER3_PRSNT1
  J57     B1  GND_B1  SCONN140_G64V3431BHR  I242
  R1578    1      A  Q_RES       I345

PD_RST_RTCRST_N   @S9S_MB_2U_LIB.S9S_MB_2U(SCH_1):PD_RST_RTCRST_N
  R1333    2      B  Q_RES       I49
  S2       2     A2  SW8S_DHNF04FTVTR  I35

PD_SMB_OCP1_HP_ADD0   @S9S_MB_2U_LIB.S9S_MB_2U(SCH_1):PD_SMB_OCP1_HP_ADD0
  R1127    2      B  Q_RES       I133
  R1128    1      A  Q_RES       I137
  U51     21     A0  PCA9555PW   I125

PD_SMB_OCP1_HP_ADD1   @S9S_MB_2U_LIB.S9S_MB_2U(SCH_1):PD_SMB_OCP1_HP_ADD1
  R1125    2      B  Q_RES       I134
  R1126    1      A  Q_RES       I140
  U51      2     A1  PCA9555PW   I125

PD_SMB_OCP1_HP_ADD2   @S9S_MB_2U_LIB.S9S_MB_2U(SCH_1):PD_SMB_OCP1_HP_ADD2
  R1123    2      B  Q_RES       I142
  R1124    1      A  Q_RES       I143
  U51      3     A2  PCA9555PW   I125

PD_SUSCLK       @S9S_MB_2U_LIB.S9S_MB_2U(SCH_1):PD_SUSCLK
  R1197    2      B  Q_RES       I50
  U4     AR7  SUSCLK  EMMITSBURG_REV0P9  I36

PD_TRST_P3      @S9S_MB_2U_LIB.S9S_MB_2U(SCH_1):PD_TRST_P3
  J42      8      8  SCONN60_QSH03001LDAKTR  I44
  R769     1      A  Q_RES       I102

PD_USB_INT_ILIM   @S9S_MB_2U_LIB.S9S_MB_2U(SCH_1):PD_USB_INT_ILIM
  R462     1      A  Q_RES       I25
  U27      5   ILIM  TPS2553DBVR1  I24

PECI_BMC        @S9S_MB_2U_LIB.S9S_MB_2U(SCH_1):PECI_BMC
  J41    B27  PETP3  SCONN168_623403212  I115
  R144     1      A  Q_RES        I2

PECI_CPU0_GTL_R   @S9S_MB_2U_LIB.S9S_MB_2U(SCH_1):PECI_CPU0_GTL_R
  R3       2      B  Q_RES       I21
  U2     BH24   PECI  SOCKET4677_AZIFS054P001C01  I57

PECI_CPU1_GTL_R   @S9S_MB_2U_LIB.S9S_MB_2U(SCH_1):PECI_CPU1_GTL_R
  R63      2      B  Q_RES       I10
  U1     BH24   PECI  SOCKET4677_AZIFS054P001C01  I51

PECI_CPU_GTL    @S9S_MB_2U_LIB.S9S_MB_2U(SCH_1):PECI_CPU_GTL
  R3       1      A  Q_RES       I21
  R63      1      A  Q_RES       I10
  R143     2      B  Q_RES       I16
  R144     2      B  Q_RES        I2
  R146     2      B  Q_RES        I6
  R148     1      A  Q_RES        I4

PECI_PCH        @S9S_MB_2U_LIB.S9S_MB_2U(SCH_1):PECI_PCH
  R143     1      A  Q_RES       I16
  U4     J10  ME_PECI  EMMITSBURG_REV0P9  I36

PGPPA_AUX       @S9S_MB_2U_LIB.S9S_MB_2U(SCH_1):PGPPA_AUX
  C513     1      A  Q_CAP        I5
  C535     1      A  Q_CAP        I4
  C605     1      A  Q_CAP       I37
  C606     1      A  Q_CAP       I45
  C607     1      A  Q_CAP       I36
  C608     1      A  Q_CAP       I43
  C1229    1      A  Q_CAP       I168
  C1408    1      A  Q_CAP       I206
  R1253    1      A  Q_RES       I23
  R1254    1      A  Q_RES       I24
  R1255    1      A  Q_RES       I26
  R1271    1      A  Q_RES        I5
  R1697    1      A  Q_RES       I186
  R1747    2      B  Q_RES        I2
  R1750    1      A  Q_RES       I59
  R1763    1      A  Q_RES        I7
  R1765    1      A  Q_RES       I13
  R1961    1      A  Q_RES       I70
  U54      5    VCC  74LVC1G07GV  I165
  U60      5    VCC  NC7SB3157   I34
  U61      5    VCC  NC7SB3157   I39
  U101     5    VCC  SN74LVC1G17DCKR  I205

PRSNT0_N        @S9S_MB_2U_LIB.S9S_MB_2U(SCH_1):PRSNT0_N
  J41    OCP_B3    LD#  SCONN168_623403212  I115
  R1801    1      A  Q_RES       I398

PSU1_THROTTLE_R   @S9S_MB_2U_LIB.S9S_MB_2U(SCH_1):PSU1_THROTTLE_R
  J44     19     19  CONN24_52SH90245BRD  I125
  L12      1      1  Q_INDUCTOR  I57

PUD_PCH_BOOT_MODE_CPU0   @S9S_MB_2U_LIB.S9S_MB_2U(SCH_1):PUD_PCH_BOOT_MODE_CPU0
  R252     2      B  Q_RES       I30
  U2     CF61  PCH_BOOT_MODE  SOCKET4677_AZIFS054P001C01   I1

PUD_PCH_BOOT_MODE_CPU1   @S9S_MB_2U_LIB.S9S_MB_2U(SCH_1):PUD_PCH_BOOT_MODE_CPU1
  R258     2      B  Q_RES       I44
  U1     CF61  PCH_BOOT_MODE  SOCKET4677_AZIFS054P001C01   I5

PUD_XTAL_CPU0_MODE0   @S9S_MB_2U_LIB.S9S_MB_2U(SCH_1):PUD_XTAL_CPU0_MODE0
  R1232    2      B  Q_RES       I156
  R1238    2      B  Q_RES       I161
  U2     CL72  XTAL_MODE_0  SOCKET4677_AZIFS054P001C01  I57

PUD_XTAL_CPU0_MODE1   @S9S_MB_2U_LIB.S9S_MB_2U(SCH_1):PUD_XTAL_CPU0_MODE1
  R1233    2      B  Q_RES       I158
  R1239    2      B  Q_RES       I163
  U2     CJ72  XTAL_MODE_1  SOCKET4677_AZIFS054P001C01  I57

PUD_XTAL_CPU1_MODE0   @S9S_MB_2U_LIB.S9S_MB_2U(SCH_1):PUD_XTAL_CPU1_MODE0
  R1229    2      B  Q_RES       I169
  R1235    2      B  Q_RES       I176
  U1     CL72  XTAL_MODE_0  SOCKET4677_AZIFS054P001C01  I51

PUD_XTAL_CPU1_MODE1   @S9S_MB_2U_LIB.S9S_MB_2U(SCH_1):PUD_XTAL_CPU1_MODE1
  R1230    2      B  Q_RES       I170
  R1236    2      B  Q_RES       I177
  U1     CJ72  XTAL_MODE_1  SOCKET4677_AZIFS054P001C01  I51

PU_ACPRESENT    @S9S_MB_2U_LIB.S9S_MB_2U(SCH_1):PU_ACPRESENT
  R1198    2      B  Q_RES       I48
  U4     AN7  ACPRESENT  EMMITSBURG_REV0P9  I36

PU_BIOS_RCVR_BOOT   @S9S_MB_2U_LIB.S9S_MB_2U(SCH_1):PU_BIOS_RCVR_BOOT
  R1317    2      B  Q_RES       I28
  S1       2     A2  SW8S_DHNF04FTVTR   I4

PU_CK440_SHFT_LD_N   @S9S_MB_2U_LIB.S9S_MB_2U(SCH_1):PU_CK440_SHFT_LD_N
  R1204    2      B  Q_RES       I273
  R1267    1      A  Q_RES       I276
  U13    B42  SHFT_LD#  9SQ440NQQI8  I180

PU_CLK25M_OSC_FPGA_EN   @S9S_MB_2U_LIB.S9S_MB_2U(SCH_1):PU_CLK25M_OSC_FPGA_EN
  OSC2     1     OE  Q_OSC4P     I132
  R1099    2      B  Q_RES       I136

PU_CLK_PFT_LOST_N   @S9S_MB_2U_LIB.S9S_MB_2U(SCH_1):PU_CLK_PFT_LOST_N
  R1958    2      B  Q_RES       I303
  U13     B4  PFT_LOST#  9SQ440NQQI8  I180

PU_CPU0_FRMAGENT   @S9S_MB_2U_LIB.S9S_MB_2U(SCH_1):PU_CPU0_FRMAGENT
  R277     2      B  Q_RES       I62
  U2     AU17  FRMAGENT  SOCKET4677_AZIFS054P001C01  I57

PU_CPU0_LEGACY_SKT   @S9S_MB_2U_LIB.S9S_MB_2U(SCH_1):PU_CPU0_LEGACY_SKT
  R282     2      B  Q_RES       I53
  U2     CY59  LEGACY_SKT  SOCKET4677_AZIFS054P001C01  I57

PU_CPU0_SAFE_MODE_BOOT   @S9S_MB_2U_LIB.S9S_MB_2U(SCH_1):PU_CPU0_SAFE_MODE_BOOT
  R276     2      B  Q_RES       I66
  U2     AU23  SAFE_MODE_BOOT  SOCKET4677_AZIFS054P001C01  I57

PU_CPU0_SOCKET_ID0   @S9S_MB_2U_LIB.S9S_MB_2U(SCH_1):PU_CPU0_SOCKET_ID0
  R279     2      B  Q_RES       I54
  U2     CW60  SOCKET_ID0  SOCKET4677_AZIFS054P001C01  I57

PU_CPU0_SOCKET_ID1   @S9S_MB_2U_LIB.S9S_MB_2U(SCH_1):PU_CPU0_SOCKET_ID1
  R280     2      B  Q_RES       I57
  U2     CY61  SOCKET_ID1  SOCKET4677_AZIFS054P001C01  I57

PU_CPU0_SOCKET_ID2   @S9S_MB_2U_LIB.S9S_MB_2U(SCH_1):PU_CPU0_SOCKET_ID2
  R281     2      B  Q_RES       I58
  U2     CT61  SOCKET_ID2  SOCKET4677_AZIFS054P001C01  I57

PU_CPU0_TXT_AGENT   @S9S_MB_2U_LIB.S9S_MB_2U(SCH_1):PU_CPU0_TXT_AGENT
  R275     2      B  Q_RES       I68
  U2     BT26  TXT_AGENT  SOCKET4677_AZIFS054P001C01  I57

PU_CPU0_UPI0_AC_COUPLING   @S9S_MB_2U_LIB.S9S_MB_2U(SCH_1):PU_CPU0_UPI0_AC_COUPLING
  R94      2      B  Q_RES       I25
  U2     BA23  UPI0_AC_COUPLING  SOCKET4677_AZIFS054P001C01   I1

PU_CPU0_UPI1_AC_COUPLING   @S9S_MB_2U_LIB.S9S_MB_2U(SCH_1):PU_CPU0_UPI1_AC_COUPLING
  R95      2      B  Q_RES       I23
  U2     CW19  UPI1_AC_COUPLING  SOCKET4677_AZIFS054P001C01   I1

PU_CPU0_UPI2_AC_COUPLING   @S9S_MB_2U_LIB.S9S_MB_2U(SCH_1):PU_CPU0_UPI2_AC_COUPLING
  R96      2      B  Q_RES       I22
  U2     BB65  UPI2_AC_COUPLING  SOCKET4677_AZIFS054P001C01   I1

PU_CPU0_UPI3_AC_COUPLING   @S9S_MB_2U_LIB.S9S_MB_2U(SCH_1):PU_CPU0_UPI3_AC_COUPLING
  R97      2      B  Q_RES       I114
  U2     CK71  UPI3_AC_COUPLING  SOCKET4677_AZIFS054P001C01   I1

PU_CPU1_FRMAGENT   @S9S_MB_2U_LIB.S9S_MB_2U(SCH_1):PU_CPU1_FRMAGENT
  R263     2      B  Q_RES       I125
  U1     AU17  FRMAGENT  SOCKET4677_AZIFS054P001C01  I51

PU_CPU1_LEGACY_SKT   @S9S_MB_2U_LIB.S9S_MB_2U(SCH_1):PU_CPU1_LEGACY_SKT
  R268     2      B  Q_RES       I94
  U1     CY59  LEGACY_SKT  SOCKET4677_AZIFS054P001C01  I51

PU_CPU1_SAFE_MODE_BOOT   @S9S_MB_2U_LIB.S9S_MB_2U(SCH_1):PU_CPU1_SAFE_MODE_BOOT
  R262     2      B  Q_RES       I100
  U1     AU23  SAFE_MODE_BOOT  SOCKET4677_AZIFS054P001C01  I51

PU_CPU1_SOCKET_ID0   @S9S_MB_2U_LIB.S9S_MB_2U(SCH_1):PU_CPU1_SOCKET_ID0
  R265     2      B  Q_RES       I97
  U1     CW60  SOCKET_ID0  SOCKET4677_AZIFS054P001C01  I51

PU_CPU1_SOCKET_ID1   @S9S_MB_2U_LIB.S9S_MB_2U(SCH_1):PU_CPU1_SOCKET_ID1
  R266     2      B  Q_RES       I96
  U1     CY61  SOCKET_ID1  SOCKET4677_AZIFS054P001C01  I51

PU_CPU1_SOCKET_ID2   @S9S_MB_2U_LIB.S9S_MB_2U(SCH_1):PU_CPU1_SOCKET_ID2
  R267     2      B  Q_RES       I95
  U1     CT61  SOCKET_ID2  SOCKET4677_AZIFS054P001C01  I51

PU_CPU1_TXT_AGENT   @S9S_MB_2U_LIB.S9S_MB_2U(SCH_1):PU_CPU1_TXT_AGENT
  R261     2      B  Q_RES       I101
  U1     BT26  TXT_AGENT  SOCKET4677_AZIFS054P001C01  I51

PU_CPU1_UPI0_AC_COUPLING   @S9S_MB_2U_LIB.S9S_MB_2U(SCH_1):PU_CPU1_UPI0_AC_COUPLING
  R90      2      B  Q_RES       I135
  U1     BA23  UPI0_AC_COUPLING  SOCKET4677_AZIFS054P001C01  I23

PU_CPU1_UPI1_AC_COUPLING   @S9S_MB_2U_LIB.S9S_MB_2U(SCH_1):PU_CPU1_UPI1_AC_COUPLING
  R91      2      B  Q_RES       I136
  U1     CW19  UPI1_AC_COUPLING  SOCKET4677_AZIFS054P001C01  I23

PU_CPU1_UPI2_AC_COUPLING   @S9S_MB_2U_LIB.S9S_MB_2U(SCH_1):PU_CPU1_UPI2_AC_COUPLING
  R92      2      B  Q_RES       I140
  U1     BB65  UPI2_AC_COUPLING  SOCKET4677_AZIFS054P001C01  I23

PU_CPU1_UPI3_AC_COUPLING   @S9S_MB_2U_LIB.S9S_MB_2U(SCH_1):PU_CPU1_UPI3_AC_COUPLING
  R93      2      B  Q_RES       I141
  U1     CK71  UPI3_AC_COUPLING  SOCKET4677_AZIFS054P001C01  I23

PU_DAS_DSS_N    @S9S_MB_2U_LIB.S9S_MB_2U(SCH_1):PU_DAS_DSS_N
  J59     10  DAS_DSS#||LED1#  SCONN75K_APCI0155P004A  I178
  R484     2      B  Q_RES       I170

PU_EDSFF1B_PERST1_CLKREQ_N   @S9S_MB_2U_LIB.S9S_MB_2U(SCH_1):PU_EDSFF1B_PERST1_CLKREQ_N
  J87    A11  PERST1_N_CLKREQ_N  SCONN84_123318136  I43
  R1979    1      A  Q_RES       I87

PU_EDSFF2A_PERST1_CLKREQ_N   @S9S_MB_2U_LIB.S9S_MB_2U(SCH_1):PU_EDSFF2A_PERST1_CLKREQ_N
  J33    A11  PERST1_N_CLKREQ_N  SCONN84_123318136  I53
  R395     1      A  Q_RES       I77

PU_EDSFF2B_PERST1_CLKREQ_N   @S9S_MB_2U_LIB.S9S_MB_2U(SCH_1):PU_EDSFF2B_PERST1_CLKREQ_N
  J34    A11  PERST1_N_CLKREQ_N  SCONN84_123318136  I43
  R399     1      A  Q_RES       I77

PU_ESPI_ENABLE_STRAP   @S9S_MB_2U_LIB.S9S_MB_2U(SCH_1):PU_ESPI_ENABLE_STRAP
  R2133    2      B  Q_RES       I80
  S1       1     A1  SW8S_DHNF04FTVTR   I4

PU_FLASH_SECURITY_STRAP   @S9S_MB_2U_LIB.S9S_MB_2U(SCH_1):PU_FLASH_SECURITY_STRAP
  R1325    2      B  Q_RES       I75
  S2       1     A1  SW8S_DHNF04FTVTR  I35

PU_GTL2014_BMC_JTAG_DIR_1   @S9S_MB_2U_LIB.S9S_MB_2U(SCH_1):PU_GTL2014_BMC_JTAG_DIR_1
  R1377    2      B  Q_RES       I11
  U84      1    DIR  GTL2014PW   I18

PU_GTL2014_BMC_JTAG_DIR_2   @S9S_MB_2U_LIB.S9S_MB_2U(SCH_1):PU_GTL2014_BMC_JTAG_DIR_2
  R1376    2      B  Q_RES       I35
  U83      1    DIR  GTL2014PW   I45

PU_LAN_WAKE_N   @S9S_MB_2U_LIB.S9S_MB_2U(SCH_1):PU_LAN_WAKE_N
  R453     2      B  Q_RES       I77
  U4     AU7  LAN_WAKE_N  EMMITSBURG_REV0P9  I36

PU_LPC_PME_N    @S9S_MB_2U_LIB.S9S_MB_2U(SCH_1):PU_LPC_PME_N
  R1259    2      B  Q_RES        I8
  U4     AJ3  GPP_D_9_PME_N  EMMITSBURG_REV0P9  I93

PU_MAIN_FPGA_CONFIG_DONE   @S9S_MB_2U_LIB.S9S_MB_2U(SCH_1):PU_MAIN_FPGA_CONFIG_DONE
  R1401    1      A  Q_RES       I277
  U122    H8  DIFFIO_RX_T24N||CONF_DONE  10M04SAU324I7G  I139

PU_MAIN_FPGA_CONFIG_N   @S9S_MB_2U_LIB.S9S_MB_2U(SCH_1):PU_MAIN_FPGA_CONFIG_N
  R1488    1      A  Q_RES       I279
  U122    H9  NCONFIG  10M04SAU324I7G  I139

PU_MAIN_FPGA_STATUS_N   @S9S_MB_2U_LIB.S9S_MB_2U(SCH_1):PU_MAIN_FPGA_STATUS_N
  R1436    1      A  Q_RES       I278
  U122    G8  DIFFIO_RX_T24P||NSTATUS  10M04SAU324I7G  I139

PU_MP5981_0_D_OC   @S9S_MB_2U_LIB.S9S_MB_2U(SCH_1):PU_MP5981_0_D_OC
  R2072    2      B  Q_RES       I130
  U107     3   D_OC  MP5981GLUZ  I113

PU_MP5981_0_GOK   @S9S_MB_2U_LIB.S9S_MB_2U(SCH_1):PU_MP5981_0_GOK
  R2073    2      B  Q_RES       I137
  U107     5    GOK  MP5981GLUZ  I113

PU_MP5981_1_D_OC   @S9S_MB_2U_LIB.S9S_MB_2U(SCH_1):PU_MP5981_1_D_OC
  R2085    2      B  Q_RES       I103
  U81      3   D_OC  MP5981GLUZ  I66

PU_MP5981_1_GOK   @S9S_MB_2U_LIB.S9S_MB_2U(SCH_1):PU_MP5981_1_GOK
  R2084    2      B  Q_RES       I102
  U81      5    GOK  MP5981GLUZ  I66

PU_NO_REBOOT_STRAP   @S9S_MB_2U_LIB.S9S_MB_2U(SCH_1):PU_NO_REBOOT_STRAP
  R367     2      B  Q_RES       I11
  U4     AU16  GPPC_S_1_SPKR_TIME_SYNC_1  EMMITSBURG_REV0P9  I27

PU_OC3_USB_N    @S9S_MB_2U_LIB.S9S_MB_2U(SCH_1):PU_OC3_USB_N
  R635     1      A  Q_RES       I234
  U4     BG28  GPPC_B_8_USB2_OCB_3  EMMITSBURG_REV0P9  I93

PU_OC4_USB_N    @S9S_MB_2U_LIB.S9S_MB_2U(SCH_1):PU_OC4_USB_N
  R727     1      A  Q_RES       I236
  U4     BG26  GPPC_B_9_USB2_OCB_4  EMMITSBURG_REV0P9  I93

PU_OC5_USB_N    @S9S_MB_2U_LIB.S9S_MB_2U(SCH_1):PU_OC5_USB_N
  R770     1      A  Q_RES       I239
  U4     BG24  GPPC_B_10_USB2_OCB_5  EMMITSBURG_REV0P9  I93

PU_OC6_USB_N    @S9S_MB_2U_LIB.S9S_MB_2U(SCH_1):PU_OC6_USB_N
  R913     1      A  Q_RES       I241
  U4     BG22  GPPC_B_11_USB2_OCB_6  EMMITSBURG_REV0P9  I93

PU_OCP_SFF_WAKE_OE   @S9S_MB_2U_LIB.S9S_MB_2U(SCH_1):PU_OCP_SFF_WAKE_OE
  R1592    2      B  Q_RES       I37
  U82      1     OE  74LVC1G126GW  I35

PU_PCH_PLD_3V3AUX_ALERT_N   @S9S_MB_2U_LIB.S9S_MB_2U(SCH_1):PU_PCH_PLD_3V3AUX_ALERT_N
  R1583    1      A  Q_RES       I144
  U4     AN2  GPPC_C_21_MC_SMBALERT_N  EMMITSBURG_REV0P9  I93

PU_PCH_PMCALERT_N   @S9S_MB_2U_LIB.S9S_MB_2U(SCH_1):PU_PCH_PMCALERT_N
  R456     2      B  Q_RES       I66
  U4      J4  GPPC_H_18_PMCALERT_N  EMMITSBURG_REV0P9  I22

PU_PCH_VRALERT_N   @S9S_MB_2U_LIB.S9S_MB_2U(SCH_1):PU_PCH_VRALERT_N
  R1257    2      B  Q_RES        I4
  U4     AC3  GPP_D_15_VRALERT_N  EMMITSBURG_REV0P9  I93

PU_PIROM_CPU0_SM_WP   @S9S_MB_2U_LIB.S9S_MB_2U(SCH_1):PU_PIROM_CPU0_SM_WP
  R650     2      B  Q_RES       I32
  R997     1      A  Q_RES       I31
  U2     CR72  I2C_PIROM_SM_WP  SOCKET4677_AZIFS054P001C01   I1

PU_PIROM_CPU1_ADDR0   @S9S_MB_2U_LIB.S9S_MB_2U(SCH_1):PU_PIROM_CPU1_ADDR0
  R629     2      B  Q_RES       I13
  R630     1      A  Q_RES       I15
  U1     CR70  I2C_PIROM_AD_0  SOCKET4677_AZIFS054P001C01  I29

PU_PIROM_CPU1_SM_WP   @S9S_MB_2U_LIB.S9S_MB_2U(SCH_1):PU_PIROM_CPU1_SM_WP
  R1004    2      B  Q_RES       I35
  R1005    1      A  Q_RES       I36
  U1     CR72  I2C_PIROM_SM_WP  SOCKET4677_AZIFS054P001C01  I29

PU_PLD_HEARTBEAT_LVC3   @S9S_MB_2U_LIB.S9S_MB_2U(SCH_1):PU_PLD_HEARTBEAT_LVC3
  D0       A      A  Q_LED       I239
  R1195    2      B  Q_RES       I241

PU_RST_DEDI_BUSY_PLD_N   @S9S_MB_2U_LIB.S9S_MB_2U(SCH_1):PU_RST_DEDI_BUSY_PLD_N
  R1681    2      B  Q_RES       I296
  U122    K3  DIFFIO_RX_L16P  10M04SAU324I7G  I93

PU_RST_SMB_EDSFF_N   @S9S_MB_2U_LIB.S9S_MB_2U(SCH_1):PU_RST_SMB_EDSFF_N
  R1522    2      B  Q_RES       I97
  U24      3  RESET#  PCA9548APW  I60

PU_RST_SMB_OCP_SFF_N   @S9S_MB_2U_LIB.S9S_MB_2U(SCH_1):PU_RST_SMB_OCP_SFF_N
  J37     A9  SMRST#  SCONN168_623403212  I86
  R454     2      B  Q_RES       I314

PU_RST_SMB_PCIE3_N   @S9S_MB_2U_LIB.S9S_MB_2U(SCH_1):PU_RST_SMB_PCIE3_N
  R1667    2      B  Q_RES       I183
  R1822    2      B  Q_RES       I152
  R2197    2      B  Q_RES       I112
  U10      3  RESET#  PCA9546APWR  I194
  U36      3  RESET#  PCA9546APWR  I179
  U141     3  RESET#  PCA9546APWR  I91

PU_S3M_CPU0_CPLD_CONFD   @S9S_MB_2U_LIB.S9S_MB_2U(SCH_1):PU_S3M_CPU0_CPLD_CONFD
  R320     2      B  Q_RES       I20
  U2     CJ64  CPLD_CONF_DONE  SOCKET4677_AZIFS054P001C01   I1

PU_S3M_CPU0_CPLD_STATUS   @S9S_MB_2U_LIB.S9S_MB_2U(SCH_1):PU_S3M_CPU0_CPLD_STATUS
  R319     2      B  Q_RES       I19
  U2     CH65  CPLD_NSTATUS  SOCKET4677_AZIFS054P001C01   I1

PU_S3M_CPU1_CPLD_CONFD   @S9S_MB_2U_LIB.S9S_MB_2U(SCH_1):PU_S3M_CPU1_CPLD_CONFD
  R326     2      B  Q_RES       I29
  U1     CJ64  CPLD_CONF_DONE  SOCKET4677_AZIFS054P001C01   I5

PU_S3M_CPU1_CPLD_STATUS   @S9S_MB_2U_LIB.S9S_MB_2U(SCH_1):PU_S3M_CPU1_CPLD_STATUS
  R325     2      B  Q_RES       I28
  U1     CH65  CPLD_NSTATUS  SOCKET4677_AZIFS054P001C01   I5

PU_SMB_EDSFF_3V3AUX_SCL7   @S9S_MB_2U_LIB.S9S_MB_2U(SCH_1):PU_SMB_EDSFF_3V3AUX_SCL7
  R2057    2      B  Q_RES       I147
  R2065    2      B  Q_RES       I109

PU_SMB_EDSFF_3V3AUX_SDA7   @S9S_MB_2U_LIB.S9S_MB_2U(SCH_1):PU_SMB_EDSFF_3V3AUX_SDA7
  R2058    2      B  Q_RES       I146
  R2066    2      B  Q_RES       I108

PU_SMB_PCH_PLD_3V3AUX_SCL   @S9S_MB_2U_LIB.S9S_MB_2U(SCH_1):PU_SMB_PCH_PLD_3V3AUX_SCL
  R1581    1      A  Q_RES       I142
  U4     AL1  GPPC_C_19_MC_SMBCLK  EMMITSBURG_REV0P9  I93

PU_SMB_PCH_PLD_3V3AUX_SDA   @S9S_MB_2U_LIB.S9S_MB_2U(SCH_1):PU_SMB_PCH_PLD_3V3AUX_SDA
  R1582    1      A  Q_RES       I141
  U4     AT1  GPPC_C_20_MC_SMBDATA  EMMITSBURG_REV0P9  I93

PU_SMB_SML3_3V3AUX_PCH_SCL   @S9S_MB_2U_LIB.S9S_MB_2U(SCH_1):PU_SMB_SML3_3V3AUX_PCH_SCL
  R1451    1      A  Q_RES       I109
  U4     AN4  GPPC_C_12_ME_SML3CLK  EMMITSBURG_REV0P9  I93

PU_SMB_SML3_3V3AUX_PCH_SDA   @S9S_MB_2U_LIB.S9S_MB_2U(SCH_1):PU_SMB_SML3_3V3AUX_PCH_SDA
  R1452    1      A  Q_RES       I112
  U4     AY1  GPPC_C_13_ME_SML3DATA  EMMITSBURG_REV0P9  I93

PU_SMB_SML4_3V3AUX_PCH_SCL   @S9S_MB_2U_LIB.S9S_MB_2U(SCH_1):PU_SMB_SML4_3V3AUX_PCH_SCL
  R1453    1      A  Q_RES       I120
  U4     BA2  GPPC_C_15_ME_SML4CLK  EMMITSBURG_REV0P9  I93

PU_SMB_SML4_3V3AUX_PCH_SDA   @S9S_MB_2U_LIB.S9S_MB_2U(SCH_1):PU_SMB_SML4_3V3AUX_PCH_SDA
  R1454    1      A  Q_RES       I121
  U4     AV1  GPPC_C_16_ME_SML4DATA  EMMITSBURG_REV0P9  I93

PU_SWAP_OVERRIDE_N   @S9S_MB_2U_LIB.S9S_MB_2U(SCH_1):PU_SWAP_OVERRIDE_N
  R1320    2      B  Q_RES       I68
  S1       3     A3  SW8S_DHNF04FTVTR   I4

PU_TAP_ODT_CPU0_EN   @S9S_MB_2U_LIB.S9S_MB_2U(SCH_1):PU_TAP_ODT_CPU0_EN
  R1009    2      B  Q_RES       I136
  U2     AY20  TAP_ODT_EN  SOCKET4677_AZIFS054P001C01   I1

PU_TAP_ODT_CPU1_EN   @S9S_MB_2U_LIB.S9S_MB_2U(SCH_1):PU_TAP_ODT_CPU1_EN
  R1008    2      B  Q_RES       I139
  U1     AY20  TAP_ODT_EN  SOCKET4677_AZIFS054P001C01  I29

PU_USB_INT_P5V_EN_N   @S9S_MB_2U_LIB.S9S_MB_2U(SCH_1):PU_USB_INT_P5V_EN_N
  C564     1      A  Q_CAP        I9
  R461     2      B  Q_RES       I10
  U27      3     EN  TPS2553DBVR1  I24

PVCC1_AUX       @S9S_MB_2U_LIB.S9S_MB_2U(SCH_1):PVCC1_AUX
  PR395    2      B  Q_RES       I10
  PR396    2      B  Q_RES        I2
  PR1329    1      A  Q_RES        I7

PVCCA_AUX_PLD   @S9S_MB_2U_LIB.S9S_MB_2U(SCH_1):PVCCA_AUX_PLD
  C1115    1      A  Q_CAP       I227
  C1124    1      A  Q_CAP       I200
  C1130    1      A  Q_CAP       I199
  C1136    1      A  Q_CAP       I198
  C1140    1      A  Q_CAP       I197
  C1144    1      A  Q_CAP       I195
  C1148    1      A  Q_CAP       I194
  L36      2      2  Q_INDUCTOR  I228
  R507     1      A  Q_RES       I173
  U122    F4  VCCA3_F4  10M04SAU324I7G  I164
  U122    F6  VCCA3_F6  10M04SAU324I7G  I164
  U122   F14  VCCA2_F14  10M04SAU324I7G  I164
  U122    M6  VCCA1_M6  10M04SAU324I7G  I164
  U122   P13  VCCA4_P13  10M04SAU324I7G  I164

PVCCD_HV_CPU0   @S9S_MB_2U_LIB.S9S_MB_2U(SCH_1):PVCCD_HV_CPU0
  C399     1      A  Q_CAP       I102
  C401     1      A  Q_CAP       I105
  C403     1      A  Q_CAP       I104
  C405     1      A  Q_CAP       I103
  C491     1      A  Q_CAP       I10
  C495     1      A  Q_CAP       I14
  C499     1      A  Q_CAP       I107
  C503     1      A  Q_CAP       I110
  C507     1      A  Q_CAP       I109
  C511     1      A  Q_CAP       I108
  C515     1      A  Q_CAP       I126
  C518     1      A  Q_CAP       I130
  PC639    1      A  Q_CAP       I346
  PC641    1      A  Q_CAP       I352
  PC642    1      A  Q_CAP       I353
  PC1644    1      A  Q_CAPP      I349
  PC1645    1      A  Q_CAPP      I350
  PC1910    1      A  Q_CAPP      I348
  PL35     2      2  Q_INDUCTOR  I345
  PR592    2      B  Q_RES       I33
  R175     2      B  Q_RES       I74
  R177     2      B  Q_RES       I72
  R179     2      B  Q_RES       I70
  R181     2      B  Q_RES       I68
  R511     1      A  Q_RES       I266
  R839     1      A  Q_RES       I125
  R840     1      A  Q_RES       I119
  R841     1      A  Q_RES       I121
  R842     1      A  Q_RES       I123
  U2     AT36  VCCD_HV0  SOCKET4677_AZIFS054P001C01   I8
  U2     AT55  VCCD_HV1  SOCKET4677_AZIFS054P001C01   I8
  U2     AU3  VCCD_HV2  SOCKET4677_AZIFS054P001C01   I8
  U2     AU7  VCCD_HV5  SOCKET4677_AZIFS054P001C01   I8
  U2     AU35  VCCD_HV3  SOCKET4677_AZIFS054P001C01   I8
  U2     AU54  VCCD_HV4  SOCKET4677_AZIFS054P001C01   I8
  U2     AV34  VCCD_HV6  SOCKET4677_AZIFS054P001C01   I8
  U2     AV36  VCCD_HV7  SOCKET4677_AZIFS054P001C01   I8
  U2     AV53  VCCD_HV8  SOCKET4677_AZIFS054P001C01   I8
  U2     AV55  VCCD_HV9  SOCKET4677_AZIFS054P001C01   I8
  U2     BA3  VCCD_HV10  SOCKET4677_AZIFS054P001C01   I8
  U2     BA7  VCCD_HV11  SOCKET4677_AZIFS054P001C01   I8
  U2     BE3  VCCD_HV13  SOCKET4677_AZIFS054P001C01   I8
  U2     BE7  VCCD_HV14  SOCKET4677_AZIFS054P001C01   I8
  U2     BE11  VCCD_HV12  SOCKET4677_AZIFS054P001C01   I8
  U2     BJ3  VCCD_HV16  SOCKET4677_AZIFS054P001C01   I8
  U2     BJ7  VCCD_HV17  SOCKET4677_AZIFS054P001C01   I8
  U2     BJ11  VCCD_HV15  SOCKET4677_AZIFS054P001C01   I8
  U2     BN7  VCCD_HV18  SOCKET4677_AZIFS054P001C01   I8
  U2     CA7  VCCD_HV19  SOCKET4677_AZIFS054P001C01   I8
  U2     CE7  VCCD_HV20  SOCKET4677_AZIFS054P001C01   I8
  U2     CW35  VCCD_HV21  SOCKET4677_AZIFS054P001C01   I8
  U2     CW37  VCCD_HV22  SOCKET4677_AZIFS054P001C01   I8
  U2     CW52  VCCD_HV23  SOCKET4677_AZIFS054P001C01   I8
  U2     CW54  VCCD_HV26  SOCKET4677_AZIFS054P001C01   I8
  U2     CW56  VCCD_HV24  SOCKET4677_AZIFS054P001C01   I8
  U2     CY34  VCCD_HV25  SOCKET4677_AZIFS054P001C01   I8
  U2     CY36  VCCD_HV27  SOCKET4677_AZIFS054P001C01   I8
  U2     CY53  VCCD_HV28  SOCKET4677_AZIFS054P001C01   I8

PVCCD_HV_CPU0_ACSP1   @S9S_MB_2U_LIB.S9S_MB_2U(SCH_1):PVCCD_HV_CPU0_ACSP1
  PU35    23    CS7  ISL69260IRAZT  I51
  PU36    25   IMON  RAA2213404GNPHB0  I333

PVCCD_HV_CPU0_ADDR   @S9S_MB_2U_LIB.S9S_MB_2U(SCH_1):PVCCD_HV_CPU0_ADDR
  PR357    2      B  Q_RES        I7
  PR358    2      B  Q_RES        I6
  PU35    34  ADDR_CFG  ISL69260IRAZT  I51

PVCCD_HV_CPU0_APWM1   @S9S_MB_2U_LIB.S9S_MB_2U(SCH_1):PVCCD_HV_CPU0_APWM1
  PU35     8   PWM7  ISL69260IRAZT  I51
  PU36    21    PWM  RAA2213404GNPHB0  I333

PVCCD_HV_CPU0_ATSEN   @S9S_MB_2U_LIB.S9S_MB_2U(SCH_1):PVCCD_HV_CPU0_ATSEN
  PC631    1      A  Q_CAP       I55
  PR634    1      A  Q_RES       I57
  PU35    35  TEMP0  ISL69260IRAZT  I51
  PU36     1   TMON  RAA2213404GNPHB0  I333

PVCCD_HV_CPU0_EN_R   @S9S_MB_2U_LIB.S9S_MB_2U(SCH_1):PVCCD_HV_CPU0_EN_R
  PR363    2      B  Q_RES       I40
  PU35    13    EN0  ISL69260IRAZT  I51

PVCCD_HV_CPU0_FAULT   @S9S_MB_2U_LIB.S9S_MB_2U(SCH_1):PVCCD_HV_CPU0_FAULT
  PR372    2      B  Q_RES       I17
  PU35    33    CFP  ISL69260IRAZT  I51

PVCCD_HV_CPU0_ISENSE_N   @S9S_MB_2U_LIB.S9S_MB_2U(SCH_1):PVCCD_HV_CPU0_ISENSE_N
  PC628    1      A  Q_CAP       I48
  PC813    1      A  Q_CAP       I49
  PR373    1      A  Q_RES       I46
  PR1390    2      B  Q_RES        I9
  PU35    38  VINSEN  ISL69260IRAZT  I51

PVCCD_HV_CPU0_ISENSE_P   @S9S_MB_2U_LIB.S9S_MB_2U(SCH_1):PVCCD_HV_CPU0_ISENSE_P
  PC624    1      A  Q_CAP       I13
  PC813    2      B  Q_CAP       I49
  PR369    1      A  Q_RES       I12
  PR1380    2      B  Q_RES       I10
  PU35    37  IINSEN||VMON||VSYS  ISL69260IRAZT  I51

PVCCD_HV_CPU0_ISYS_R   @S9S_MB_2U_LIB.S9S_MB_2U(SCH_1):PVCCD_HV_CPU0_ISYS_R
  PR409    1      A  Q_RES       I59
  PR1311    1      A  Q_RES       I58
  PU35    36  TEMP1||ISYS  ISL69260IRAZT  I51

PVCCD_HV_CPU0_LSET1   @S9S_MB_2U_LIB.S9S_MB_2U(SCH_1):PVCCD_HV_CPU0_LSET1
  PR2718    1      A  Q_RES       I325
  PU36     5    GL1  RAA2213404GNPHB0  I333

PVCCD_HV_CPU0_NC1   @S9S_MB_2U_LIB.S9S_MB_2U(SCH_1):PVCCD_HV_CPU0_NC1
  PR1785    1      A  Q_RES       I342
  PU36     3  LGCTRL  RAA2213404GNPHB0  I333

PVCCD_HV_CPU0_PIN_ALT   @S9S_MB_2U_LIB.S9S_MB_2U(SCH_1):PVCCD_HV_CPU0_PIN_ALT
  PR370    2      B  Q_RES       I15
  PU35    15  NPINALERT||NPSYSCRIT  ISL69260IRAZT  I51

PVCCD_HV_CPU0_PVCC   @S9S_MB_2U_LIB.S9S_MB_2U(SCH_1):PVCCD_HV_CPU0_PVCC
  PR380    1      A  Q_RES       I336
  PR635    2      B  Q_RES       I335
  PR636    2      B  Q_RES       I337

PVCCD_HV_CPU0_VCC   @S9S_MB_2U_LIB.S9S_MB_2U(SCH_1):PVCCD_HV_CPU0_VCC
  PC629    1      A  Q_CAP       I65
  PC632    1      A  Q_CAP       I66
  PR375    1      A  Q_RES       I72
  PU35    39    VCC  ISL69260IRAZT  I51

PVCCD_HV_CPU0_VDD1   @S9S_MB_2U_LIB.S9S_MB_2U(SCH_1):PVCCD_HV_CPU0_VDD1
  PC633    1      A  Q_CAP       I332
  PR380    2      B  Q_RES       I336
  PR1785    2      B  Q_RES       I342
  PU36     4    VCC  RAA2213404GNPHB0  I333
  PU36    22    NC1  RAA2213404GNPHB0  I333

PVCCD_HV_CPU0_VREF   @S9S_MB_2U_LIB.S9S_MB_2U(SCH_1):PVCCD_HV_CPU0_VREF
  PC630    1      A  Q_CAP       I63
  PC1196    1      A  Q_CAP       I64
  PC1354    2      B  Q_CAP       I330
  PR357    1      A  Q_RES        I7
  PU35    40   VCCS  ISL69260IRAZT  I51
  PU36    24  REFIN  RAA2213404GNPHB0  I333

PVCCD_HV_CPU1   @S9S_MB_2U_LIB.S9S_MB_2U(SCH_1):PVCCD_HV_CPU1
  C423     1      A  Q_CAP       I11
  C425     1      A  Q_CAP       I17
  C427     1      A  Q_CAP       I19
  C429     1      A  Q_CAP       I34
  C447     1      A  Q_CAP       I24
  C451     1      A  Q_CAP       I29
  C455     1      A  Q_CAP       I129
  C459     1      A  Q_CAP       I128
  C463     1      A  Q_CAP       I127
  C467     1      A  Q_CAP       I126
  C471     1      A  Q_CAP       I52
  C474     1      A  Q_CAP       I54
  PC379    1      A  Q_CAP       I27
  PC381    1      A  Q_CAP       I28
  PC382    1      A  Q_CAP       I34
  PC384    1      A  Q_CAPP      I21
  PC385    1      A  Q_CAPP      I23
  PC1940    1      A  Q_CAPP      I37
  PL17     2      2  Q_INDUCTOR  I26
  PR559    2      B  Q_RES       I223
  R135     2      B  Q_RES       I62
  R137     2      B  Q_RES       I60
  R151     2      B  Q_RES       I58
  R153     2      B  Q_RES       I56
  R819     1      A  Q_RES       I90
  R820     1      A  Q_RES       I82
  R821     1      A  Q_RES       I84
  R822     1      A  Q_RES       I88
  U1     AT36  VCCD_HV0  SOCKET4677_AZIFS054P001C01   I8
  U1     AT55  VCCD_HV1  SOCKET4677_AZIFS054P001C01   I8
  U1     AU3  VCCD_HV2  SOCKET4677_AZIFS054P001C01   I8
  U1     AU7  VCCD_HV5  SOCKET4677_AZIFS054P001C01   I8
  U1     AU35  VCCD_HV3  SOCKET4677_AZIFS054P001C01   I8
  U1     AU54  VCCD_HV4  SOCKET4677_AZIFS054P001C01   I8
  U1     AV34  VCCD_HV6  SOCKET4677_AZIFS054P001C01   I8
  U1     AV36  VCCD_HV7  SOCKET4677_AZIFS054P001C01   I8
  U1     AV53  VCCD_HV8  SOCKET4677_AZIFS054P001C01   I8
  U1     AV55  VCCD_HV9  SOCKET4677_AZIFS054P001C01   I8
  U1     BA3  VCCD_HV10  SOCKET4677_AZIFS054P001C01   I8
  U1     BA7  VCCD_HV11  SOCKET4677_AZIFS054P001C01   I8
  U1     BE3  VCCD_HV13  SOCKET4677_AZIFS054P001C01   I8
  U1     BE7  VCCD_HV14  SOCKET4677_AZIFS054P001C01   I8
  U1     BE11  VCCD_HV12  SOCKET4677_AZIFS054P001C01   I8
  U1     BJ3  VCCD_HV16  SOCKET4677_AZIFS054P001C01   I8
  U1     BJ7  VCCD_HV17  SOCKET4677_AZIFS054P001C01   I8
  U1     BJ11  VCCD_HV15  SOCKET4677_AZIFS054P001C01   I8
  U1     BN7  VCCD_HV18  SOCKET4677_AZIFS054P001C01   I8
  U1     CA7  VCCD_HV19  SOCKET4677_AZIFS054P001C01   I8
  U1     CE7  VCCD_HV20  SOCKET4677_AZIFS054P001C01   I8
  U1     CW35  VCCD_HV21  SOCKET4677_AZIFS054P001C01   I8
  U1     CW37  VCCD_HV22  SOCKET4677_AZIFS054P001C01   I8
  U1     CW52  VCCD_HV23  SOCKET4677_AZIFS054P001C01   I8
  U1     CW54  VCCD_HV26  SOCKET4677_AZIFS054P001C01   I8
  U1     CW56  VCCD_HV24  SOCKET4677_AZIFS054P001C01   I8
  U1     CY34  VCCD_HV25  SOCKET4677_AZIFS054P001C01   I8
  U1     CY36  VCCD_HV27  SOCKET4677_AZIFS054P001C01   I8
  U1     CY53  VCCD_HV28  SOCKET4677_AZIFS054P001C01   I8

PVCCD_HV_CPU1_ACSP1   @S9S_MB_2U_LIB.S9S_MB_2U(SCH_1):PVCCD_HV_CPU1_ACSP1
  PU17    25   IMON  RAA2213404GNPHB0  I38
  PU18    23    CS7  ISL69260IRAZT  I243

PVCCD_HV_CPU1_ADDR   @S9S_MB_2U_LIB.S9S_MB_2U(SCH_1):PVCCD_HV_CPU1_ADDR
  PR202    2      B  Q_RES       I204
  PR203    2      B  Q_RES       I201
  PU18    34  ADDR_CFG  ISL69260IRAZT  I243

PVCCD_HV_CPU1_APWM1   @S9S_MB_2U_LIB.S9S_MB_2U(SCH_1):PVCCD_HV_CPU1_APWM1
  PU17    21    PWM  RAA2213404GNPHB0  I38
  PU18     8   PWM7  ISL69260IRAZT  I243

PVCCD_HV_CPU1_ATSEN   @S9S_MB_2U_LIB.S9S_MB_2U(SCH_1):PVCCD_HV_CPU1_ATSEN
  PC393    1      A  Q_CAP       I251
  PR705    1      A  Q_RES       I263
  PU17     1   TMON  RAA2213404GNPHB0  I38
  PU18    35  TEMP0  ISL69260IRAZT  I243

PVCCD_HV_CPU1_EN_R   @S9S_MB_2U_LIB.S9S_MB_2U(SCH_1):PVCCD_HV_CPU1_EN_R
  PR208    2      B  Q_RES       I230
  PU18    13    EN0  ISL69260IRAZT  I243

PVCCD_HV_CPU1_FAULT   @S9S_MB_2U_LIB.S9S_MB_2U(SCH_1):PVCCD_HV_CPU1_FAULT
  PR217    2      B  Q_RES       I247
  PU18    33    CFP  ISL69260IRAZT  I243

PVCCD_HV_CPU1_ISENSE_N   @S9S_MB_2U_LIB.S9S_MB_2U(SCH_1):PVCCD_HV_CPU1_ISENSE_N
  PC390    1      A  Q_CAP       I240
  PC814    1      A  Q_CAP       I241
  PR218    1      A  Q_RES       I238
  PR1410    2      B  Q_RES       I202
  PU18    38  VINSEN  ISL69260IRAZT  I243

PVCCD_HV_CPU1_ISENSE_P   @S9S_MB_2U_LIB.S9S_MB_2U(SCH_1):PVCCD_HV_CPU1_ISENSE_P
  PC386    1      A  Q_CAP       I237
  PC814    2      B  Q_CAP       I241
  PR214    1      A  Q_RES       I236
  PR1400    2      B  Q_RES       I203
  PU18    37  IINSEN||VMON||VSYS  ISL69260IRAZT  I243

PVCCD_HV_CPU1_ISYS_R   @S9S_MB_2U_LIB.S9S_MB_2U(SCH_1):PVCCD_HV_CPU1_ISYS_R
  PR410    1      A  Q_RES       I260
  PR1315    1      A  Q_RES       I259
  PU18    36  TEMP1||ISYS  ISL69260IRAZT  I243

PVCCD_HV_CPU1_LSET1   @S9S_MB_2U_LIB.S9S_MB_2U(SCH_1):PVCCD_HV_CPU1_LSET1
  PR1746    1      A  Q_RES        I2
  PU17     5    GL1  RAA2213404GNPHB0  I38

PVCCD_HV_CPU1_NC1   @S9S_MB_2U_LIB.S9S_MB_2U(SCH_1):PVCCD_HV_CPU1_NC1
  PR1805    1      A  Q_RES       I17
  PU17     3  LGCTRL  RAA2213404GNPHB0  I38

PVCCD_HV_CPU1_PIN_ALT   @S9S_MB_2U_LIB.S9S_MB_2U(SCH_1):PVCCD_HV_CPU1_PIN_ALT
  PR215    2      B  Q_RES       I245
  PU18    15  NPINALERT||NPSYSCRIT  ISL69260IRAZT  I243

PVCCD_HV_CPU1_PVCC   @S9S_MB_2U_LIB.S9S_MB_2U(SCH_1):PVCCD_HV_CPU1_PVCC
  PR200    1      A  Q_RES       I13
  PR706    2      B  Q_RES       I11
  PR707    2      B  Q_RES       I14

PVCCD_HV_CPU1_VCC   @S9S_MB_2U_LIB.S9S_MB_2U(SCH_1):PVCCD_HV_CPU1_VCC
  PC391    1      A  Q_CAP       I257
  PC394    1      A  Q_CAP       I258
  PR220    1      A  Q_RES       I274
  PU18    39    VCC  ISL69260IRAZT  I243

PVCCD_HV_CPU1_VDD1   @S9S_MB_2U_LIB.S9S_MB_2U(SCH_1):PVCCD_HV_CPU1_VDD1
  PC373    1      A  Q_CAP       I10
  PR200    2      B  Q_RES       I13
  PR1805    2      B  Q_RES       I17
  PU17     4    VCC  RAA2213404GNPHB0  I38
  PU17    22    NC1  RAA2213404GNPHB0  I38

PVCCD_HV_CPU1_VREF   @S9S_MB_2U_LIB.S9S_MB_2U(SCH_1):PVCCD_HV_CPU1_VREF
  PC392    1      A  Q_CAP       I255
  PC1289    1      A  Q_CAP       I256
  PC1371    2      B  Q_CAP        I8
  PR202    1      A  Q_RES       I204
  PU17    24  REFIN  RAA2213404GNPHB0  I38
  PU18    40   VCCS  ISL69260IRAZT  I243

PVCCFA_EHV_CPU0   @S9S_MB_2U_LIB.S9S_MB_2U(SCH_1):PVCCFA_EHV_CPU0
  C419     1      A  Q_CAP       I142
  C420     1      A  Q_CAP       I146
  C421     1      A  Q_CAP       I145
  C422     1      A  Q_CAP       I143
  C492     1      A  Q_CAP       I66
  C496     1      A  Q_CAP       I67
  C500     1      A  Q_CAP       I55
  C504     1      A  Q_CAP       I56
  C508     1      A  Q_CAP       I77
  C512     1      A  Q_CAP       I78
  C516     1      A  Q_CAP       I79
  C519     1      A  Q_CAP       I81
  PC181    1      A  Q_CAP       I22
  PC184    1      A  Q_CAP       I24
  PC186    1      A  Q_CAP       I25
  PC1900    1      A  Q_CAPP      I28
  PC2180    1      A  Q_CAPP      I27
  PL3      2      2  Q_INDUCTOR  I23
  PR522    2      B  Q_RES       I10
  U2     AA3  VCCFA_EHV0  SOCKET4677_AZIFS054P001C01   I8
  U2     AE3  VCCFA_EHV1  SOCKET4677_AZIFS054P001C01   I8
  U2     AJ3  VCCFA_EHV2  SOCKET4677_AZIFS054P001C01   I8
  U2     AN3  VCCFA_EHV3  SOCKET4677_AZIFS054P001C01   I8
  U2     AT61  VCCFA_EHV4  SOCKET4677_AZIFS054P001C01   I8
  U2     AU60  VCCFA_EHV5  SOCKET4677_AZIFS054P001C01   I8
  U2     AV61  VCCFA_EHV6  SOCKET4677_AZIFS054P001C01   I8
  U2     AW60  VCCFA_EHV7  SOCKET4677_AZIFS054P001C01   I8
  U2      N3  VCCFA_EHV9  SOCKET4677_AZIFS054P001C01   I8
  U2      U3  VCCFA_EHV8  SOCKET4677_AZIFS054P001C01   I8

PVCCFA_EHV_CPU0_BCSP1   @S9S_MB_2U_LIB.S9S_MB_2U(SCH_1):PVCCFA_EHV_CPU0_BCSP1
  PU5     30    CS0  ISL69260IRAZT  I51
  PU42    25   IMON  RAA2213404GNPHB0  I11

PVCCFA_EHV_CPU0_BPWM1   @S9S_MB_2U_LIB.S9S_MB_2U(SCH_1):PVCCFA_EHV_CPU0_BPWM1
  PU5      1   PWM0  ISL69260IRAZT  I51
  PU42    21    PWM  RAA2213404GNPHB0  I11

PVCCFA_EHV_CPU0_BTSEN   @S9S_MB_2U_LIB.S9S_MB_2U(SCH_1):PVCCFA_EHV_CPU0_BTSEN
  PC1271    1      A  Q_CAP       I56
  PR436    1      A  Q_RES       I79
  PU5     36  TEMP1||ISYS  ISL69260IRAZT  I51
  PU42     1   TMON  RAA2213404GNPHB0  I11

PVCCFA_EHV_CPU0_EN_R   @S9S_MB_2U_LIB.S9S_MB_2U(SCH_1):PVCCFA_EHV_CPU0_EN_R
  PC219    1      A  Q_CAP       I37
  PR119    2      B  Q_RES       I32
  PU5     20    EN1  ISL69260IRAZT  I51

PVCCFA_EHV_CPU0_LSET1   @S9S_MB_2U_LIB.S9S_MB_2U(SCH_1):PVCCFA_EHV_CPU0_LSET1
  PR1709    1      A  Q_RES        I2
  PU42     5    GL1  RAA2213404GNPHB0  I11

PVCCFA_EHV_CPU0_NC1   @S9S_MB_2U_LIB.S9S_MB_2U(SCH_1):PVCCFA_EHV_CPU0_NC1
  PR1779    1      A  Q_RES       I19
  PU42     3  LGCTRL  RAA2213404GNPHB0  I11

PVCCFA_EHV_CPU0_PVCC   @S9S_MB_2U_LIB.S9S_MB_2U(SCH_1):PVCCFA_EHV_CPU0_PVCC
  PR97     1      A  Q_RES       I14
  PR442    2      B  Q_RES       I13
  PR443    2      B  Q_RES       I15

PVCCFA_EHV_CPU0_VDD1   @S9S_MB_2U_LIB.S9S_MB_2U(SCH_1):PVCCFA_EHV_CPU0_VDD1
  PC175    1      A  Q_CAP       I10
  PR97     2      B  Q_RES       I14
  PR1779    2      B  Q_RES       I19
  PU42     4    VCC  RAA2213404GNPHB0  I11
  PU42    22    NC1  RAA2213404GNPHB0  I11

PVCCFA_EHV_CPU1   @S9S_MB_2U_LIB.S9S_MB_2U(SCH_1):PVCCFA_EHV_CPU1
  C443     1      A  Q_CAP       I79
  C444     1      A  Q_CAP       I101
  C445     1      A  Q_CAP       I102
  C446     1      A  Q_CAP       I105
  C448     1      A  Q_CAP       I23
  C452     1      A  Q_CAP       I27
  C456     1      A  Q_CAP       I136
  C460     1      A  Q_CAP       I135
  C464     1      A  Q_CAP       I134
  C468     1      A  Q_CAP       I133
  C472     1      A  Q_CAP       I132
  C475     1      A  Q_CAP       I131
  PC434    1      A  Q_CAP       I25
  PC435    1      A  Q_CAP       I30
  PC437    1      A  Q_CAP       I31
  PC1930    1      A  Q_CAPP      I33
  PC2199    1      A  Q_CAPP      I32
  PL20     2      2  Q_INDUCTOR  I23
  PR569    2      B  Q_RES       I21
  U1     AA3  VCCFA_EHV0  SOCKET4677_AZIFS054P001C01   I8
  U1     AE3  VCCFA_EHV1  SOCKET4677_AZIFS054P001C01   I8
  U1     AJ3  VCCFA_EHV2  SOCKET4677_AZIFS054P001C01   I8
  U1     AN3  VCCFA_EHV3  SOCKET4677_AZIFS054P001C01   I8
  U1     AT61  VCCFA_EHV4  SOCKET4677_AZIFS054P001C01   I8
  U1     AU60  VCCFA_EHV5  SOCKET4677_AZIFS054P001C01   I8
  U1     AV61  VCCFA_EHV6  SOCKET4677_AZIFS054P001C01   I8
  U1     AW60  VCCFA_EHV7  SOCKET4677_AZIFS054P001C01   I8
  U1      N3  VCCFA_EHV9  SOCKET4677_AZIFS054P001C01   I8
  U1      U3  VCCFA_EHV8  SOCKET4677_AZIFS054P001C01   I8

PVCCFA_EHV_CPU1_BCSP1   @S9S_MB_2U_LIB.S9S_MB_2U(SCH_1):PVCCFA_EHV_CPU1_BCSP1
  PU22    30    CS0  ISL69260IRAZT  I61
  PU49    25   IMON  RAA2213404GNPHB0  I14

PVCCFA_EHV_CPU1_BPWM1   @S9S_MB_2U_LIB.S9S_MB_2U(SCH_1):PVCCFA_EHV_CPU1_BPWM1
  PU22     1   PWM0  ISL69260IRAZT  I61
  PU49    21    PWM  RAA2213404GNPHB0  I14

PVCCFA_EHV_CPU1_BTSEN   @S9S_MB_2U_LIB.S9S_MB_2U(SCH_1):PVCCFA_EHV_CPU1_BTSEN
  PC1292    1      A  Q_CAP       I68
  PR667    1      A  Q_RES       I93
  PU22    36  TEMP1||ISYS  ISL69260IRAZT  I61
  PU49     1   TMON  RAA2213404GNPHB0  I14

PVCCFA_EHV_CPU1_EN_R   @S9S_MB_2U_LIB.S9S_MB_2U(SCH_1):PVCCFA_EHV_CPU1_EN_R
  PC472    1      A  Q_CAP       I59
  PR272    2      B  Q_RES       I18
  PU22    20    EN1  ISL69260IRAZT  I61

PVCCFA_EHV_CPU1_LSET1   @S9S_MB_2U_LIB.S9S_MB_2U(SCH_1):PVCCFA_EHV_CPU1_LSET1
  PR1728    1      A  Q_RES        I2
  PU49     5    GL1  RAA2213404GNPHB0  I14

PVCCFA_EHV_CPU1_NC1   @S9S_MB_2U_LIB.S9S_MB_2U(SCH_1):PVCCFA_EHV_CPU1_NC1
  PR1799    1      A  Q_RES       I19
  PU49     3  LGCTRL  RAA2213404GNPHB0  I14

PVCCFA_EHV_CPU1_PVCC   @S9S_MB_2U_LIB.S9S_MB_2U(SCH_1):PVCCFA_EHV_CPU1_PVCC
  PR250    1      A  Q_RES       I13
  PR678    2      B  Q_RES       I11
  PR699    2      B  Q_RES       I16

PVCCFA_EHV_CPU1_VDD1   @S9S_MB_2U_LIB.S9S_MB_2U(SCH_1):PVCCFA_EHV_CPU1_VDD1
  PC428    1      A  Q_CAP        I9
  PR250    2      B  Q_RES       I13
  PR1799    2      B  Q_RES       I19
  PU49     4    VCC  RAA2213404GNPHB0  I14
  PU49    22    NC1  RAA2213404GNPHB0  I14

PVCCFA_EHV_FIVRA_CPU0   @S9S_MB_2U_LIB.S9S_MB_2U(SCH_1):PVCCFA_EHV_FIVRA_CPU0
  C400     1      A  Q_CAP       I134
  C402     1      A  Q_CAP       I133
  C404     1      A  Q_CAP       I132
  C406     1      A  Q_CAP       I131
  C407     1      A  Q_CAP       I135
  C409     1      A  Q_CAP       I136
  C411     1      A  Q_CAP       I137
  C413     1      A  Q_CAP       I138
  C415     1      A  Q_CAP       I139
  C417     1      A  Q_CAP       I140
  C418     1      A  Q_CAP       I141
  C493     1      A  Q_CAP        I1
  C494     1      A  Q_CAP        I1
  C497     1      A  Q_CAP        I2
  C498     1      A  Q_CAP        I6
  C501     1      A  Q_CAP        I3
  C502     1      A  Q_CAP        I7
  C505     1      A  Q_CAP        I4
  C506     1      A  Q_CAP       I12
  C509     1      A  Q_CAP       I105
  C510     1      A  Q_CAP       I13
  C514     1      A  Q_CAP       I18
  C517     1      A  Q_CAP       I19
  C520     1      A  Q_CAP       I20
  C521     1      A  Q_CAP       I27
  C523     1      A  Q_CAP       I28
  C526     1      A  Q_CAP       I29
  C529     1      A  Q_CAP       I31
  PC1183    1      A  Q_CAPP      I56
  PC1183_P0_3    1      A  Q_CAP       I65
  PC1183_P0_4    1      A  Q_CAP       I53
  PC1185    1      A  Q_CAPP      I57
  PC1185_P0_3    1      A  Q_CAP       I67
  PC1186    1      A  Q_CAPP      I60
  PC1186_P0_4    1      A  Q_CAP       I54
  PC1187    1      A  Q_CAPP      I61
  PC1187_P0_3    1      A  Q_CAP       I68
  PC1188_P0_4    1      A  Q_CAP       I55
  PC2170    1      A  Q_CAPP      I63
  PC2645    1      A  Q_CAPP      I68
  PC612_P0_1    1      A  Q_CAP       I70
  PC613_P0_2    1      A  Q_CAP       I59
  PC615_P0_1    1      A  Q_CAP       I72
  PC616_P0_2    1      A  Q_CAP       I60
  PC617_P0_1    1      A  Q_CAP       I73
  PC618_P0_2    1      A  Q_CAP       I61
  PC619    1      A  Q_CAPP      I62
  PC620    1      A  Q_CAPP      I63
  PC621    1      A  Q_CAPP      I65
  PC623    1      A  Q_CAPP      I66
  PL2      2      2  Q_INDUCTOR  I75
  PL33     2      2  Q_INDUCTOR  I81
  PL34     2      2  Q_INDUCTOR  I82
  PL210    2      2  Q_INDUCTOR  I30
  PR587    2      B  Q_RES       I20
  PR1322    2      B  Q_RES       I53
  PR1323    2      B  Q_RES       I36
  PR1324    2      B  Q_RES       I47
  PR1325    2      B  Q_RES       I29
  U2     AA7  VCCFA_EHV_FIVRA2  SOCKET4677_AZIFS054P001C01   I4
  U2     AA11  VCCFA_EHV_FIVRA0  SOCKET4677_AZIFS054P001C01   I4
  U2     AA15  VCCFA_EHV_FIVRA1  SOCKET4677_AZIFS054P001C01   I4
  U2     AD85  VCCFA_EHV_FIVRA3  SOCKET4677_AZIFS054P001C01   I4
  U2     AD89  VCCFA_EHV_FIVRA4  SOCKET4677_AZIFS054P001C01   I4
  U2     AE7  VCCFA_EHV_FIVRA7  SOCKET4677_AZIFS054P001C01   I4
  U2     AE11  VCCFA_EHV_FIVRA5  SOCKET4677_AZIFS054P001C01   I4
  U2     AE15  VCCFA_EHV_FIVRA6  SOCKET4677_AZIFS054P001C01   I4
  U2     AF77  VCCFA_EHV_FIVRA8  SOCKET4677_AZIFS054P001C01   I4
  U2     AG78  VCCFA_EHV_FIVRA9  SOCKET4677_AZIFS054P001C01   I4
  U2     AH85  VCCFA_EHV_FIVRA10  SOCKET4677_AZIFS054P001C01   I4
  U2     AH89  VCCFA_EHV_FIVRA11  SOCKET4677_AZIFS054P001C01   I4
  U2     AJ7  VCCFA_EHV_FIVRA14  SOCKET4677_AZIFS054P001C01   I4
  U2     AJ11  VCCFA_EHV_FIVRA12  SOCKET4677_AZIFS054P001C01   I4
  U2     AJ15  VCCFA_EHV_FIVRA13  SOCKET4677_AZIFS054P001C01   I4
  U2     AM79  VCCFA_EHV_FIVRA15  SOCKET4677_AZIFS054P001C01   I4
  U2     AM85  VCCFA_EHV_FIVRA16  SOCKET4677_AZIFS054P001C01   I4
  U2     AM89  VCCFA_EHV_FIVRA17  SOCKET4677_AZIFS054P001C01   I4
  U2     AN7  VCCFA_EHV_FIVRA20  SOCKET4677_AZIFS054P001C01   I4
  U2     AN11  VCCFA_EHV_FIVRA18  SOCKET4677_AZIFS054P001C01   I4
  U2     AN15  VCCFA_EHV_FIVRA19  SOCKET4677_AZIFS054P001C01   I4
  U2     AN80  VCCFA_EHV_FIVRA21  SOCKET4677_AZIFS054P001C01   I4
  U2     AT73  VCCFA_EHV_FIVRA22  SOCKET4677_AZIFS054P001C01   I4
  U2     AT89  VCCFA_EHV_FIVRA23  SOCKET4677_AZIFS054P001C01   I4
  U2     AU15  VCCFA_EHV_FIVRA24  SOCKET4677_AZIFS054P001C01   I4
  U2     AW76  VCCFA_EHV_FIVRA25  SOCKET4677_AZIFS054P001C01   I4
  U2     AY89  VCCFA_EHV_FIVRA26  SOCKET4677_AZIFS054P001C01   I4
  U2     BE72  VCCFA_EHV_FIVRA27  SOCKET4677_AZIFS054P001C01   I4
  U2     BF77  VCCFA_EHV_FIVRA28  SOCKET4677_AZIFS054P001C01   I4
  U2     BH79  VCCFA_EHV_FIVRA29  SOCKET4677_AZIFS054P001C01   I4
  U2     BJ72  VCCFA_EHV_FIVRA30  SOCKET4677_AZIFS054P001C01   I4
  U2     BJ78  VCCFA_EHV_FIVRA31  SOCKET4677_AZIFS054P001C01   I4
  U2     C84  VCCFA_EHV_FIVRA32  SOCKET4677_AZIFS054P001C01   I4
  U2     C88  VCCFA_EHV_FIVRA33  SOCKET4677_AZIFS054P001C01   I4
  U2     CE74  VCCFA_EHV_FIVRA34  SOCKET4677_AZIFS054P001C01   I4
  U2     CK73  VCCFA_EHV_FIVRA35  SOCKET4677_AZIFS054P001C01   I4
  U2     CK79  VCCFA_EHV_FIVRA36  SOCKET4677_AZIFS054P001C01   I4
  U2     CM73  VCCFA_EHV_FIVRA37  SOCKET4677_AZIFS054P001C01   I4
  U2     CN78  VCCFA_EHV_FIVRA38  SOCKET4677_AZIFS054P001C01   I4
  U2     CP73  VCCFA_EHV_FIVRA39  SOCKET4677_AZIFS054P001C01   I4
  U2     CT77  VCCFA_EHV_FIVRA40  SOCKET4677_AZIFS054P001C01   I4
  U2     CT85  VCCFA_EHV_FIVRA41  SOCKET4677_AZIFS054P001C01   I4
  U2     CY75  VCCFA_EHV_FIVRA42  SOCKET4677_AZIFS054P001C01   I4
  U2     CY79  VCCFA_EHV_FIVRA43  SOCKET4677_AZIFS054P001C01   I4
  U2     CY85  VCCFA_EHV_FIVRA44  SOCKET4677_AZIFS054P001C01   I4
  U2     CY89  VCCFA_EHV_FIVRA45  SOCKET4677_AZIFS054P001C01   I4
  U2     DD77  VCCFA_EHV_FIVRA46  SOCKET4677_AZIFS054P001C01   I4
  U2     DD83  VCCFA_EHV_FIVRA47  SOCKET4677_AZIFS054P001C01   I4
  U2     DD85  VCCFA_EHV_FIVRA48  SOCKET4677_AZIFS054P001C01   I4
  U2     DD89  VCCFA_EHV_FIVRA49  SOCKET4677_AZIFS054P001C01   I4
  U2     DH89  VCCFA_EHV_FIVRA50  SOCKET4677_AZIFS054P001C01   I4
  U2     DM83  VCCFA_EHV_FIVRA51  SOCKET4677_AZIFS054P001C01   I4
  U2     DM85  VCCFA_EHV_FIVRA52  SOCKET4677_AZIFS054P001C01   I4
  U2     DM89  VCCFA_EHV_FIVRA53  SOCKET4677_AZIFS054P001C01   I4
  U2     DN3  VCCFA_EHV_FIVRA56  SOCKET4677_AZIFS054P001C01   I4
  U2     DN7  VCCFA_EHV_FIVRA57  SOCKET4677_AZIFS054P001C01   I4
  U2     DN11  VCCFA_EHV_FIVRA54  SOCKET4677_AZIFS054P001C01   I4
  U2     DN15  VCCFA_EHV_FIVRA55  SOCKET4677_AZIFS054P001C01   I4
  U2     DT79  VCCFA_EHV_FIVRA58  SOCKET4677_AZIFS054P001C01   I4
  U2     DT85  VCCFA_EHV_FIVRA59  SOCKET4677_AZIFS054P001C01   I4
  U2     DT89  VCCFA_EHV_FIVRA60  SOCKET4677_AZIFS054P001C01   I4
  U2     DU3  VCCFA_EHV_FIVRA63  SOCKET4677_AZIFS054P001C01   I4
  U2     DU7  VCCFA_EHV_FIVRA64  SOCKET4677_AZIFS054P001C01   I4
  U2     DU11  VCCFA_EHV_FIVRA61  SOCKET4677_AZIFS054P001C01   I4
  U2     DU15  VCCFA_EHV_FIVRA62  SOCKET4677_AZIFS054P001C01   I4
  U2     DY85  VCCFA_EHV_FIVRA65  SOCKET4677_AZIFS054P001C01   I4
  U2     DY89  VCCFA_EHV_FIVRA66  SOCKET4677_AZIFS054P001C01   I4
  U2     EA3  VCCFA_EHV_FIVRA69  SOCKET4677_AZIFS054P001C01   I4
  U2     EA7  VCCFA_EHV_FIVRA70  SOCKET4677_AZIFS054P001C01   I4
  U2     EA11  VCCFA_EHV_FIVRA67  SOCKET4677_AZIFS054P001C01   I4
  U2     EA15  VCCFA_EHV_FIVRA68  SOCKET4677_AZIFS054P001C01   I4
  U2     EC78  VCCFA_EHV_FIVRA71  SOCKET4677_AZIFS054P001C01   I4
  U2     ED79  VCCFA_EHV_FIVRA72  SOCKET4677_AZIFS054P001C01   I4
  U2     ED85  VCCFA_EHV_FIVRA73  SOCKET4677_AZIFS054P001C01   I4
  U2     ED89  VCCFA_EHV_FIVRA74  SOCKET4677_AZIFS054P001C01   I4
  U2     EE7  VCCFA_EHV_FIVRA77  SOCKET4677_AZIFS054P001C01   I4
  U2     EE11  VCCFA_EHV_FIVRA75  SOCKET4677_AZIFS054P001C01   I4
  U2     EE15  VCCFA_EHV_FIVRA76  SOCKET4677_AZIFS054P001C01   I4
  U2     EE84  VCCFA_EHV_FIVRA78  SOCKET4677_AZIFS054P001C01   I4
  U2     EF79  VCCFA_EHV_FIVRA79  SOCKET4677_AZIFS054P001C01   I4
  U2     EG80  VCCFA_EHV_FIVRA80  SOCKET4677_AZIFS054P001C01   I4
  U2     EJ15  VCCFA_EHV_FIVRA81  SOCKET4677_AZIFS054P001C01   I4
  U2     EJ84  VCCFA_EHV_FIVRA82  SOCKET4677_AZIFS054P001C01   I4
  U2     EN84  VCCFA_EHV_FIVRA83  SOCKET4677_AZIFS054P001C01   I4
  U2     H89  VCCFA_EHV_FIVRA84  SOCKET4677_AZIFS054P001C01   I4
  U2      J7  VCCFA_EHV_FIVRA86  SOCKET4677_AZIFS054P001C01   I4
  U2     J11  VCCFA_EHV_FIVRA85  SOCKET4677_AZIFS054P001C01   I4
  U2     J80  VCCFA_EHV_FIVRA87  SOCKET4677_AZIFS054P001C01   I4
  U2     K87  VCCFA_EHV_FIVRA88  SOCKET4677_AZIFS054P001C01   I4
  U2     L84  VCCFA_EHV_FIVRA89  SOCKET4677_AZIFS054P001C01   I4
  U2     M85  VCCFA_EHV_FIVRA90  SOCKET4677_AZIFS054P001C01   I4
  U2     M89  VCCFA_EHV_FIVRA91  SOCKET4677_AZIFS054P001C01   I4
  U2      N7  VCCFA_EHV_FIVRA93  SOCKET4677_AZIFS054P001C01   I4
  U2     N11  VCCFA_EHV_FIVRA92  SOCKET4677_AZIFS054P001C01   I4
  U2     P79  VCCFA_EHV_FIVRA94  SOCKET4677_AZIFS054P001C01   I4
  U2     R80  VCCFA_EHV_FIVRA95  SOCKET4677_AZIFS054P001C01   I4
  U2     T85  VCCFA_EHV_FIVRA96  SOCKET4677_AZIFS054P001C01   I4
  U2     T89  VCCFA_EHV_FIVRA97  SOCKET4677_AZIFS054P001C01   I4
  U2      U7  VCCFA_EHV_FIVRA100  SOCKET4677_AZIFS054P001C01   I4
  U2     U11  VCCFA_EHV_FIVRA98  SOCKET4677_AZIFS054P001C01   I4
  U2     U15  VCCFA_EHV_FIVRA99  SOCKET4677_AZIFS054P001C01   I4
  U2     W80  VCCFA_EHV_FIVRA101  SOCKET4677_AZIFS054P001C01   I4
  U2     Y79  VCCFA_EHV_FIVRA102  SOCKET4677_AZIFS054P001C01   I4
  U2     Y85  VCCFA_EHV_FIVRA103  SOCKET4677_AZIFS054P001C01   I4
  U2     Y89  VCCFA_EHV_FIVRA104  SOCKET4677_AZIFS054P001C01   I4

PVCCFA_EHV_FIVRA_CPU0_EN_R   @S9S_MB_2U_LIB.S9S_MB_2U(SCH_1):PVCCFA_EHV_FIVRA_CPU0_EN_R
  PC592    1      A  Q_CAP       I43
  PR337    2      B  Q_RES       I41
  PU14    24    EN1  RAA229126GNPHA0  I48

PVCCFA_EHV_FIVRA_CPU0_IMON1   @S9S_MB_2U_LIB.S9S_MB_2U(SCH_1):PVCCFA_EHV_FIVRA_CPU0_IMON1
  PU14    38    CS0  RAA229126GNPHA0  I48
  PU69_P0_1   38   IOUT  ISL99390FRZTR5935  I35

PVCCFA_EHV_FIVRA_CPU0_IMON2   @S9S_MB_2U_LIB.S9S_MB_2U(SCH_1):PVCCFA_EHV_FIVRA_CPU0_IMON2
  PU14    37    CS1  RAA229126GNPHA0  I48
  PU70_P0_2   38   IOUT  ISL99390FRZTR5935  I30

PVCCFA_EHV_FIVRA_CPU0_LSET1   @S9S_MB_2U_LIB.S9S_MB_2U(SCH_1):PVCCFA_EHV_FIVRA_CPU0_LSET1
  PR354    1      A  Q_RES       I17
  PU69_P0_1   37   LSET  ISL99390FRZTR5935  I35

PVCCFA_EHV_FIVRA_CPU0_LSET2   @S9S_MB_2U_LIB.S9S_MB_2U(SCH_1):PVCCFA_EHV_FIVRA_CPU0_LSET2
  PR353    1      A  Q_RES        I2
  PU70_P0_2   37   LSET  ISL99390FRZTR5935  I30

PVCCFA_EHV_FIVRA_CPU0_LSET3   @S9S_MB_2U_LIB.S9S_MB_2U(SCH_1):PVCCFA_EHV_FIVRA_CPU0_LSET3
  PR1298    1      A  Q_RES       I13
  PU71_P0_3   37   LSET  ISL99390FRZTR5935  I40

PVCCFA_EHV_FIVRA_CPU0_LSET4   @S9S_MB_2U_LIB.S9S_MB_2U(SCH_1):PVCCFA_EHV_FIVRA_CPU0_LSET4
  PR1297    1      A  Q_RES        I2
  PU72_P0_4   37   LSET  ISL99390FRZTR5935  I24

PVCCFA_EHV_FIVRA_CPU0_PVCC1   @S9S_MB_2U_LIB.S9S_MB_2U(SCH_1):PVCCFA_EHV_FIVRA_CPU0_PVCC1
  PC1211_P0_1    1      A  Q_CAP       I48
  PC1213_P0_3    1      A  Q_CAP       I42
  PR355    1      A  Q_RES       I25
  PR444    2      B  Q_RES       I24
  PR632    2      B  Q_RES       I26
  PR1299    1      A  Q_RES       I21
  PU69_P0_1    4   PVCC  ISL99390FRZTR5935  I35
  PU71_P0_3    4   PVCC  ISL99390FRZTR5935  I40

PVCCFA_EHV_FIVRA_CPU0_PVCC2   @S9S_MB_2U_LIB.S9S_MB_2U(SCH_1):PVCCFA_EHV_FIVRA_CPU0_PVCC2
  PC1212_P0_2    1      A  Q_CAP       I33
  PC1214_P0_4    1      A  Q_CAP       I26
  PR356    1      A  Q_RES       I10
  PR447    2      B  Q_RES       I11
  PR633    2      B  Q_RES       I14
  PR1300    1      A  Q_RES       I10
  PU70_P0_2    4   PVCC  ISL99390FRZTR5935  I30
  PU72_P0_4    4   PVCC  ISL99390FRZTR5935  I24

PVCCFA_EHV_FIVRA_CPU0_PWM1   @S9S_MB_2U_LIB.S9S_MB_2U(SCH_1):PVCCFA_EHV_FIVRA_CPU0_PWM1
  PU14     1   PWM0  RAA229126GNPHA0  I48
  PU69_P0_1   34    PWM  ISL99390FRZTR5935  I35

PVCCFA_EHV_FIVRA_CPU0_PWM2   @S9S_MB_2U_LIB.S9S_MB_2U(SCH_1):PVCCFA_EHV_FIVRA_CPU0_PWM2
  PU14     2   PWM1  RAA229126GNPHA0  I48
  PU70_P0_2   34    PWM  ISL99390FRZTR5935  I30

PVCCFA_EHV_FIVRA_CPU0_VDD1   @S9S_MB_2U_LIB.S9S_MB_2U(SCH_1):PVCCFA_EHV_FIVRA_CPU0_VDD1
  PC600    1      A  Q_CAP       I23
  PR355    2      B  Q_RES       I25
  PU69_P0_1    3    VCC  ISL99390FRZTR5935  I35
  PU69_P0_1   35     EN  ISL99390FRZTR5935  I35

PVCCFA_EHV_FIVRA_CPU0_VDD2   @S9S_MB_2U_LIB.S9S_MB_2U(SCH_1):PVCCFA_EHV_FIVRA_CPU0_VDD2
  PC601    1      A  Q_CAP        I8
  PR356    2      B  Q_RES       I10
  PU70_P0_2    3    VCC  ISL99390FRZTR5935  I30
  PU70_P0_2   35     EN  ISL99390FRZTR5935  I30

PVCCFA_EHV_FIVRA_CPU0_VDD3   @S9S_MB_2U_LIB.S9S_MB_2U(SCH_1):PVCCFA_EHV_FIVRA_CPU0_VDD3
  PC1171    1      A  Q_CAP       I20
  PR1299    2      B  Q_RES       I21
  PU71_P0_3    3    VCC  ISL99390FRZTR5935  I40
  PU71_P0_3   35     EN  ISL99390FRZTR5935  I40

PVCCFA_EHV_FIVRA_CPU0_VDD4   @S9S_MB_2U_LIB.S9S_MB_2U(SCH_1):PVCCFA_EHV_FIVRA_CPU0_VDD4
  PC1172    1      A  Q_CAP        I9
  PR1300    2      B  Q_RES       I10
  PU72_P0_4    3    VCC  ISL99390FRZTR5935  I24
  PU72_P0_4   35     EN  ISL99390FRZTR5935  I24

PVCCFA_EHV_FIVRA_CPU0_VOS1   @S9S_MB_2U_LIB.S9S_MB_2U(SCH_1):PVCCFA_EHV_FIVRA_CPU0_VOS1
  PR1322    1      A  Q_RES       I53
  PU69_P0_1    1    VOS  ISL99390FRZTR5935  I35

PVCCFA_EHV_FIVRA_CPU0_VOS2   @S9S_MB_2U_LIB.S9S_MB_2U(SCH_1):PVCCFA_EHV_FIVRA_CPU0_VOS2
  PR1323    1      A  Q_RES       I36
  PU70_P0_2    1    VOS  ISL99390FRZTR5935  I30

PVCCFA_EHV_FIVRA_CPU0_VOS3   @S9S_MB_2U_LIB.S9S_MB_2U(SCH_1):PVCCFA_EHV_FIVRA_CPU0_VOS3
  PR1324    1      A  Q_RES       I47
  PU71_P0_3    1    VOS  ISL99390FRZTR5935  I40

PVCCFA_EHV_FIVRA_CPU0_VOS4   @S9S_MB_2U_LIB.S9S_MB_2U(SCH_1):PVCCFA_EHV_FIVRA_CPU0_VOS4
  PR1325    1      A  Q_RES       I29
  PU72_P0_4    1    VOS  ISL99390FRZTR5935  I24

PVCCFA_EHV_FIVRA_CPU1   @S9S_MB_2U_LIB.S9S_MB_2U(SCH_1):PVCCFA_EHV_FIVRA_CPU1
  C424     1      A  Q_CAP        I1
  C426     1      A  Q_CAP        I3
  C428     1      A  Q_CAP        I4
  C430     1      A  Q_CAP        I5
  C431     1      A  Q_CAP        I7
  C433     1      A  Q_CAP        I8
  C435     1      A  Q_CAP        I9
  C437     1      A  Q_CAP       I10
  C439     1      A  Q_CAP       I65
  C441     1      A  Q_CAP       I66
  C442     1      A  Q_CAP       I69
  C449     1      A  Q_CAP        I3
  C450     1      A  Q_CAP        I1
  C453     1      A  Q_CAP        I5
  C454     1      A  Q_CAP        I3
  C457     1      A  Q_CAP        I7
  C458     1      A  Q_CAP        I4
  C461     1      A  Q_CAP        I9
  C462     1      A  Q_CAP        I5
  C465     1      A  Q_CAP       I11
  C466     1      A  Q_CAP        I6
  C470     1      A  Q_CAP        I7
  C473     1      A  Q_CAP        I8
  C476     1      A  Q_CAP        I9
  C477     1      A  Q_CAP       I10
  C479     1      A  Q_CAP       I11
  C482     1      A  Q_CAP       I74
  C485     1      A  Q_CAP       I76
  PC1201    1      A  Q_CAPP      I55
  PC1203    1      A  Q_CAPP      I56
  PC1203_P1_4    1      A  Q_CAP       I80
  PC1204_P1_3    1      A  Q_CAP       I66
  PC1206_P1_3    1      A  Q_CAP       I67
  PC1207_P1_4    1      A  Q_CAP       I75
  PC1208_P1_3    1      A  Q_CAP       I68
  PC1209_P1_4    1      A  Q_CAP       I54
  PC408_P1_2    1      A  Q_CAP       I282
  PC410_P1_1    1      A  Q_CAP       I265
  PC411_P1_2    1      A  Q_CAP       I248
  PC412_P1_1    1      A  Q_CAP       I268
  PC413_P1_2    1      A  Q_CAP       I249
  PC414    1      A  Q_CAPP      I252
  PC415    1      A  Q_CAPP      I253
  PC416    1      A  Q_CAPP      I254
  PC418    1      A  Q_CAPP      I270
  PC1204    1      A  Q_CAPP      I59
  PC1205    1      A  Q_CAPP      I61
  PC2171    1      A  Q_CAPP      I272
  PC2172    1      A  Q_CAPP      I63
  PC621_P1_1    1      A  Q_CAP       I281
  PL12     2      2  Q_INDUCTOR  I76
  PL18     2      2  Q_INDUCTOR  I279
  PL19     2      2  Q_INDUCTOR  I280
  PL113    2      2  Q_INDUCTOR  I77
  PR561    2      B  Q_RES       I175
  PR1331    2      B  Q_RES       I260
  PR1332    2      B  Q_RES       I239
  PR1333    2      B  Q_RES       I47
  PR1334    2      B  Q_RES       I30
  U1     AA7  VCCFA_EHV_FIVRA2  SOCKET4677_AZIFS054P001C01   I1
  U1     AA11  VCCFA_EHV_FIVRA0  SOCKET4677_AZIFS054P001C01   I1
  U1     AA15  VCCFA_EHV_FIVRA1  SOCKET4677_AZIFS054P001C01   I1
  U1     AD85  VCCFA_EHV_FIVRA3  SOCKET4677_AZIFS054P001C01   I1
  U1     AD89  VCCFA_EHV_FIVRA4  SOCKET4677_AZIFS054P001C01   I1
  U1     AE7  VCCFA_EHV_FIVRA7  SOCKET4677_AZIFS054P001C01   I1
  U1     AE11  VCCFA_EHV_FIVRA5  SOCKET4677_AZIFS054P001C01   I1
  U1     AE15  VCCFA_EHV_FIVRA6  SOCKET4677_AZIFS054P001C01   I1
  U1     AF77  VCCFA_EHV_FIVRA8  SOCKET4677_AZIFS054P001C01   I1
  U1     AG78  VCCFA_EHV_FIVRA9  SOCKET4677_AZIFS054P001C01   I1
  U1     AH85  VCCFA_EHV_FIVRA10  SOCKET4677_AZIFS054P001C01   I1
  U1     AH89  VCCFA_EHV_FIVRA11  SOCKET4677_AZIFS054P001C01   I1
  U1     AJ7  VCCFA_EHV_FIVRA14  SOCKET4677_AZIFS054P001C01   I1
  U1     AJ11  VCCFA_EHV_FIVRA12  SOCKET4677_AZIFS054P001C01   I1
  U1     AJ15  VCCFA_EHV_FIVRA13  SOCKET4677_AZIFS054P001C01   I1
  U1     AM79  VCCFA_EHV_FIVRA15  SOCKET4677_AZIFS054P001C01   I1
  U1     AM85  VCCFA_EHV_FIVRA16  SOCKET4677_AZIFS054P001C01   I1
  U1     AM89  VCCFA_EHV_FIVRA17  SOCKET4677_AZIFS054P001C01   I1
  U1     AN7  VCCFA_EHV_FIVRA20  SOCKET4677_AZIFS054P001C01   I1
  U1     AN11  VCCFA_EHV_FIVRA18  SOCKET4677_AZIFS054P001C01   I1
  U1     AN15  VCCFA_EHV_FIVRA19  SOCKET4677_AZIFS054P001C01   I1
  U1     AN80  VCCFA_EHV_FIVRA21  SOCKET4677_AZIFS054P001C01   I1
  U1     AT73  VCCFA_EHV_FIVRA22  SOCKET4677_AZIFS054P001C01   I1
  U1     AT89  VCCFA_EHV_FIVRA23  SOCKET4677_AZIFS054P001C01   I1
  U1     AU15  VCCFA_EHV_FIVRA24  SOCKET4677_AZIFS054P001C01   I1
  U1     AW76  VCCFA_EHV_FIVRA25  SOCKET4677_AZIFS054P001C01   I1
  U1     AY89  VCCFA_EHV_FIVRA26  SOCKET4677_AZIFS054P001C01   I1
  U1     BE72  VCCFA_EHV_FIVRA27  SOCKET4677_AZIFS054P001C01   I1
  U1     BF77  VCCFA_EHV_FIVRA28  SOCKET4677_AZIFS054P001C01   I1
  U1     BH79  VCCFA_EHV_FIVRA29  SOCKET4677_AZIFS054P001C01   I1
  U1     BJ72  VCCFA_EHV_FIVRA30  SOCKET4677_AZIFS054P001C01   I1
  U1     BJ78  VCCFA_EHV_FIVRA31  SOCKET4677_AZIFS054P001C01   I1
  U1     C84  VCCFA_EHV_FIVRA32  SOCKET4677_AZIFS054P001C01   I1
  U1     C88  VCCFA_EHV_FIVRA33  SOCKET4677_AZIFS054P001C01   I1
  U1     CE74  VCCFA_EHV_FIVRA34  SOCKET4677_AZIFS054P001C01   I1
  U1     CK73  VCCFA_EHV_FIVRA35  SOCKET4677_AZIFS054P001C01   I1
  U1     CK79  VCCFA_EHV_FIVRA36  SOCKET4677_AZIFS054P001C01   I1
  U1     CM73  VCCFA_EHV_FIVRA37  SOCKET4677_AZIFS054P001C01   I1
  U1     CN78  VCCFA_EHV_FIVRA38  SOCKET4677_AZIFS054P001C01   I1
  U1     CP73  VCCFA_EHV_FIVRA39  SOCKET4677_AZIFS054P001C01   I1
  U1     CT77  VCCFA_EHV_FIVRA40  SOCKET4677_AZIFS054P001C01   I1
  U1     CT85  VCCFA_EHV_FIVRA41  SOCKET4677_AZIFS054P001C01   I1
  U1     CY75  VCCFA_EHV_FIVRA42  SOCKET4677_AZIFS054P001C01   I1
  U1     CY79  VCCFA_EHV_FIVRA43  SOCKET4677_AZIFS054P001C01   I1
  U1     CY85  VCCFA_EHV_FIVRA44  SOCKET4677_AZIFS054P001C01   I1
  U1     CY89  VCCFA_EHV_FIVRA45  SOCKET4677_AZIFS054P001C01   I1
  U1     DD77  VCCFA_EHV_FIVRA46  SOCKET4677_AZIFS054P001C01   I1
  U1     DD83  VCCFA_EHV_FIVRA47  SOCKET4677_AZIFS054P001C01   I1
  U1     DD85  VCCFA_EHV_FIVRA48  SOCKET4677_AZIFS054P001C01   I1
  U1     DD89  VCCFA_EHV_FIVRA49  SOCKET4677_AZIFS054P001C01   I1
  U1     DH89  VCCFA_EHV_FIVRA50  SOCKET4677_AZIFS054P001C01   I1
  U1     DM83  VCCFA_EHV_FIVRA51  SOCKET4677_AZIFS054P001C01   I1
  U1     DM85  VCCFA_EHV_FIVRA52  SOCKET4677_AZIFS054P001C01   I1
  U1     DM89  VCCFA_EHV_FIVRA53  SOCKET4677_AZIFS054P001C01   I1
  U1     DN3  VCCFA_EHV_FIVRA56  SOCKET4677_AZIFS054P001C01   I1
  U1     DN7  VCCFA_EHV_FIVRA57  SOCKET4677_AZIFS054P001C01   I1
  U1     DN11  VCCFA_EHV_FIVRA54  SOCKET4677_AZIFS054P001C01   I1
  U1     DN15  VCCFA_EHV_FIVRA55  SOCKET4677_AZIFS054P001C01   I1
  U1     DT79  VCCFA_EHV_FIVRA58  SOCKET4677_AZIFS054P001C01   I1
  U1     DT85  VCCFA_EHV_FIVRA59  SOCKET4677_AZIFS054P001C01   I1
  U1     DT89  VCCFA_EHV_FIVRA60  SOCKET4677_AZIFS054P001C01   I1
  U1     DU3  VCCFA_EHV_FIVRA63  SOCKET4677_AZIFS054P001C01   I1
  U1     DU7  VCCFA_EHV_FIVRA64  SOCKET4677_AZIFS054P001C01   I1
  U1     DU11  VCCFA_EHV_FIVRA61  SOCKET4677_AZIFS054P001C01   I1
  U1     DU15  VCCFA_EHV_FIVRA62  SOCKET4677_AZIFS054P001C01   I1
  U1     DY85  VCCFA_EHV_FIVRA65  SOCKET4677_AZIFS054P001C01   I1
  U1     DY89  VCCFA_EHV_FIVRA66  SOCKET4677_AZIFS054P001C01   I1
  U1     EA3  VCCFA_EHV_FIVRA69  SOCKET4677_AZIFS054P001C01   I1
  U1     EA7  VCCFA_EHV_FIVRA70  SOCKET4677_AZIFS054P001C01   I1
  U1     EA11  VCCFA_EHV_FIVRA67  SOCKET4677_AZIFS054P001C01   I1
  U1     EA15  VCCFA_EHV_FIVRA68  SOCKET4677_AZIFS054P001C01   I1
  U1     EC78  VCCFA_EHV_FIVRA71  SOCKET4677_AZIFS054P001C01   I1
  U1     ED79  VCCFA_EHV_FIVRA72  SOCKET4677_AZIFS054P001C01   I1
  U1     ED85  VCCFA_EHV_FIVRA73  SOCKET4677_AZIFS054P001C01   I1
  U1     ED89  VCCFA_EHV_FIVRA74  SOCKET4677_AZIFS054P001C01   I1
  U1     EE7  VCCFA_EHV_FIVRA77  SOCKET4677_AZIFS054P001C01   I1
  U1     EE11  VCCFA_EHV_FIVRA75  SOCKET4677_AZIFS054P001C01   I1
  U1     EE15  VCCFA_EHV_FIVRA76  SOCKET4677_AZIFS054P001C01   I1
  U1     EE84  VCCFA_EHV_FIVRA78  SOCKET4677_AZIFS054P001C01   I1
  U1     EF79  VCCFA_EHV_FIVRA79  SOCKET4677_AZIFS054P001C01   I1
  U1     EG80  VCCFA_EHV_FIVRA80  SOCKET4677_AZIFS054P001C01   I1
  U1     EJ15  VCCFA_EHV_FIVRA81  SOCKET4677_AZIFS054P001C01   I1
  U1     EJ84  VCCFA_EHV_FIVRA82  SOCKET4677_AZIFS054P001C01   I1
  U1     EN84  VCCFA_EHV_FIVRA83  SOCKET4677_AZIFS054P001C01   I1
  U1     H89  VCCFA_EHV_FIVRA84  SOCKET4677_AZIFS054P001C01   I1
  U1      J7  VCCFA_EHV_FIVRA86  SOCKET4677_AZIFS054P001C01   I1
  U1     J11  VCCFA_EHV_FIVRA85  SOCKET4677_AZIFS054P001C01   I1
  U1     J80  VCCFA_EHV_FIVRA87  SOCKET4677_AZIFS054P001C01   I1
  U1     K87  VCCFA_EHV_FIVRA88  SOCKET4677_AZIFS054P001C01   I1
  U1     L84  VCCFA_EHV_FIVRA89  SOCKET4677_AZIFS054P001C01   I1
  U1     M85  VCCFA_EHV_FIVRA90  SOCKET4677_AZIFS054P001C01   I1
  U1     M89  VCCFA_EHV_FIVRA91  SOCKET4677_AZIFS054P001C01   I1
  U1      N7  VCCFA_EHV_FIVRA93  SOCKET4677_AZIFS054P001C01   I1
  U1     N11  VCCFA_EHV_FIVRA92  SOCKET4677_AZIFS054P001C01   I1
  U1     P79  VCCFA_EHV_FIVRA94  SOCKET4677_AZIFS054P001C01   I1
  U1     R80  VCCFA_EHV_FIVRA95  SOCKET4677_AZIFS054P001C01   I1
  U1     T85  VCCFA_EHV_FIVRA96  SOCKET4677_AZIFS054P001C01   I1
  U1     T89  VCCFA_EHV_FIVRA97  SOCKET4677_AZIFS054P001C01   I1
  U1      U7  VCCFA_EHV_FIVRA100  SOCKET4677_AZIFS054P001C01   I1
  U1     U11  VCCFA_EHV_FIVRA98  SOCKET4677_AZIFS054P001C01   I1
  U1     U15  VCCFA_EHV_FIVRA99  SOCKET4677_AZIFS054P001C01   I1
  U1     W80  VCCFA_EHV_FIVRA101  SOCKET4677_AZIFS054P001C01   I1
  U1     Y79  VCCFA_EHV_FIVRA102  SOCKET4677_AZIFS054P001C01   I1
  U1     Y85  VCCFA_EHV_FIVRA103  SOCKET4677_AZIFS054P001C01   I1
  U1     Y89  VCCFA_EHV_FIVRA104  SOCKET4677_AZIFS054P001C01   I1

PVCCFA_EHV_FIVRA_CPU1_EN_R   @S9S_MB_2U_LIB.S9S_MB_2U(SCH_1):PVCCFA_EHV_FIVRA_CPU1_EN_R
  PC420    1      A  Q_CAP       I206
  PR234    2      B  Q_RES       I204
  PU29    24    EN1  RAA229126GNPHA0  I211

PVCCFA_EHV_FIVRA_CPU1_IMON1   @S9S_MB_2U_LIB.S9S_MB_2U(SCH_1):PVCCFA_EHV_FIVRA_CPU1_IMON1
  PU29    38    CS0  RAA229126GNPHA0  I211
  PU75_P1_1   38   IOUT  ISL99390FRZTR5935  I278

PVCCFA_EHV_FIVRA_CPU1_IMON2   @S9S_MB_2U_LIB.S9S_MB_2U(SCH_1):PVCCFA_EHV_FIVRA_CPU1_IMON2
  PU29    37    CS1  RAA229126GNPHA0  I211
  PU76_P1_2   38   IOUT  ISL99390FRZTR5935  I221

PVCCFA_EHV_FIVRA_CPU1_IMON3   @S9S_MB_2U_LIB.S9S_MB_2U(SCH_1):PVCCFA_EHV_FIVRA_CPU1_IMON3
  PU29    36    CS2  RAA229126GNPHA0  I211
  PU77_P1_3   38   IOUT  ISL99390FRZTR5935  I27

PVCCFA_EHV_FIVRA_CPU1_IMON4   @S9S_MB_2U_LIB.S9S_MB_2U(SCH_1):PVCCFA_EHV_FIVRA_CPU1_IMON4
  PU29    35    CS3  RAA229126GNPHA0  I211
  PU78_P1_4   38   IOUT  ISL99390FRZTR5935  I24

PVCCFA_EHV_FIVRA_CPU1_LSET1   @S9S_MB_2U_LIB.S9S_MB_2U(SCH_1):PVCCFA_EHV_FIVRA_CPU1_LSET1
  PR225    1      A  Q_RES       I213
  PU75_P1_1   37   LSET  ISL99390FRZTR5935  I278

PVCCFA_EHV_FIVRA_CPU1_LSET2   @S9S_MB_2U_LIB.S9S_MB_2U(SCH_1):PVCCFA_EHV_FIVRA_CPU1_LSET2
  PR224    1      A  Q_RES       I202
  PU76_P1_2   37   LSET  ISL99390FRZTR5935  I221

PVCCFA_EHV_FIVRA_CPU1_LSET3   @S9S_MB_2U_LIB.S9S_MB_2U(SCH_1):PVCCFA_EHV_FIVRA_CPU1_LSET3
  PR1305    1      A  Q_RES       I13
  PU77_P1_3   37   LSET  ISL99390FRZTR5935  I27

PVCCFA_EHV_FIVRA_CPU1_LSET4   @S9S_MB_2U_LIB.S9S_MB_2U(SCH_1):PVCCFA_EHV_FIVRA_CPU1_LSET4
  PR1304    1      A  Q_RES        I2
  PU78_P1_4   37   LSET  ISL99390FRZTR5935  I24

PVCCFA_EHV_FIVRA_CPU1_PVCC1   @S9S_MB_2U_LIB.S9S_MB_2U(SCH_1):PVCCFA_EHV_FIVRA_CPU1_PVCC1
  PC1242_P1_1    1      A  Q_CAP       I234
  PC1244_P1_3    1      A  Q_CAP       I42
  PR226    1      A  Q_RES       I232
  PR701    2      B  Q_RES       I277
  PR703    2      B  Q_RES       I235
  PR1306    1      A  Q_RES       I21
  PU75_P1_1    4   PVCC  ISL99390FRZTR5935  I278
  PU77_P1_3    4   PVCC  ISL99390FRZTR5935  I27

PVCCFA_EHV_FIVRA_CPU1_PVCC2   @S9S_MB_2U_LIB.S9S_MB_2U(SCH_1):PVCCFA_EHV_FIVRA_CPU1_PVCC2
  PC1243_P1_2    1      A  Q_CAP       I217
  PC1245_P1_4    1      A  Q_CAP       I26
  PR227    1      A  Q_RES       I215
  PR702    2      B  Q_RES       I210
  PR704    2      B  Q_RES       I219
  PR1307    1      A  Q_RES       I10
  PU76_P1_2    4   PVCC  ISL99390FRZTR5935  I221
  PU78_P1_4    4   PVCC  ISL99390FRZTR5935  I24

PVCCFA_EHV_FIVRA_CPU1_PWM1   @S9S_MB_2U_LIB.S9S_MB_2U(SCH_1):PVCCFA_EHV_FIVRA_CPU1_PWM1
  PU29     1   PWM0  RAA229126GNPHA0  I211
  PU75_P1_1   34    PWM  ISL99390FRZTR5935  I278

PVCCFA_EHV_FIVRA_CPU1_PWM2   @S9S_MB_2U_LIB.S9S_MB_2U(SCH_1):PVCCFA_EHV_FIVRA_CPU1_PWM2
  PU29     2   PWM1  RAA229126GNPHA0  I211
  PU76_P1_2   34    PWM  ISL99390FRZTR5935  I221

PVCCFA_EHV_FIVRA_CPU1_PWM3   @S9S_MB_2U_LIB.S9S_MB_2U(SCH_1):PVCCFA_EHV_FIVRA_CPU1_PWM3
  PU29     3   PWM2  RAA229126GNPHA0  I211
  PU77_P1_3   34    PWM  ISL99390FRZTR5935  I27

PVCCFA_EHV_FIVRA_CPU1_PWM4   @S9S_MB_2U_LIB.S9S_MB_2U(SCH_1):PVCCFA_EHV_FIVRA_CPU1_PWM4
  PU29     4   PWM3  RAA229126GNPHA0  I211
  PU78_P1_4   34    PWM  ISL99390FRZTR5935  I24

PVCCFA_EHV_FIVRA_CPU1_VDD1   @S9S_MB_2U_LIB.S9S_MB_2U(SCH_1):PVCCFA_EHV_FIVRA_CPU1_VDD1
  PC395    1      A  Q_CAP       I230
  PR226    2      B  Q_RES       I232
  PU75_P1_1    3    VCC  ISL99390FRZTR5935  I278
  PU75_P1_1   35     EN  ISL99390FRZTR5935  I278

PVCCFA_EHV_FIVRA_CPU1_VDD2   @S9S_MB_2U_LIB.S9S_MB_2U(SCH_1):PVCCFA_EHV_FIVRA_CPU1_VDD2
  PC396    1      A  Q_CAP       I214
  PR227    2      B  Q_RES       I215
  PU76_P1_2    3    VCC  ISL99390FRZTR5935  I221
  PU76_P1_2   35     EN  ISL99390FRZTR5935  I221

PVCCFA_EHV_FIVRA_CPU1_VDD3   @S9S_MB_2U_LIB.S9S_MB_2U(SCH_1):PVCCFA_EHV_FIVRA_CPU1_VDD3
  PC1191    1      A  Q_CAP       I20
  PR1306    2      B  Q_RES       I21
  PU77_P1_3    3    VCC  ISL99390FRZTR5935  I27
  PU77_P1_3   35     EN  ISL99390FRZTR5935  I27

PVCCFA_EHV_FIVRA_CPU1_VDD4   @S9S_MB_2U_LIB.S9S_MB_2U(SCH_1):PVCCFA_EHV_FIVRA_CPU1_VDD4
  PC1192    1      A  Q_CAP        I9
  PR1307    2      B  Q_RES       I10
  PU78_P1_4    3    VCC  ISL99390FRZTR5935  I24
  PU78_P1_4   35     EN  ISL99390FRZTR5935  I24

PVCCFA_EHV_FIVRA_CPU1_VOS1   @S9S_MB_2U_LIB.S9S_MB_2U(SCH_1):PVCCFA_EHV_FIVRA_CPU1_VOS1
  PR1331    1      A  Q_RES       I260
  PU75_P1_1    1    VOS  ISL99390FRZTR5935  I278

PVCCFA_EHV_FIVRA_CPU1_VOS2   @S9S_MB_2U_LIB.S9S_MB_2U(SCH_1):PVCCFA_EHV_FIVRA_CPU1_VOS2
  PR1332    1      A  Q_RES       I239
  PU76_P1_2    1    VOS  ISL99390FRZTR5935  I221

PVCCFA_EHV_FIVRA_CPU1_VOS3   @S9S_MB_2U_LIB.S9S_MB_2U(SCH_1):PVCCFA_EHV_FIVRA_CPU1_VOS3
  PR1333    1      A  Q_RES       I47
  PU77_P1_3    1    VOS  ISL99390FRZTR5935  I27

PVCCFA_EHV_FIVRA_CPU1_VOS4   @S9S_MB_2U_LIB.S9S_MB_2U(SCH_1):PVCCFA_EHV_FIVRA_CPU1_VOS4
  PR1334    1      A  Q_RES       I30
  PU78_P1_4    1    VOS  ISL99390FRZTR5935  I24

PVCCINFAON_CPU0   @S9S_MB_2U_LIB.S9S_MB_2U(SCH_1):PVCCINFAON_CPU0
  C408     1      A  Q_CAP       I115
  C410     1      A  Q_CAP       I114
  C412     1      A  Q_CAP       I113
  C414     1      A  Q_CAP       I112
  C416     1      A  Q_CAP       I111
  C522     1      A  Q_CAP       I33
  C525     1      A  Q_CAP       I114
  C528     1      A  Q_CAP       I118
  C530     1      A  Q_CAP       I117
  C531     1      A  Q_CAP       I115
  C532     1      A  Q_CAP       I163
  C533     1      A  Q_CAP       I164
  C534     1      A  Q_CAP       I165
  PC1573    1      A  Q_CAPP      I201
  PC1574    1      A  Q_CAPP      I199
  PC1575    1      A  Q_CAPP      I202
  PC1576    1      A  Q_CAPP      I200
  PC1579    1      A  Q_CAPP      I215
  PC199_P0_1    1      A  Q_CAP       I191
  PC202_P0_1    1      A  Q_CAP       I192
  PC203_P0_2    1      A  Q_CAP       I194
  PC204_P0_1    1      A  Q_CAP       I197
  PC205_P0_2    1      A  Q_CAP       I195
  PL4      2      2  Q_INDUCTOR  I207
  PL5      2      2  Q_INDUCTOR  I184
  PR521    2      B  Q_RES       I16
  R323     1      A  Q_RES        I4
  U2     AY18  VCCINFAON33  SOCKET4677_AZIFS054P001C01   I7
  U2     BA15  VCCINFAON34  SOCKET4677_AZIFS054P001C01   I7
  U2     BC60  VCCINFAON35  SOCKET4677_AZIFS054P001C01   I7
  U2     BE15  VCCINFAON36  SOCKET4677_AZIFS054P001C01   I7
  U2     BE60  VCCINFAON37  SOCKET4677_AZIFS054P001C01   I7
  U2     BG60  VCCINFAON38  SOCKET4677_AZIFS054P001C01   I7
  U2     BJ15  VCCINFAON39  SOCKET4677_AZIFS054P001C01   I7
  U2     BJ60  VCCINFAON40  SOCKET4677_AZIFS054P001C01   I7
  U2     BK61  VCCINFAON41  SOCKET4677_AZIFS054P001C01   I7
  U2     BN15  VCCINFAON42  SOCKET4677_AZIFS054P001C01   I7
  U2     CA15  VCCINFAON43  SOCKET4677_AZIFS054P001C01   I7
  U2     CE15  VCCINFAON0  SOCKET4677_AZIFS054P001C01   I8
  U2     CE19  VCCINFAON44  SOCKET4677_AZIFS054P001C01   I7
  U2     CJ3  VCCINFAON2  SOCKET4677_AZIFS054P001C01   I8
  U2     CJ7  VCCINFAON3  SOCKET4677_AZIFS054P001C01   I8
  U2     CJ11  VCCINFAON45  SOCKET4677_AZIFS054P001C01   I7
  U2     CJ15  VCCINFAON1  SOCKET4677_AZIFS054P001C01   I8
  U2     CJ19  VCCINFAON46  SOCKET4677_AZIFS054P001C01   I7
  U2     CN3  VCCINFAON6  SOCKET4677_AZIFS054P001C01   I8
  U2     CN7  VCCINFAON9  SOCKET4677_AZIFS054P001C01   I8
  U2     CN11  VCCINFAON4  SOCKET4677_AZIFS054P001C01   I8
  U2     CN15  VCCINFAON5  SOCKET4677_AZIFS054P001C01   I8
  U2     CN19  VCCINFAON47  SOCKET4677_AZIFS054P001C01   I7
  U2     CN64  VCCINFAON7  SOCKET4677_AZIFS054P001C01   I8
  U2     CN66  VCCINFAON8  SOCKET4677_AZIFS054P001C01   I8
  U2     CP63  VCCINFAON48  SOCKET4677_AZIFS054P001C01   I7
  U2     CP65  VCCINFAON10  SOCKET4677_AZIFS054P001C01   I8
  U2     CP67  VCCINFAON11  SOCKET4677_AZIFS054P001C01   I8
  U2     CR66  VCCINFAON54  SOCKET4677_AZIFS054P001C01   I8
  U2     CT63  VCCINFAON49  SOCKET4677_AZIFS054P001C01   I7
  U2     CT65  VCCINFAON12  SOCKET4677_AZIFS054P001C01   I8
  U2     CT67  VCCINFAON13  SOCKET4677_AZIFS054P001C01   I8
  U2     CU3  VCCINFAON16  SOCKET4677_AZIFS054P001C01   I8
  U2     CU7  VCCINFAON18  SOCKET4677_AZIFS054P001C01   I8
  U2     CU11  VCCINFAON14  SOCKET4677_AZIFS054P001C01   I8
  U2     CU15  VCCINFAON15  SOCKET4677_AZIFS054P001C01   I8
  U2     CU64  VCCINFAON17  SOCKET4677_AZIFS054P001C01   I8
  U2     CV61  VCCINFAON50  SOCKET4677_AZIFS054P001C01   I7
  U2     CV63  VCCINFAON51  SOCKET4677_AZIFS054P001C01   I7
  U2     CV65  VCCINFAON19  SOCKET4677_AZIFS054P001C01   I8
  U2     CV67  VCCINFAON20  SOCKET4677_AZIFS054P001C01   I8
  U2     CW62  VCCINFAON52  SOCKET4677_AZIFS054P001C01   I7
  U2     CW64  VCCINFAON55  SOCKET4677_AZIFS054P001C01   I8
  U2     CW66  VCCINFAON21  SOCKET4677_AZIFS054P001C01   I8
  U2     CY65  VCCINFAON22  SOCKET4677_AZIFS054P001C01   I8
  U2     CY67  VCCINFAON23  SOCKET4677_AZIFS054P001C01   I8
  U2     DA3  VCCINFAON56  SOCKET4677_AZIFS054P001C01   I8
  U2     DA7  VCCINFAON57  SOCKET4677_AZIFS054P001C01   I8
  U2     DA11  VCCINFAON24  SOCKET4677_AZIFS054P001C01   I8
  U2     DA15  VCCINFAON25  SOCKET4677_AZIFS054P001C01   I8
  U2     DA21  VCCINFAON53  SOCKET4677_AZIFS054P001C01   I7
  U2     DA64  VCCINFAON26  SOCKET4677_AZIFS054P001C01   I8
  U2     DE3  VCCINFAON29  SOCKET4677_AZIFS054P001C01   I8
  U2     DE7  VCCINFAON58  SOCKET4677_AZIFS054P001C01   I8
  U2     DE11  VCCINFAON27  SOCKET4677_AZIFS054P001C01   I8
  U2     DE15  VCCINFAON28  SOCKET4677_AZIFS054P001C01   I8
  U2     DJ3  VCCINFAON31  SOCKET4677_AZIFS054P001C01   I8
  U2     DJ7  VCCINFAON32  SOCKET4677_AZIFS054P001C01   I8
  U2     DJ11  VCCINFAON59  SOCKET4677_AZIFS054P001C01   I8
  U2     DJ15  VCCINFAON30  SOCKET4677_AZIFS054P001C01   I8

PVCCINFAON_CPU0_ACSP1   @S9S_MB_2U_LIB.S9S_MB_2U(SCH_1):PVCCINFAON_CPU0_ACSP1
  PU43_P0_1   25   IMON  RAA2213404GNPHB0  I166
  PU5     23    CS7  ISL69260IRAZT  I51

PVCCINFAON_CPU0_ACSP2   @S9S_MB_2U_LIB.S9S_MB_2U(SCH_1):PVCCINFAON_CPU0_ACSP2
  PU44_P0_2   25   IMON  RAA2213404GNPHB0  I164
  PU5     24    CS6  ISL69260IRAZT  I51

PVCCINFAON_CPU0_ADDR   @S9S_MB_2U_LIB.S9S_MB_2U(SCH_1):PVCCINFAON_CPU0_ADDR
  PR105    2      B  Q_RES        I3
  PR106    1      A  Q_RES       I25
  PU5     34  ADDR_CFG  ISL69260IRAZT  I51

PVCCINFAON_CPU0_APWM1   @S9S_MB_2U_LIB.S9S_MB_2U(SCH_1):PVCCINFAON_CPU0_APWM1
  PU43_P0_1   21    PWM  RAA2213404GNPHB0  I166
  PU5      8   PWM7  ISL69260IRAZT  I51

PVCCINFAON_CPU0_APWM2   @S9S_MB_2U_LIB.S9S_MB_2U(SCH_1):PVCCINFAON_CPU0_APWM2
  PU44_P0_2   21    PWM  RAA2213404GNPHB0  I164
  PU5      7   PWM6  ISL69260IRAZT  I51

PVCCINFAON_CPU0_ATSEN   @S9S_MB_2U_LIB.S9S_MB_2U(SCH_1):PVCCINFAON_CPU0_ATSEN
  PC222    1      A  Q_CAP       I55
  PR435    1      A  Q_RES       I73
  PU43_P0_1    1   TMON  RAA2213404GNPHB0  I166
  PU44_P0_2    1   TMON  RAA2213404GNPHB0  I164
  PU5     35  TEMP0  ISL69260IRAZT  I51

PVCCINFAON_CPU0_CSPIN   @S9S_MB_2U_LIB.S9S_MB_2U(SCH_1):PVCCINFAON_CPU0_CSPIN
  PC214    1      A  Q_CAP       I35
  PR107    2      B  Q_RES       I28
  PR122    1      A  Q_RES       I33
  PU5     37  IINSEN||VMON||VSYS  ISL69260IRAZT  I51

PVCCINFAON_CPU0_EN_R   @S9S_MB_2U_LIB.S9S_MB_2U(SCH_1):PVCCINFAON_CPU0_EN_R
  PC217    1      A  Q_CAP       I65
  PR111    2      B  Q_RES       I64
  PU5     13    EN0  ISL69260IRAZT  I51

PVCCINFAON_CPU0_LSET1   @S9S_MB_2U_LIB.S9S_MB_2U(SCH_1):PVCCINFAON_CPU0_LSET1
  PR1708    1      A  Q_RES       I156
  PU43_P0_1    5    GL1  RAA2213404GNPHB0  I166

PVCCINFAON_CPU0_LSET2   @S9S_MB_2U_LIB.S9S_MB_2U(SCH_1):PVCCINFAON_CPU0_LSET2
  PR1707    1      A  Q_RES       I146
  PU44_P0_2    5    GL1  RAA2213404GNPHB0  I164

PVCCINFAON_CPU0_PH1_NC1   @S9S_MB_2U_LIB.S9S_MB_2U(SCH_1):PVCCINFAON_CPU0_PH1_NC1
  PR1776    1      A  Q_RES       I188
  PU43_P0_1    3  LGCTRL  RAA2213404GNPHB0  I166

PVCCINFAON_CPU0_PH2_NC1   @S9S_MB_2U_LIB.S9S_MB_2U(SCH_1):PVCCINFAON_CPU0_PH2_NC1
  PR1777    1      A  Q_RES       I180
  PU44_P0_2    3  LGCTRL  RAA2213404GNPHB0  I164

PVCCINFAON_CPU0_PIN_ALERT   @S9S_MB_2U_LIB.S9S_MB_2U(SCH_1):PVCCINFAON_CPU0_PIN_ALERT
  PR524    2      B  Q_RES       I42
  PU5     15  NPINALERT||NPSYSCRIT  ISL69260IRAZT  I51

PVCCINFAON_CPU0_PVCC   @S9S_MB_2U_LIB.S9S_MB_2U(SCH_1):PVCCINFAON_CPU0_PVCC
  PR101    1      A  Q_RES       I175
  PR102    1      A  Q_RES       I158
  PR437    2      B  Q_RES       I170
  PR441    2      B  Q_RES       I176

PVCCINFAON_CPU0_VCC   @S9S_MB_2U_LIB.S9S_MB_2U(SCH_1):PVCCINFAON_CPU0_VCC
  PC223    1      A  Q_CAP       I88
  PC225    1      A  Q_CAP       I92
  PR130    1      A  Q_RES       I95
  PU5     39    VCC  ISL69260IRAZT  I51

PVCCINFAON_CPU0_VDD1   @S9S_MB_2U_LIB.S9S_MB_2U(SCH_1):PVCCINFAON_CPU0_VDD1
  PC187    1      A  Q_CAP       I174
  PR101    2      B  Q_RES       I175
  PR1776    2      B  Q_RES       I188
  PU43_P0_1    4    VCC  RAA2213404GNPHB0  I166
  PU43_P0_1   22    NC1  RAA2213404GNPHB0  I166

PVCCINFAON_CPU0_VDD2   @S9S_MB_2U_LIB.S9S_MB_2U(SCH_1):PVCCINFAON_CPU0_VDD2
  PC188    1      A  Q_CAP       I153
  PR102    2      B  Q_RES       I158
  PR1777    2      B  Q_RES       I180
  PU44_P0_2    4    VCC  RAA2213404GNPHB0  I164
  PU44_P0_2   22    NC1  RAA2213404GNPHB0  I164

PVCCINFAON_CPU0_VIN_CSNIN   @S9S_MB_2U_LIB.S9S_MB_2U(SCH_1):PVCCINFAON_CPU0_VIN_CSNIN
  PC221    1      A  Q_CAP       I49
  PR108    2      B  Q_RES       I27
  PR123    1      A  Q_RES       I36
  PU5     38  VINSEN  ISL69260IRAZT  I51

PVCCINFAON_CPU0_VREF   @S9S_MB_2U_LIB.S9S_MB_2U(SCH_1):PVCCINFAON_CPU0_VREF
  PC224    1      A  Q_CAP       I87
  PC1346    2      B  Q_CAP       I152
  PC1347    2      B  Q_CAP       I163
  PC1348    2      B  Q_CAP        I7
  PC1372    1      A  Q_CAP       I90
  PR105    1      A  Q_RES        I3
  PU43_P0_1   24  REFIN  RAA2213404GNPHB0  I166
  PU44_P0_2   24  REFIN  RAA2213404GNPHB0  I164
  PU5     40   VCCS  ISL69260IRAZT  I51
  PU42    24  REFIN  RAA2213404GNPHB0  I11

PVCCINFAON_CPU0_VR_FAULT   @S9S_MB_2U_LIB.S9S_MB_2U(SCH_1):PVCCINFAON_CPU0_VR_FAULT
  PR523    2      B  Q_RES       I41
  PU5     33    CFP  ISL69260IRAZT  I51

PVCCINFAON_CPU1   @S9S_MB_2U_LIB.S9S_MB_2U(SCH_1):PVCCINFAON_CPU1
  C432     1      A  Q_CAP       I39
  C434     1      A  Q_CAP       I42
  C436     1      A  Q_CAP       I43
  C438     1      A  Q_CAP       I71
  C440     1      A  Q_CAP       I73
  C478     1      A  Q_CAP       I70
  C481     1      A  Q_CAP       I77
  C484     1      A  Q_CAP       I78
  C486     1      A  Q_CAP       I79
  C487     1      A  Q_CAP       I80
  C488     1      A  Q_CAP       I134
  C489     1      A  Q_CAP       I133
  C490     1      A  Q_CAP       I132
  PC1588    1      A  Q_CAPP      I48
  PC1593    1      A  Q_CAPP      I47
  PC1594    1      A  Q_CAPP      I68
  PC1595    1      A  Q_CAPP      I67
  PC1596    1      A  Q_CAPP      I69
  PC452_P1_1    1      A  Q_CAP       I58
  PC455_P1_1    1      A  Q_CAP       I59
  PC456_P1_2    1      A  Q_CAP       I41
  PC457_P1_1    1      A  Q_CAP       I62
  PC458_P1_2    1      A  Q_CAP       I43
  PL21     2      2  Q_INDUCTOR  I55
  PL22     2      2  Q_INDUCTOR  I33
  PR568    2      B  Q_RES       I98
  R329     1      A  Q_RES        I8
  U1     AY18  VCCINFAON33  SOCKET4677_AZIFS054P001C01   I1
  U1     BA15  VCCINFAON34  SOCKET4677_AZIFS054P001C01   I1
  U1     BC60  VCCINFAON35  SOCKET4677_AZIFS054P001C01   I1
  U1     BE15  VCCINFAON36  SOCKET4677_AZIFS054P001C01   I1
  U1     BE60  VCCINFAON37  SOCKET4677_AZIFS054P001C01   I1
  U1     BG60  VCCINFAON38  SOCKET4677_AZIFS054P001C01   I1
  U1     BJ15  VCCINFAON39  SOCKET4677_AZIFS054P001C01   I1
  U1     BJ60  VCCINFAON40  SOCKET4677_AZIFS054P001C01   I1
  U1     BK61  VCCINFAON41  SOCKET4677_AZIFS054P001C01   I1
  U1     BN15  VCCINFAON42  SOCKET4677_AZIFS054P001C01   I1
  U1     CA15  VCCINFAON43  SOCKET4677_AZIFS054P001C01   I1
  U1     CE15  VCCINFAON0  SOCKET4677_AZIFS054P001C01   I8
  U1     CE19  VCCINFAON44  SOCKET4677_AZIFS054P001C01   I1
  U1     CJ3  VCCINFAON2  SOCKET4677_AZIFS054P001C01   I8
  U1     CJ7  VCCINFAON3  SOCKET4677_AZIFS054P001C01   I8
  U1     CJ11  VCCINFAON45  SOCKET4677_AZIFS054P001C01   I1
  U1     CJ15  VCCINFAON1  SOCKET4677_AZIFS054P001C01   I8
  U1     CJ19  VCCINFAON46  SOCKET4677_AZIFS054P001C01   I1
  U1     CN3  VCCINFAON6  SOCKET4677_AZIFS054P001C01   I8
  U1     CN7  VCCINFAON9  SOCKET4677_AZIFS054P001C01   I8
  U1     CN11  VCCINFAON4  SOCKET4677_AZIFS054P001C01   I8
  U1     CN15  VCCINFAON5  SOCKET4677_AZIFS054P001C01   I8
  U1     CN19  VCCINFAON47  SOCKET4677_AZIFS054P001C01   I1
  U1     CN64  VCCINFAON7  SOCKET4677_AZIFS054P001C01   I8
  U1     CN66  VCCINFAON8  SOCKET4677_AZIFS054P001C01   I8
  U1     CP63  VCCINFAON48  SOCKET4677_AZIFS054P001C01   I1
  U1     CP65  VCCINFAON10  SOCKET4677_AZIFS054P001C01   I8
  U1     CP67  VCCINFAON11  SOCKET4677_AZIFS054P001C01   I8
  U1     CR66  VCCINFAON54  SOCKET4677_AZIFS054P001C01   I8
  U1     CT63  VCCINFAON49  SOCKET4677_AZIFS054P001C01   I1
  U1     CT65  VCCINFAON12  SOCKET4677_AZIFS054P001C01   I8
  U1     CT67  VCCINFAON13  SOCKET4677_AZIFS054P001C01   I8
  U1     CU3  VCCINFAON16  SOCKET4677_AZIFS054P001C01   I8
  U1     CU7  VCCINFAON18  SOCKET4677_AZIFS054P001C01   I8
  U1     CU11  VCCINFAON14  SOCKET4677_AZIFS054P001C01   I8
  U1     CU15  VCCINFAON15  SOCKET4677_AZIFS054P001C01   I8
  U1     CU64  VCCINFAON17  SOCKET4677_AZIFS054P001C01   I8
  U1     CV61  VCCINFAON50  SOCKET4677_AZIFS054P001C01   I1
  U1     CV63  VCCINFAON51  SOCKET4677_AZIFS054P001C01   I1
  U1     CV65  VCCINFAON19  SOCKET4677_AZIFS054P001C01   I8
  U1     CV67  VCCINFAON20  SOCKET4677_AZIFS054P001C01   I8
  U1     CW62  VCCINFAON52  SOCKET4677_AZIFS054P001C01   I1
  U1     CW64  VCCINFAON55  SOCKET4677_AZIFS054P001C01   I8
  U1     CW66  VCCINFAON21  SOCKET4677_AZIFS054P001C01   I8
  U1     CY65  VCCINFAON22  SOCKET4677_AZIFS054P001C01   I8
  U1     CY67  VCCINFAON23  SOCKET4677_AZIFS054P001C01   I8
  U1     DA3  VCCINFAON56  SOCKET4677_AZIFS054P001C01   I8
  U1     DA7  VCCINFAON57  SOCKET4677_AZIFS054P001C01   I8
  U1     DA11  VCCINFAON24  SOCKET4677_AZIFS054P001C01   I8
  U1     DA15  VCCINFAON25  SOCKET4677_AZIFS054P001C01   I8
  U1     DA21  VCCINFAON53  SOCKET4677_AZIFS054P001C01   I1
  U1     DA64  VCCINFAON26  SOCKET4677_AZIFS054P001C01   I8
  U1     DE3  VCCINFAON29  SOCKET4677_AZIFS054P001C01   I8
  U1     DE7  VCCINFAON58  SOCKET4677_AZIFS054P001C01   I8
  U1     DE11  VCCINFAON27  SOCKET4677_AZIFS054P001C01   I8
  U1     DE15  VCCINFAON28  SOCKET4677_AZIFS054P001C01   I8
  U1     DJ3  VCCINFAON31  SOCKET4677_AZIFS054P001C01   I8
  U1     DJ7  VCCINFAON32  SOCKET4677_AZIFS054P001C01   I8
  U1     DJ11  VCCINFAON59  SOCKET4677_AZIFS054P001C01   I8
  U1     DJ15  VCCINFAON30  SOCKET4677_AZIFS054P001C01   I8

PVCCINFAON_CPU1_ACSP1   @S9S_MB_2U_LIB.S9S_MB_2U(SCH_1):PVCCINFAON_CPU1_ACSP1
  PU22    23    CS7  ISL69260IRAZT  I61
  PU50_P1_1   25   IMON  RAA2213404GNPHB0  I17

PVCCINFAON_CPU1_ACSP2   @S9S_MB_2U_LIB.S9S_MB_2U(SCH_1):PVCCINFAON_CPU1_ACSP2
  PU22    24    CS6  ISL69260IRAZT  I61
  PU51_P1_2   25   IMON  RAA2213404GNPHB0  I12

PVCCINFAON_CPU1_ADDR   @S9S_MB_2U_LIB.S9S_MB_2U(SCH_1):PVCCINFAON_CPU1_ADDR
  PR258    2      B  Q_RES       I10
  PR259    1      A  Q_RES        I6
  PU22    34  ADDR_CFG  ISL69260IRAZT  I61

PVCCINFAON_CPU1_APWM1   @S9S_MB_2U_LIB.S9S_MB_2U(SCH_1):PVCCINFAON_CPU1_APWM1
  PU22     8   PWM7  ISL69260IRAZT  I61
  PU50_P1_1   21    PWM  RAA2213404GNPHB0  I17

PVCCINFAON_CPU1_APWM2   @S9S_MB_2U_LIB.S9S_MB_2U(SCH_1):PVCCINFAON_CPU1_APWM2
  PU22     7   PWM6  ISL69260IRAZT  I61
  PU51_P1_2   21    PWM  RAA2213404GNPHB0  I12

PVCCINFAON_CPU1_ATSEN   @S9S_MB_2U_LIB.S9S_MB_2U(SCH_1):PVCCINFAON_CPU1_ATSEN
  PC475    1      A  Q_CAP       I67
  PR665    1      A  Q_RES       I70
  PU22    35  TEMP0  ISL69260IRAZT  I61
  PU50_P1_1    1   TMON  RAA2213404GNPHB0  I17
  PU51_P1_2    1   TMON  RAA2213404GNPHB0  I12

PVCCINFAON_CPU1_CSPIN   @S9S_MB_2U_LIB.S9S_MB_2U(SCH_1):PVCCINFAON_CPU1_CSPIN
  PC467    1      A  Q_CAP       I54
  PR260    2      B  Q_RES       I12
  PR275    1      A  Q_RES       I13
  PU22    37  IINSEN||VMON||VSYS  ISL69260IRAZT  I61

PVCCINFAON_CPU1_EN_R   @S9S_MB_2U_LIB.S9S_MB_2U(SCH_1):PVCCINFAON_CPU1_EN_R
  PC470    1      A  Q_CAP       I74
  PR264    2      B  Q_RES       I51
  PU22    13    EN0  ISL69260IRAZT  I61

PVCCINFAON_CPU1_LSET1   @S9S_MB_2U_LIB.S9S_MB_2U(SCH_1):PVCCINFAON_CPU1_LSET1
  PR1726    1      A  Q_RES        I7
  PU50_P1_1    5    GL1  RAA2213404GNPHB0  I17

PVCCINFAON_CPU1_LSET2   @S9S_MB_2U_LIB.S9S_MB_2U(SCH_1):PVCCINFAON_CPU1_LSET2
  PR1727    1      A  Q_RES        I3
  PU51_P1_2    5    GL1  RAA2213404GNPHB0  I12

PVCCINFAON_CPU1_PH1_NC1   @S9S_MB_2U_LIB.S9S_MB_2U(SCH_1):PVCCINFAON_CPU1_PH1_NC1
  PR1796    1      A  Q_RES       I49
  PU50_P1_1    3  LGCTRL  RAA2213404GNPHB0  I17

PVCCINFAON_CPU1_PH2_NC1   @S9S_MB_2U_LIB.S9S_MB_2U(SCH_1):PVCCINFAON_CPU1_PH2_NC1
  PR1797    1      A  Q_RES       I31
  PU51_P1_2    3  LGCTRL  RAA2213404GNPHB0  I12

PVCCINFAON_CPU1_PIN_ALERT   @S9S_MB_2U_LIB.S9S_MB_2U(SCH_1):PVCCINFAON_CPU1_PIN_ALERT
  PR571    2      B  Q_RES       I25
  PU22    15  NPINALERT||NPSYSCRIT  ISL69260IRAZT  I61

PVCCINFAON_CPU1_PVCC   @S9S_MB_2U_LIB.S9S_MB_2U(SCH_1):PVCCINFAON_CPU1_PVCC
  PR254    1      A  Q_RES       I27
  PR255    1      A  Q_RES       I15
  PR668    2      B  Q_RES       I20
  PR677    2      B  Q_RES       I28

PVCCINFAON_CPU1_VCC   @S9S_MB_2U_LIB.S9S_MB_2U(SCH_1):PVCCINFAON_CPU1_VCC
  PC476    1      A  Q_CAP       I82
  PC478    1      A  Q_CAP       I83
  PR283    1      A  Q_RES       I89
  PU22    39    VCC  ISL69260IRAZT  I61

PVCCINFAON_CPU1_VDD1   @S9S_MB_2U_LIB.S9S_MB_2U(SCH_1):PVCCINFAON_CPU1_VDD1
  PC440    1      A  Q_CAP       I26
  PR254    2      B  Q_RES       I27
  PR1796    2      B  Q_RES       I49
  PU50_P1_1    4    VCC  RAA2213404GNPHB0  I17
  PU50_P1_1   22    NC1  RAA2213404GNPHB0  I17

PVCCINFAON_CPU1_VDD2   @S9S_MB_2U_LIB.S9S_MB_2U(SCH_1):PVCCINFAON_CPU1_VDD2
  PC441    1      A  Q_CAP       I14
  PR255    2      B  Q_RES       I15
  PR1797    2      B  Q_RES       I31
  PU51_P1_2    4    VCC  RAA2213404GNPHB0  I12
  PU51_P1_2   22    NC1  RAA2213404GNPHB0  I12

PVCCINFAON_CPU1_VIN_CSNIN   @S9S_MB_2U_LIB.S9S_MB_2U(SCH_1):PVCCINFAON_CPU1_VIN_CSNIN
  PC474    1      A  Q_CAP       I57
  PR261    2      B  Q_RES       I11
  PR276    1      A  Q_RES       I56
  PU22    38  VINSEN  ISL69260IRAZT  I61

PVCCINFAON_CPU1_VREF   @S9S_MB_2U_LIB.S9S_MB_2U(SCH_1):PVCCINFAON_CPU1_VREF
  PC477    1      A  Q_CAP       I80
  PC1193    1      A  Q_CAP       I81
  PC1364    2      B  Q_CAP       I24
  PC1365    2      B  Q_CAP       I11
  PC1366    2      B  Q_CAP        I8
  PR258    1      A  Q_RES       I10
  PU22    40   VCCS  ISL69260IRAZT  I61
  PU49    24  REFIN  RAA2213404GNPHB0  I14
  PU50_P1_1   24  REFIN  RAA2213404GNPHB0  I17
  PU51_P1_2   24  REFIN  RAA2213404GNPHB0  I12

PVCCINFAON_CPU1_VR_FAULT   @S9S_MB_2U_LIB.S9S_MB_2U(SCH_1):PVCCINFAON_CPU1_VR_FAULT
  PR570    2      B  Q_RES       I26
  PU22    33    CFP  ISL69260IRAZT  I61

PVCCIN_CPU0     @S9S_MB_2U_LIB.S9S_MB_2U(SCH_1):PVCCIN_CPU0
  C101     1      A  Q_CAP       I148
  C212     1      A  Q_CAP       I159
  C213     1      A  Q_CAP       I149
  C214     1      A  Q_CAP       I151
  C215     1      A  Q_CAP       I152
  C216     1      A  Q_CAP       I153
  C217     1      A  Q_CAP       I154
  C218     1      A  Q_CAP       I155
  C219     1      A  Q_CAP       I156
  C220     1      A  Q_CAP       I158
  C355     1      A  Q_CAP       I22
  C356     1      A  Q_CAP       I20
  C357     1      A  Q_CAP       I237
  C358     1      A  Q_CAP       I26
  C359     1      A  Q_CAP       I25
  C360     1      A  Q_CAP       I234
  C361     1      A  Q_CAP       I28
  C362     1      A  Q_CAP       I27
  C363     1      A  Q_CAP       I232
  C364     1      A  Q_CAP       I43
  C365     1      A  Q_CAP       I42
  C366     1      A  Q_CAP       I70
  C367     1      A  Q_CAP       I45
  C368     1      A  Q_CAP       I44
  C369     1      A  Q_CAP       I82
  C370     1      A  Q_CAP       I50
  C371     1      A  Q_CAP       I49
  C372     1      A  Q_CAP       I83
  C373     1      A  Q_CAP       I52
  C374     1      A  Q_CAP       I88
  C376     1      A  Q_CAP       I54
  C377     1      A  Q_CAP       I90
  C379     1      A  Q_CAP       I77
  C380     1      A  Q_CAP       I95
  C381     1      A  Q_CAP       I189
  C382     1      A  Q_CAP       I80
  C383     1      A  Q_CAP       I97
  C384     1      A  Q_CAP       I187
  C385     1      A  Q_CAP       I113
  C386     1      A  Q_CAP       I41
  C387     1      A  Q_CAP       I112
  C388     1      A  Q_CAP       I46
  C389     1      A  Q_CAP       I217
  C390     1      A  Q_CAP       I47
  C391     1      A  Q_CAP       I216
  C392     1      A  Q_CAP       I62
  C393     1      A  Q_CAP       I215
  C394     1      A  Q_CAP       I63
  C396     1      A  Q_CAP       I68
  C397     1      A  Q_CAP       I236
  C398     1      A  Q_CAP       I69
  C524     1      A  Q_CAP       I186
  C527     1      A  Q_CAP       I185
  C966     1      A  Q_CAP        I7
  C967     1      A  Q_CAP       I53
  C968     1      A  Q_CAP       I99
  C969     1      A  Q_CAP       I101
  C970     1      A  Q_CAP        I8
  C971     1      A  Q_CAP       I52
  C972     1      A  Q_CAP       I97
  C973     1      A  Q_CAP       I98
  C974     1      A  Q_CAP        I9
  C975     1      A  Q_CAP       I51
  C976     1      A  Q_CAP       I95
  C977     1      A  Q_CAP       I96
  C978     1      A  Q_CAP       I10
  C979     1      A  Q_CAP       I50
  C980     1      A  Q_CAP       I93
  C981     1      A  Q_CAP       I94
  C982     1      A  Q_CAP       I12
  C983     1      A  Q_CAP       I49
  C984     1      A  Q_CAP       I91
  C985     1      A  Q_CAP       I92
  C986     1      A  Q_CAP       I14
  C987     1      A  Q_CAP       I48
  C988     1      A  Q_CAP       I89
  C989     1      A  Q_CAP       I90
  C990     1      A  Q_CAP       I13
  C991     1      A  Q_CAP       I47
  C992     1      A  Q_CAP       I88
  C993     1      A  Q_CAP       I87
  C994     1      A  Q_CAP       I17
  C995     1      A  Q_CAP       I46
  C996     1      A  Q_CAP       I85
  C997     1      A  Q_CAP       I86
  C998     1      A  Q_CAP       I15
  C999     1      A  Q_CAP       I44
  C1000    1      A  Q_CAP       I81
  C1001    1      A  Q_CAP       I82
  C1002    1      A  Q_CAP       I16
  C1003    1      A  Q_CAP       I42
  C1004    1      A  Q_CAP       I78
  C1005    1      A  Q_CAP       I80
  C1006    1      A  Q_CAP       I29
  C1007    1      A  Q_CAP       I41
  C1008    1      A  Q_CAP       I75
  C1009    1      A  Q_CAP       I77
  C1010    1      A  Q_CAP       I18
  C1011    1      A  Q_CAP       I40
  C1012    1      A  Q_CAP       I73
  C1013    1      A  Q_CAP       I74
  C1014    1      A  Q_CAP       I19
  C1015    1      A  Q_CAP       I39
  C1016    1      A  Q_CAP       I71
  C1017    1      A  Q_CAP       I72
  C1018    1      A  Q_CAP       I20
  C1019    1      A  Q_CAP       I38
  C1020    1      A  Q_CAP       I69
  C1021    1      A  Q_CAP       I70
  C1022    1      A  Q_CAP       I21
  C1023    1      A  Q_CAP       I37
  C1024    1      A  Q_CAP       I66
  C1025    1      A  Q_CAP       I68
  C1026    1      A  Q_CAP       I22
  C1027    1      A  Q_CAP       I36
  C1028    1      A  Q_CAP       I65
  C1029    1      A  Q_CAP       I67
  C1030    1      A  Q_CAP       I23
  C1031    1      A  Q_CAP       I35
  C1032    1      A  Q_CAP       I63
  C1033    1      A  Q_CAP       I64
  C1034    1      A  Q_CAP       I24
  C1035    1      A  Q_CAP       I33
  C1036    1      A  Q_CAP       I60
  C1037    1      A  Q_CAP       I61
  C1038    1      A  Q_CAP       I26
  C1039    1      A  Q_CAP       I32
  C1040    1      A  Q_CAP       I58
  C1041    1      A  Q_CAP       I59
  C1043    1      A  Q_CAP       I30
  C1044    1      A  Q_CAP       I54
  C1045    1      A  Q_CAP       I56
  PC16     1      A  Q_CAPP      I130
  PC1920    1      A  Q_CAPP      I54
  PC2336    1      A  Q_CAPP      I53
  PC242_P0_8    1      A  Q_CAP       I104
  PC243_P0_7    1      A  Q_CAP       I79
  PC244_P0_8    1      A  Q_CAP       I103
  PC245_P0_7    1      A  Q_CAP       I78
  PC246_P0_8    1      A  Q_CAP       I101
  PC247_P0_7    1      A  Q_CAP       I77
  PC266_P0_6    1      A  Q_CAP       I95
  PC267_P0_5    1      A  Q_CAP       I80
  PC268_P0_6    1      A  Q_CAP       I94
  PC269_P0_5    1      A  Q_CAP       I79
  PC288_P0_4    1      A  Q_CAP       I96
  PC289_P0_3    1      A  Q_CAP       I79
  PC290_P0_4    1      A  Q_CAP       I95
  PC291_P0_3    1      A  Q_CAP       I78
  PC308_P0_1    1      A  Q_CAP       I111
  PC310_P0_1    1      A  Q_CAP       I110
  PC311_P0_2    1      A  Q_CAP       I128
  PC312_P0_1    1      A  Q_CAP       I109
  PC313_P0_2    1      A  Q_CAP       I127
  PC314_P0_1    1      A  Q_CAP       I108
  PC316    1      A  Q_CAPP      I56
  PC319    1      A  Q_CAPP      I58
  PC322    1      A  Q_CAPP      I59
  PC323    1      A  Q_CAPP      I55
  PC325    1      A  Q_CAPP      I81
  PC326    1      A  Q_CAPP      I79
  PL7      4      4  Q_INDUCTOR4P_14  I117
  PL8      4      4  Q_INDUCTOR4P_14  I81
  PL9      4      4  Q_INDUCTOR4P_14  I90
  PL10     4      4  Q_INDUCTOR4P_14  I74
  PL11     4      4  Q_INDUCTOR4P_14  I90
  PL13     4      4  Q_INDUCTOR4P_14  I122
  PL112    4      4  Q_INDUCTOR4P_14  I74
  PL114    4      4  Q_INDUCTOR4P_14  I104
  PR136    2      B  Q_RES       I99
  PR137    2      B  Q_RES       I84
  PR142    2      B  Q_RES       I92
  PR143    2      B  Q_RES       I76
  PR148    2      B  Q_RES       I92
  PR149    2      B  Q_RES       I76
  PR154    2      B  Q_RES       I124
  PR155    2      B  Q_RES       I112
  PR531    2      B  Q_RES       I31
  U2     BD91  VCCIN0  SOCKET4677_AZIFS054P001C01   I7
  U2     BE86  VCCIN1  SOCKET4677_AZIFS054P001C01   I7
  U2     BE88  VCCIN2  SOCKET4677_AZIFS054P001C01   I7
  U2     BE90  VCCIN3  SOCKET4677_AZIFS054P001C01   I7
  U2     BF85  VCCIN4  SOCKET4677_AZIFS054P001C01   I7
  U2     BF87  VCCIN5  SOCKET4677_AZIFS054P001C01   I7
  U2     BF89  VCCIN6  SOCKET4677_AZIFS054P001C01   I7
  U2     BF91  VCCIN7  SOCKET4677_AZIFS054P001C01   I7
  U2     BG84  VCCIN8  SOCKET4677_AZIFS054P001C01   I7
  U2     BG86  VCCIN9  SOCKET4677_AZIFS054P001C01   I7
  U2     BG88  VCCIN10  SOCKET4677_AZIFS054P001C01   I7
  U2     BG90  VCCIN11  SOCKET4677_AZIFS054P001C01   I7
  U2     BH85  VCCIN12  SOCKET4677_AZIFS054P001C01   I7
  U2     BH87  VCCIN13  SOCKET4677_AZIFS054P001C01   I7
  U2     BH89  VCCIN14  SOCKET4677_AZIFS054P001C01   I7
  U2     BH91  VCCIN15  SOCKET4677_AZIFS054P001C01   I7
  U2     BK81  VCCIN16  SOCKET4677_AZIFS054P001C01   I7
  U2     BK83  VCCIN17  SOCKET4677_AZIFS054P001C01   I7
  U2     BK85  VCCIN18  SOCKET4677_AZIFS054P001C01   I7
  U2     BK87  VCCIN19  SOCKET4677_AZIFS054P001C01   I7
  U2     BK89  VCCIN20  SOCKET4677_AZIFS054P001C01   I7
  U2     BK91  VCCIN21  SOCKET4677_AZIFS054P001C01   I7
  U2     BL80  VCCIN22  SOCKET4677_AZIFS054P001C01   I7
  U2     BL82  VCCIN23  SOCKET4677_AZIFS054P001C01   I7
  U2     BL84  VCCIN24  SOCKET4677_AZIFS054P001C01   I7
  U2     BL86  VCCIN25  SOCKET4677_AZIFS054P001C01   I7
  U2     BL88  VCCIN26  SOCKET4677_AZIFS054P001C01   I7
  U2     BL90  VCCIN27  SOCKET4677_AZIFS054P001C01   I7
  U2     BM79  VCCIN28  SOCKET4677_AZIFS054P001C01   I7
  U2     BM81  VCCIN29  SOCKET4677_AZIFS054P001C01   I7
  U2     BM83  VCCIN30  SOCKET4677_AZIFS054P001C01   I7
  U2     BM85  VCCIN31  SOCKET4677_AZIFS054P001C01   I7
  U2     BM87  VCCIN32  SOCKET4677_AZIFS054P001C01   I7
  U2     BM89  VCCIN33  SOCKET4677_AZIFS054P001C01   I7
  U2     BM91  VCCIN34  SOCKET4677_AZIFS054P001C01   I7
  U2     BN33  VCCIN35  SOCKET4677_AZIFS054P001C01   I7
  U2     BN35  VCCIN36  SOCKET4677_AZIFS054P001C01   I7
  U2     BN37  VCCIN37  SOCKET4677_AZIFS054P001C01   I7
  U2     BN39  VCCIN38  SOCKET4677_AZIFS054P001C01   I7
  U2     BN41  VCCIN39  SOCKET4677_AZIFS054P001C01   I7
  U2     BN43  VCCIN40  SOCKET4677_AZIFS054P001C01   I7
  U2     BN45  VCCIN41  SOCKET4677_AZIFS054P001C01   I7
  U2     BN48  VCCIN42  SOCKET4677_AZIFS054P001C01   I7
  U2     BN50  VCCIN43  SOCKET4677_AZIFS054P001C01   I7
  U2     BN52  VCCIN44  SOCKET4677_AZIFS054P001C01   I7
  U2     BN54  VCCIN45  SOCKET4677_AZIFS054P001C01   I7
  U2     BN56  VCCIN46  SOCKET4677_AZIFS054P001C01   I7
  U2     BN58  VCCIN47  SOCKET4677_AZIFS054P001C01   I7
  U2     BN60  VCCIN48  SOCKET4677_AZIFS054P001C01   I7
  U2     BN78  VCCIN49  SOCKET4677_AZIFS054P001C01   I7
  U2     BN80  VCCIN50  SOCKET4677_AZIFS054P001C01   I7
  U2     BN82  VCCIN51  SOCKET4677_AZIFS054P001C01   I7
  U2     BN84  VCCIN52  SOCKET4677_AZIFS054P001C01   I7
  U2     BN86  VCCIN53  SOCKET4677_AZIFS054P001C01   I7
  U2     BN88  VCCIN54  SOCKET4677_AZIFS054P001C01   I7
  U2     BN90  VCCIN55  SOCKET4677_AZIFS054P001C01   I7
  U2     BP32  VCCIN56  SOCKET4677_AZIFS054P001C01   I7
  U2     BP34  VCCIN57  SOCKET4677_AZIFS054P001C01   I7
  U2     BP36  VCCIN58  SOCKET4677_AZIFS054P001C01   I7
  U2     BP38  VCCIN59  SOCKET4677_AZIFS054P001C01   I7
  U2     BP40  VCCIN60  SOCKET4677_AZIFS054P001C01   I7
  U2     BP42  VCCIN61  SOCKET4677_AZIFS054P001C01   I7
  U2     BP44  VCCIN62  SOCKET4677_AZIFS054P001C01   I7
  U2     BP47  VCCIN63  SOCKET4677_AZIFS054P001C01   I7
  U2     BP49  VCCIN64  SOCKET4677_AZIFS054P001C01   I7
  U2     BP51  VCCIN65  SOCKET4677_AZIFS054P001C01   I7
  U2     BP53  VCCIN66  SOCKET4677_AZIFS054P001C01   I7
  U2     BP55  VCCIN67  SOCKET4677_AZIFS054P001C01   I7
  U2     BP57  VCCIN68  SOCKET4677_AZIFS054P001C01   I7
  U2     BP59  VCCIN69  SOCKET4677_AZIFS054P001C01   I7
  U2     BP61  VCCIN70  SOCKET4677_AZIFS054P001C01   I7
  U2     BP79  VCCIN71  SOCKET4677_AZIFS054P001C01   I7
  U2     BP81  VCCIN72  SOCKET4677_AZIFS054P001C01   I7
  U2     BP83  VCCIN73  SOCKET4677_AZIFS054P001C01   I7
  U2     BP85  VCCIN74  SOCKET4677_AZIFS054P001C01   I7
  U2     BP87  VCCIN75  SOCKET4677_AZIFS054P001C01   I7
  U2     BP89  VCCIN76  SOCKET4677_AZIFS054P001C01   I7
  U2     BR60  VCCIN77  SOCKET4677_AZIFS054P001C01   I7
  U2     BR62  VCCIN78  SOCKET4677_AZIFS054P001C01   I7
  U2     BR78  VCCIN79  SOCKET4677_AZIFS054P001C01   I7
  U2     BT32  VCCIN80  SOCKET4677_AZIFS054P001C01   I7
  U2     BT34  VCCIN81  SOCKET4677_AZIFS054P001C01   I7
  U2     BT36  VCCIN82  SOCKET4677_AZIFS054P001C01   I7
  U2     BT38  VCCIN83  SOCKET4677_AZIFS054P001C01   I7
  U2     BT40  VCCIN84  SOCKET4677_AZIFS054P001C01   I7
  U2     BT42  VCCIN85  SOCKET4677_AZIFS054P001C01   I7
  U2     BT44  VCCIN86  SOCKET4677_AZIFS054P001C01   I7
  U2     BT47  VCCIN87  SOCKET4677_AZIFS054P001C01   I7
  U2     BT49  VCCIN88  SOCKET4677_AZIFS054P001C01   I7
  U2     BT51  VCCIN89  SOCKET4677_AZIFS054P001C01   I7
  U2     BT53  VCCIN90  SOCKET4677_AZIFS054P001C01   I7
  U2     BT55  VCCIN91  SOCKET4677_AZIFS054P001C01   I7
  U2     BT57  VCCIN92  SOCKET4677_AZIFS054P001C01   I7
  U2     BT59  VCCIN93  SOCKET4677_AZIFS054P001C01   I7
  U2     BT61  VCCIN94  SOCKET4677_AZIFS054P001C01   I7
  U2     BT63  VCCIN95  SOCKET4677_AZIFS054P001C01   I7
  U2     BT65  VCCIN96  SOCKET4677_AZIFS054P001C01   I7
  U2     BT67  VCCIN97  SOCKET4677_AZIFS054P001C01   I7
  U2     BT69  VCCIN98  SOCKET4677_AZIFS054P001C01   I7
  U2     BT71  VCCIN99  SOCKET4677_AZIFS054P001C01   I7
  U2     BT73  VCCIN100  SOCKET4677_AZIFS054P001C01   I7
  U2     BT75  VCCIN101  SOCKET4677_AZIFS054P001C01   I7
  U2     BT77  VCCIN102  SOCKET4677_AZIFS054P001C01   I7
  U2     BT79  VCCIN103  SOCKET4677_AZIFS054P001C01   I7
  U2     BT81  VCCIN104  SOCKET4677_AZIFS054P001C01   I7
  U2     BT83  VCCIN105  SOCKET4677_AZIFS054P001C01   I7
  U2     BT85  VCCIN106  SOCKET4677_AZIFS054P001C01   I7
  U2     BT87  VCCIN107  SOCKET4677_AZIFS054P001C01   I7
  U2     BT89  VCCIN108  SOCKET4677_AZIFS054P001C01   I7
  U2     BU33  VCCIN109  SOCKET4677_AZIFS054P001C01   I7
  U2     BU35  VCCIN110  SOCKET4677_AZIFS054P001C01   I7
  U2     BU37  VCCIN111  SOCKET4677_AZIFS054P001C01   I7
  U2     BU39  VCCIN112  SOCKET4677_AZIFS054P001C01   I7
  U2     BU41  VCCIN113  SOCKET4677_AZIFS054P001C01   I7
  U2     BU43  VCCIN114  SOCKET4677_AZIFS054P001C01   I7
  U2     BU45  VCCIN115  SOCKET4677_AZIFS054P001C01   I7
  U2     BU48  VCCIN116  SOCKET4677_AZIFS054P001C01   I7
  U2     BU50  VCCIN117  SOCKET4677_AZIFS054P001C01   I7
  U2     BU52  VCCIN118  SOCKET4677_AZIFS054P001C01   I7
  U2     BU54  VCCIN119  SOCKET4677_AZIFS054P001C01   I7
  U2     BU56  VCCIN120  SOCKET4677_AZIFS054P001C01   I7
  U2     BU58  VCCIN121  SOCKET4677_AZIFS054P001C01   I7
  U2     BU60  VCCIN122  SOCKET4677_AZIFS054P001C01   I7
  U2     BU62  VCCIN123  SOCKET4677_AZIFS054P001C01   I7
  U2     BU64  VCCIN124  SOCKET4677_AZIFS054P001C01   I7
  U2     BU66  VCCIN125  SOCKET4677_AZIFS054P001C01   I7
  U2     BU68  VCCIN126  SOCKET4677_AZIFS054P001C01   I7
  U2     BU70  VCCIN127  SOCKET4677_AZIFS054P001C01   I7
  U2     BU72  VCCIN128  SOCKET4677_AZIFS054P001C01   I7
  U2     BU74  VCCIN129  SOCKET4677_AZIFS054P001C01   I7
  U2     BU76  VCCIN130  SOCKET4677_AZIFS054P001C01   I7
  U2     BU78  VCCIN131  SOCKET4677_AZIFS054P001C01   I7
  U2     BU80  VCCIN132  SOCKET4677_AZIFS054P001C01   I7
  U2     BU82  VCCIN133  SOCKET4677_AZIFS054P001C01   I7
  U2     BU84  VCCIN134  SOCKET4677_AZIFS054P001C01   I7
  U2     BU86  VCCIN135  SOCKET4677_AZIFS054P001C01   I7
  U2     BU88  VCCIN136  SOCKET4677_AZIFS054P001C01   I7
  U2     BU90  VCCIN137  SOCKET4677_AZIFS054P001C01   I7
  U2     BV32  VCCIN138  SOCKET4677_AZIFS054P001C01   I7
  U2     BV34  VCCIN139  SOCKET4677_AZIFS054P001C01   I7
  U2     BV36  VCCIN140  SOCKET4677_AZIFS054P001C01   I7
  U2     BV38  VCCIN141  SOCKET4677_AZIFS054P001C01   I7
  U2     BV40  VCCIN142  SOCKET4677_AZIFS054P001C01   I7
  U2     BV42  VCCIN143  SOCKET4677_AZIFS054P001C01   I7
  U2     BV44  VCCIN144  SOCKET4677_AZIFS054P001C01   I7
  U2     BV47  VCCIN145  SOCKET4677_AZIFS054P001C01   I7
  U2     BV49  VCCIN146  SOCKET4677_AZIFS054P001C01   I7
  U2     BV51  VCCIN147  SOCKET4677_AZIFS054P001C01   I7
  U2     BV53  VCCIN148  SOCKET4677_AZIFS054P001C01   I7
  U2     BV55  VCCIN149  SOCKET4677_AZIFS054P001C01   I7
  U2     BV57  VCCIN150  SOCKET4677_AZIFS054P001C01   I7
  U2     BV59  VCCIN151  SOCKET4677_AZIFS054P001C01   I7
  U2     BV61  VCCIN152  SOCKET4677_AZIFS054P001C01   I7
  U2     BV63  VCCIN153  SOCKET4677_AZIFS054P001C01   I7
  U2     BV65  VCCIN154  SOCKET4677_AZIFS054P001C01   I7
  U2     BV67  VCCIN155  SOCKET4677_AZIFS054P001C01   I7
  U2     BV69  VCCIN156  SOCKET4677_AZIFS054P001C01   I7
  U2     BV71  VCCIN157  SOCKET4677_AZIFS054P001C01   I7
  U2     BV73  VCCIN158  SOCKET4677_AZIFS054P001C01   I7
  U2     BV75  VCCIN159  SOCKET4677_AZIFS054P001C01   I7
  U2     BV77  VCCIN160  SOCKET4677_AZIFS054P001C01   I7
  U2     BV79  VCCIN161  SOCKET4677_AZIFS054P001C01   I7
  U2     BV81  VCCIN162  SOCKET4677_AZIFS054P001C01   I7
  U2     BV83  VCCIN163  SOCKET4677_AZIFS054P001C01   I7
  U2     BV85  VCCIN164  SOCKET4677_AZIFS054P001C01   I7
  U2     BV87  VCCIN165  SOCKET4677_AZIFS054P001C01   I7
  U2     BV89  VCCIN166  SOCKET4677_AZIFS054P001C01   I7
  U2     BW33  VCCIN167  SOCKET4677_AZIFS054P001C01   I7
  U2     BW35  VCCIN168  SOCKET4677_AZIFS054P001C01   I7
  U2     BW37  VCCIN169  SOCKET4677_AZIFS054P001C01   I7
  U2     BW39  VCCIN170  SOCKET4677_AZIFS054P001C01   I7
  U2     BW41  VCCIN171  SOCKET4677_AZIFS054P001C01   I7
  U2     BW43  VCCIN172  SOCKET4677_AZIFS054P001C01   I7
  U2     BW45  VCCIN173  SOCKET4677_AZIFS054P001C01   I7
  U2     BW48  VCCIN174  SOCKET4677_AZIFS054P001C01   I7
  U2     BW50  VCCIN175  SOCKET4677_AZIFS054P001C01   I7
  U2     BW52  VCCIN176  SOCKET4677_AZIFS054P001C01   I7
  U2     BW54  VCCIN177  SOCKET4677_AZIFS054P001C01   I7
  U2     BW56  VCCIN178  SOCKET4677_AZIFS054P001C01   I7
  U2     BW58  VCCIN179  SOCKET4677_AZIFS054P001C01   I7
  U2     BW60  VCCIN180  SOCKET4677_AZIFS054P001C01   I7
  U2     BW62  VCCIN181  SOCKET4677_AZIFS054P001C01   I7
  U2     BW64  VCCIN182  SOCKET4677_AZIFS054P001C01   I7
  U2     BW66  VCCIN183  SOCKET4677_AZIFS054P001C01   I7
  U2     BW68  VCCIN184  SOCKET4677_AZIFS054P001C01   I7
  U2     BW70  VCCIN185  SOCKET4677_AZIFS054P001C01   I7
  U2     BW72  VCCIN186  SOCKET4677_AZIFS054P001C01   I7
  U2     BW74  VCCIN187  SOCKET4677_AZIFS054P001C01   I7
  U2     BW76  VCCIN188  SOCKET4677_AZIFS054P001C01   I7
  U2     BW78  VCCIN189  SOCKET4677_AZIFS054P001C01   I7
  U2     BW80  VCCIN190  SOCKET4677_AZIFS054P001C01   I1
  U2     BW82  VCCIN191  SOCKET4677_AZIFS054P001C01   I1
  U2     BW84  VCCIN192  SOCKET4677_AZIFS054P001C01   I1
  U2     BW86  VCCIN193  SOCKET4677_AZIFS054P001C01   I1
  U2     BW88  VCCIN194  SOCKET4677_AZIFS054P001C01   I1
  U2     BW90  VCCIN195  SOCKET4677_AZIFS054P001C01   I1
  U2     BY32  VCCIN196  SOCKET4677_AZIFS054P001C01   I1
  U2     BY34  VCCIN197  SOCKET4677_AZIFS054P001C01   I1
  U2     BY36  VCCIN198  SOCKET4677_AZIFS054P001C01   I1
  U2     BY38  VCCIN199  SOCKET4677_AZIFS054P001C01   I1
  U2     BY40  VCCIN200  SOCKET4677_AZIFS054P001C01   I1
  U2     BY42  VCCIN201  SOCKET4677_AZIFS054P001C01   I1
  U2     BY44  VCCIN202  SOCKET4677_AZIFS054P001C01   I1
  U2     BY47  VCCIN203  SOCKET4677_AZIFS054P001C01   I1
  U2     BY49  VCCIN204  SOCKET4677_AZIFS054P001C01   I1
  U2     BY51  VCCIN205  SOCKET4677_AZIFS054P001C01   I1
  U2     BY53  VCCIN206  SOCKET4677_AZIFS054P001C01   I1
  U2     BY55  VCCIN207  SOCKET4677_AZIFS054P001C01   I1
  U2     BY57  VCCIN208  SOCKET4677_AZIFS054P001C01   I1
  U2     BY59  VCCIN209  SOCKET4677_AZIFS054P001C01   I1
  U2     BY61  VCCIN210  SOCKET4677_AZIFS054P001C01   I1
  U2     BY63  VCCIN211  SOCKET4677_AZIFS054P001C01   I1
  U2     BY65  VCCIN212  SOCKET4677_AZIFS054P001C01   I1
  U2     BY67  VCCIN213  SOCKET4677_AZIFS054P001C01   I1
  U2     BY69  VCCIN214  SOCKET4677_AZIFS054P001C01   I1
  U2     BY71  VCCIN215  SOCKET4677_AZIFS054P001C01   I1
  U2     BY73  VCCIN216  SOCKET4677_AZIFS054P001C01   I1
  U2     BY75  VCCIN217  SOCKET4677_AZIFS054P001C01   I1
  U2     BY77  VCCIN218  SOCKET4677_AZIFS054P001C01   I1
  U2     BY79  VCCIN219  SOCKET4677_AZIFS054P001C01   I1
  U2     BY81  VCCIN220  SOCKET4677_AZIFS054P001C01   I1
  U2     BY83  VCCIN221  SOCKET4677_AZIFS054P001C01   I1
  U2     BY85  VCCIN222  SOCKET4677_AZIFS054P001C01   I1
  U2     BY87  VCCIN223  SOCKET4677_AZIFS054P001C01   I1
  U2     BY89  VCCIN224  SOCKET4677_AZIFS054P001C01   I1
  U2     CA33  VCCIN225  SOCKET4677_AZIFS054P001C01   I1
  U2     CA35  VCCIN226  SOCKET4677_AZIFS054P001C01   I1
  U2     CA37  VCCIN227  SOCKET4677_AZIFS054P001C01   I1
  U2     CA39  VCCIN228  SOCKET4677_AZIFS054P001C01   I1
  U2     CA41  VCCIN229  SOCKET4677_AZIFS054P001C01   I1
  U2     CA43  VCCIN230  SOCKET4677_AZIFS054P001C01   I1
  U2     CA45  VCCIN231  SOCKET4677_AZIFS054P001C01   I1
  U2     CA48  VCCIN232  SOCKET4677_AZIFS054P001C01   I1
  U2     CA50  VCCIN233  SOCKET4677_AZIFS054P001C01   I1
  U2     CA52  VCCIN234  SOCKET4677_AZIFS054P001C01   I1
  U2     CA54  VCCIN235  SOCKET4677_AZIFS054P001C01   I1
  U2     CA56  VCCIN236  SOCKET4677_AZIFS054P001C01   I1
  U2     CA58  VCCIN237  SOCKET4677_AZIFS054P001C01   I1
  U2     CA60  VCCIN238  SOCKET4677_AZIFS054P001C01   I1
  U2     CA62  VCCIN239  SOCKET4677_AZIFS054P001C01   I1
  U2     CA64  VCCIN240  SOCKET4677_AZIFS054P001C01   I1
  U2     CA66  VCCIN241  SOCKET4677_AZIFS054P001C01   I1
  U2     CA68  VCCIN242  SOCKET4677_AZIFS054P001C01   I1
  U2     CA70  VCCIN243  SOCKET4677_AZIFS054P001C01   I1
  U2     CA72  VCCIN244  SOCKET4677_AZIFS054P001C01   I1
  U2     CA74  VCCIN245  SOCKET4677_AZIFS054P001C01   I1
  U2     CA76  VCCIN246  SOCKET4677_AZIFS054P001C01   I1
  U2     CA78  VCCIN247  SOCKET4677_AZIFS054P001C01   I1
  U2     CA80  VCCIN248  SOCKET4677_AZIFS054P001C01   I1
  U2     CA82  VCCIN249  SOCKET4677_AZIFS054P001C01   I1
  U2     CA84  VCCIN250  SOCKET4677_AZIFS054P001C01   I1
  U2     CA86  VCCIN251  SOCKET4677_AZIFS054P001C01   I1
  U2     CA88  VCCIN252  SOCKET4677_AZIFS054P001C01   I1
  U2     CA90  VCCIN253  SOCKET4677_AZIFS054P001C01   I1
  U2     CB61  VCCIN254  SOCKET4677_AZIFS054P001C01   I1
  U2     CB75  VCCIN255  SOCKET4677_AZIFS054P001C01   I1
  U2     CB77  VCCIN256  SOCKET4677_AZIFS054P001C01   I1
  U2     CC33  VCCIN257  SOCKET4677_AZIFS054P001C01   I1
  U2     CC35  VCCIN258  SOCKET4677_AZIFS054P001C01   I1
  U2     CC37  VCCIN259  SOCKET4677_AZIFS054P001C01   I1
  U2     CC39  VCCIN260  SOCKET4677_AZIFS054P001C01   I1
  U2     CC41  VCCIN261  SOCKET4677_AZIFS054P001C01   I1
  U2     CC43  VCCIN262  SOCKET4677_AZIFS054P001C01   I1
  U2     CC45  VCCIN263  SOCKET4677_AZIFS054P001C01   I1
  U2     CC48  VCCIN264  SOCKET4677_AZIFS054P001C01   I1
  U2     CC50  VCCIN265  SOCKET4677_AZIFS054P001C01   I1
  U2     CC52  VCCIN266  SOCKET4677_AZIFS054P001C01   I1
  U2     CC54  VCCIN267  SOCKET4677_AZIFS054P001C01   I1
  U2     CC56  VCCIN268  SOCKET4677_AZIFS054P001C01   I1
  U2     CC58  VCCIN269  SOCKET4677_AZIFS054P001C01   I1
  U2     CC60  VCCIN270  SOCKET4677_AZIFS054P001C01   I1
  U2     CC76  VCCIN271  SOCKET4677_AZIFS054P001C01   I1
  U2     CC78  VCCIN272  SOCKET4677_AZIFS054P001C01   I1
  U2     CC80  VCCIN273  SOCKET4677_AZIFS054P001C01   I1
  U2     CC82  VCCIN274  SOCKET4677_AZIFS054P001C01   I1
  U2     CC84  VCCIN275  SOCKET4677_AZIFS054P001C01   I1
  U2     CC86  VCCIN276  SOCKET4677_AZIFS054P001C01   I1
  U2     CC88  VCCIN277  SOCKET4677_AZIFS054P001C01   I1
  U2     CC90  VCCIN278  SOCKET4677_AZIFS054P001C01   I1
  U2     CD32  VCCIN279  SOCKET4677_AZIFS054P001C01   I1
  U2     CD34  VCCIN280  SOCKET4677_AZIFS054P001C01   I1
  U2     CD36  VCCIN281  SOCKET4677_AZIFS054P001C01   I1
  U2     CD38  VCCIN282  SOCKET4677_AZIFS054P001C01   I1
  U2     CD40  VCCIN283  SOCKET4677_AZIFS054P001C01   I1
  U2     CD42  VCCIN284  SOCKET4677_AZIFS054P001C01   I1
  U2     CD44  VCCIN285  SOCKET4677_AZIFS054P001C01   I1
  U2     CD47  VCCIN286  SOCKET4677_AZIFS054P001C01   I1
  U2     CD49  VCCIN287  SOCKET4677_AZIFS054P001C01   I1
  U2     CD51  VCCIN288  SOCKET4677_AZIFS054P001C01   I1
  U2     CD53  VCCIN289  SOCKET4677_AZIFS054P001C01   I1
  U2     CD55  VCCIN290  SOCKET4677_AZIFS054P001C01   I1
  U2     CD57  VCCIN291  SOCKET4677_AZIFS054P001C01   I1
  U2     CD59  VCCIN292  SOCKET4677_AZIFS054P001C01   I1
  U2     CD79  VCCIN293  SOCKET4677_AZIFS054P001C01   I1
  U2     CD81  VCCIN294  SOCKET4677_AZIFS054P001C01   I1
  U2     CD83  VCCIN295  SOCKET4677_AZIFS054P001C01   I1
  U2     CD85  VCCIN296  SOCKET4677_AZIFS054P001C01   I1
  U2     CD87  VCCIN297  SOCKET4677_AZIFS054P001C01   I1
  U2     CD89  VCCIN298  SOCKET4677_AZIFS054P001C01   I1
  U2     CE80  VCCIN299  SOCKET4677_AZIFS054P001C01   I1
  U2     CE82  VCCIN300  SOCKET4677_AZIFS054P001C01   I1
  U2     CE84  VCCIN301  SOCKET4677_AZIFS054P001C01   I1
  U2     CE86  VCCIN302  SOCKET4677_AZIFS054P001C01   I1
  U2     CE88  VCCIN303  SOCKET4677_AZIFS054P001C01   I1
  U2     CE90  VCCIN304  SOCKET4677_AZIFS054P001C01   I1
  U2     CF79  VCCIN305  SOCKET4677_AZIFS054P001C01   I1
  U2     CF81  VCCIN306  SOCKET4677_AZIFS054P001C01   I1
  U2     CF83  VCCIN307  SOCKET4677_AZIFS054P001C01   I1
  U2     CF85  VCCIN308  SOCKET4677_AZIFS054P001C01   I1
  U2     CF87  VCCIN309  SOCKET4677_AZIFS054P001C01   I1
  U2     CF89  VCCIN310  SOCKET4677_AZIFS054P001C01   I1
  U2     CF91  VCCIN311  SOCKET4677_AZIFS054P001C01   I1
  U2     CG80  VCCIN312  SOCKET4677_AZIFS054P001C01   I1
  U2     CG82  VCCIN313  SOCKET4677_AZIFS054P001C01   I1
  U2     CG84  VCCIN314  SOCKET4677_AZIFS054P001C01   I1
  U2     CG86  VCCIN315  SOCKET4677_AZIFS054P001C01   I1
  U2     CG88  VCCIN316  SOCKET4677_AZIFS054P001C01   I1
  U2     CG90  VCCIN317  SOCKET4677_AZIFS054P001C01   I1
  U2     CH81  VCCIN318  SOCKET4677_AZIFS054P001C01   I1
  U2     CH91  VCCIN319  SOCKET4677_AZIFS054P001C01   I1
  U2     CJ82  VCCIN320  SOCKET4677_AZIFS054P001C01   I1
  U2     CJ84  VCCIN321  SOCKET4677_AZIFS054P001C01   I1
  U2     CJ86  VCCIN322  SOCKET4677_AZIFS054P001C01   I1
  U2     CJ88  VCCIN323  SOCKET4677_AZIFS054P001C01   I1
  U2     CJ90  VCCIN324  SOCKET4677_AZIFS054P001C01   I1
  U2     CK83  VCCIN325  SOCKET4677_AZIFS054P001C01   I1
  U2     CK85  VCCIN326  SOCKET4677_AZIFS054P001C01   I1
  U2     CK87  VCCIN327  SOCKET4677_AZIFS054P001C01   I1
  U2     CK89  VCCIN328  SOCKET4677_AZIFS054P001C01   I1
  U2     CK91  VCCIN329  SOCKET4677_AZIFS054P001C01   I1
  U2     CL84  VCCIN330  SOCKET4677_AZIFS054P001C01   I1
  U2     CL86  VCCIN331  SOCKET4677_AZIFS054P001C01   I1
  U2     CL88  VCCIN332  SOCKET4677_AZIFS054P001C01   I1
  U2     CL90  VCCIN333  SOCKET4677_AZIFS054P001C01   I1
  U2     CM87  VCCIN334  SOCKET4677_AZIFS054P001C01   I1
  U2     CM89  VCCIN339  SOCKET4677_AZIFS054P001C01   I1
  U2     CM91  VCCIN335  SOCKET4677_AZIFS054P001C01   I1
  U2     CN88  VCCIN336  SOCKET4677_AZIFS054P001C01   I1
  U2     CN90  VCCIN337  SOCKET4677_AZIFS054P001C01   I1
  U2     CP89  VCCIN338  SOCKET4677_AZIFS054P001C01   I1

PVCCIN_CPU0_ADDR   @S9S_MB_2U_LIB.S9S_MB_2U(SCH_1):PVCCIN_CPU0_ADDR
  PR159    2      B  Q_RES        I7
  PR171    1      A  Q_RES        I5
  PU14    42  ADDR_CFG  RAA229126GNPHA0  I48

PVCCIN_CPU0_ATSEN   @S9S_MB_2U_LIB.S9S_MB_2U(SCH_1):PVCCIN_CPU0_ATSEN
  PC336    1      A  Q_CAP       I58
  PR400    1      A  Q_RES       I77
  PU10_P0_4   36  TOUT_FLT  ISL99390FRZTR5935  I14
  PU11_P0_3   36  TOUT_FLT  ISL99390FRZTR5935  I30
  PU12_P0_2   36  TOUT_FLT  ISL99390FRZTR5935  I87
  PU13_P0_1   36  TOUT_FLT  ISL99390FRZTR5935  I21
  PU14    43  TEMP0  RAA229126GNPHA0  I48
  PU69_P0_1   36  TOUT_FLT  ISL99390FRZTR5935  I35
  PU6_P0_8   36  TOUT_FLT  ISL99390FRZTR5935  I64
  PU70_P0_2   36  TOUT_FLT  ISL99390FRZTR5935  I30
  PU71_P0_3   36  TOUT_FLT  ISL99390FRZTR5935  I40
  PU72_P0_4   36  TOUT_FLT  ISL99390FRZTR5935  I24
  PU7_P0_7   36  TOUT_FLT  ISL99390FRZTR5935  I20
  PU8_P0_6   36  TOUT_FLT  ISL99390FRZTR5935  I62
  PU9_P0_5   36  TOUT_FLT  ISL99390FRZTR5935  I31

PVCCIN_CPU0_CSPIN   @S9S_MB_2U_LIB.S9S_MB_2U(SCH_1):PVCCIN_CPU0_CSPIN
  PC329    1      A  Q_CAP       I38
  PR157    2      B  Q_RES        I9
  PR158    1      A  Q_RES       I36
  PU14    45  VMON||IINSEN||VSYS||ISYS  RAA229126GNPHA0  I48

PVCCIN_CPU0_EN_R   @S9S_MB_2U_LIB.S9S_MB_2U(SCH_1):PVCCIN_CPU0_EN_R
  PC332    1      A  Q_CAP       I67
  PR162    2      B  Q_RES       I69
  PU14    17    EN0  RAA229126GNPHA0  I48

PVCCIN_CPU0_IMON1   @S9S_MB_2U_LIB.S9S_MB_2U(SCH_1):PVCCIN_CPU0_IMON1
  PU13_P0_1   38   IOUT  ISL99390FRZTR5935  I21
  PU14    27   CS11  RAA229126GNPHA0  I48

PVCCIN_CPU0_IMON2   @S9S_MB_2U_LIB.S9S_MB_2U(SCH_1):PVCCIN_CPU0_IMON2
  PU12_P0_2   38   IOUT  ISL99390FRZTR5935  I87
  PU14    28   CS10  RAA229126GNPHA0  I48

PVCCIN_CPU0_IMON3   @S9S_MB_2U_LIB.S9S_MB_2U(SCH_1):PVCCIN_CPU0_IMON3
  PU11_P0_3   38   IOUT  ISL99390FRZTR5935  I30
  PU14    29    CS9  RAA229126GNPHA0  I48

PVCCIN_CPU0_IMON4   @S9S_MB_2U_LIB.S9S_MB_2U(SCH_1):PVCCIN_CPU0_IMON4
  PU10_P0_4   38   IOUT  ISL99390FRZTR5935  I14
  PU14    30    CS8  RAA229126GNPHA0  I48

PVCCIN_CPU0_IMON5   @S9S_MB_2U_LIB.S9S_MB_2U(SCH_1):PVCCIN_CPU0_IMON5
  PU14    31    CS7  RAA229126GNPHA0  I48
  PU9_P0_5   38   IOUT  ISL99390FRZTR5935  I31

PVCCIN_CPU0_IMON6   @S9S_MB_2U_LIB.S9S_MB_2U(SCH_1):PVCCIN_CPU0_IMON6
  PU14    32    CS6  RAA229126GNPHA0  I48
  PU8_P0_6   38   IOUT  ISL99390FRZTR5935  I62

PVCCIN_CPU0_IMON7   @S9S_MB_2U_LIB.S9S_MB_2U(SCH_1):PVCCIN_CPU0_IMON7
  PU14    33    CS5  RAA229126GNPHA0  I48
  PU7_P0_7   38   IOUT  ISL99390FRZTR5935  I20

PVCCIN_CPU0_IMON8   @S9S_MB_2U_LIB.S9S_MB_2U(SCH_1):PVCCIN_CPU0_IMON8
  PU14    34    CS4  RAA229126GNPHA0  I48
  PU6_P0_8   38   IOUT  ISL99390FRZTR5935  I64

PVCCIN_CPU0_ISYS_R   @S9S_MB_2U_LIB.S9S_MB_2U(SCH_1):PVCCIN_CPU0_ISYS_R
  PR450    1      A  Q_RES       I82
  PR451    1      A  Q_RES       I81
  PU14    44  TEMP1||ISYS  RAA229126GNPHA0  I48

PVCCIN_CPU0_LSET1   @S9S_MB_2U_LIB.S9S_MB_2U(SCH_1):PVCCIN_CPU0_LSET1
  PR151    1      A  Q_RES       I14
  PU13_P0_1   37   LSET  ISL99390FRZTR5935  I21

PVCCIN_CPU0_LSET2   @S9S_MB_2U_LIB.S9S_MB_2U(SCH_1):PVCCIN_CPU0_LSET2
  PR150    1      A  Q_RES        I2
  PU12_P0_2   37   LSET  ISL99390FRZTR5935  I87

PVCCIN_CPU0_LSET3   @S9S_MB_2U_LIB.S9S_MB_2U(SCH_1):PVCCIN_CPU0_LSET3
  PR145    1      A  Q_RES       I19
  PU11_P0_3   37   LSET  ISL99390FRZTR5935  I30

PVCCIN_CPU0_LSET4   @S9S_MB_2U_LIB.S9S_MB_2U(SCH_1):PVCCIN_CPU0_LSET4
  PR144    1      A  Q_RES        I2
  PU10_P0_4   37   LSET  ISL99390FRZTR5935  I14

PVCCIN_CPU0_LSET5   @S9S_MB_2U_LIB.S9S_MB_2U(SCH_1):PVCCIN_CPU0_LSET5
  PR139    1      A  Q_RES       I21
  PU9_P0_5   37   LSET  ISL99390FRZTR5935  I31

PVCCIN_CPU0_LSET6   @S9S_MB_2U_LIB.S9S_MB_2U(SCH_1):PVCCIN_CPU0_LSET6
  PR138    1      A  Q_RES        I2
  PU8_P0_6   37   LSET  ISL99390FRZTR5935  I62

PVCCIN_CPU0_LSET7   @S9S_MB_2U_LIB.S9S_MB_2U(SCH_1):PVCCIN_CPU0_LSET7
  PR133    1      A  Q_RES       I13
  PU7_P0_7   37   LSET  ISL99390FRZTR5935  I20

PVCCIN_CPU0_LSET8   @S9S_MB_2U_LIB.S9S_MB_2U(SCH_1):PVCCIN_CPU0_LSET8
  PR132    1      A  Q_RES        I2
  PU6_P0_8   37   LSET  ISL99390FRZTR5935  I64

PVCCIN_CPU0_PIN_ALERT   @S9S_MB_2U_LIB.S9S_MB_2U(SCH_1):PVCCIN_CPU0_PIN_ALERT
  PR169    2      B  Q_RES       I51
  PU14    19  NPINALERT||NPSYS_CRIT  RAA229126GNPHA0  I48
  R541     2      B  Q_RES       I15

PVCCIN_CPU0_PVCC   @S9S_MB_2U_LIB.S9S_MB_2U(SCH_1):PVCCIN_CPU0_PVCC
  PC228_P0_8    1      A  Q_CAP       I19
  PC229_P0_7    1      A  Q_CAP       I30
  PC250_P0_6    1      A  Q_CAP       I12
  PC251_P0_5    1      A  Q_CAP       I34
  PC272_P0_4    1      A  Q_CAP       I17
  PC273_P0_3    1      A  Q_CAP       I32
  PC294_P0_2    1      A  Q_CAP       I18
  PC295_P0_1    1      A  Q_CAP       I35
  PR134    1      A  Q_RES       I10
  PR135    1      A  Q_RES       I26
  PR140    1      A  Q_RES       I11
  PR141    1      A  Q_RES       I32
  PR146    1      A  Q_RES       I10
  PR147    1      A  Q_RES       I27
  PR152    1      A  Q_RES       I11
  PR153    1      A  Q_RES       I32
  PR402    2      B  Q_RES       I31
  PR403    2      B  Q_RES       I36
  PU10_P0_4    4   PVCC  ISL99390FRZTR5935  I14
  PU11_P0_3    4   PVCC  ISL99390FRZTR5935  I30
  PU12_P0_2    4   PVCC  ISL99390FRZTR5935  I87
  PU13_P0_1    4   PVCC  ISL99390FRZTR5935  I21
  PU6_P0_8    4   PVCC  ISL99390FRZTR5935  I64
  PU7_P0_7    4   PVCC  ISL99390FRZTR5935  I20
  PU8_P0_6    4   PVCC  ISL99390FRZTR5935  I62
  PU9_P0_5    4   PVCC  ISL99390FRZTR5935  I31

PVCCIN_CPU0_PWM1   @S9S_MB_2U_LIB.S9S_MB_2U(SCH_1):PVCCIN_CPU0_PWM1
  PU13_P0_1   34    PWM  ISL99390FRZTR5935  I21
  PU14    12  PWM11  RAA229126GNPHA0  I48

PVCCIN_CPU0_PWM2   @S9S_MB_2U_LIB.S9S_MB_2U(SCH_1):PVCCIN_CPU0_PWM2
  PU12_P0_2   34    PWM  ISL99390FRZTR5935  I87
  PU14    11  PWM10  RAA229126GNPHA0  I48

PVCCIN_CPU0_PWM3   @S9S_MB_2U_LIB.S9S_MB_2U(SCH_1):PVCCIN_CPU0_PWM3
  PU11_P0_3   34    PWM  ISL99390FRZTR5935  I30
  PU14    10   PWM9  RAA229126GNPHA0  I48

PVCCIN_CPU0_PWM4   @S9S_MB_2U_LIB.S9S_MB_2U(SCH_1):PVCCIN_CPU0_PWM4
  PU10_P0_4   34    PWM  ISL99390FRZTR5935  I14
  PU14     9   PWM8  RAA229126GNPHA0  I48

PVCCIN_CPU0_PWM5   @S9S_MB_2U_LIB.S9S_MB_2U(SCH_1):PVCCIN_CPU0_PWM5
  PU14     8   PWM7  RAA229126GNPHA0  I48
  PU9_P0_5   34    PWM  ISL99390FRZTR5935  I31

PVCCIN_CPU0_PWM6   @S9S_MB_2U_LIB.S9S_MB_2U(SCH_1):PVCCIN_CPU0_PWM6
  PU14     7   PWM6  RAA229126GNPHA0  I48
  PU8_P0_6   34    PWM  ISL99390FRZTR5935  I62

PVCCIN_CPU0_PWM7   @S9S_MB_2U_LIB.S9S_MB_2U(SCH_1):PVCCIN_CPU0_PWM7
  PU14     6   PWM5  RAA229126GNPHA0  I48
  PU7_P0_7   34    PWM  ISL99390FRZTR5935  I20

PVCCIN_CPU0_PWM8   @S9S_MB_2U_LIB.S9S_MB_2U(SCH_1):PVCCIN_CPU0_PWM8
  PU14     5   PWM4  RAA229126GNPHA0  I48
  PU6_P0_8   34    PWM  ISL99390FRZTR5935  I64

PVCCIN_CPU0_VCC   @S9S_MB_2U_LIB.S9S_MB_2U(SCH_1):PVCCIN_CPU0_VCC
  PC334    1      A  Q_CAP       I75
  PC337    1      A  Q_CAP       I119
  PR176    1      A  Q_RES       I121
  PU14    47    VCC  RAA229126GNPHA0  I48

PVCCIN_CPU0_VDD1   @S9S_MB_2U_LIB.S9S_MB_2U(SCH_1):PVCCIN_CPU0_VDD1
  PC293    1      A  Q_CAP       I30
  PR153    2      B  Q_RES       I32
  PU13_P0_1    3    VCC  ISL99390FRZTR5935  I21
  PU13_P0_1   35     EN  ISL99390FRZTR5935  I21

PVCCIN_CPU0_VDD2   @S9S_MB_2U_LIB.S9S_MB_2U(SCH_1):PVCCIN_CPU0_VDD2
  PC292    1      A  Q_CAP        I8
  PR152    2      B  Q_RES       I11
  PU12_P0_2    3    VCC  ISL99390FRZTR5935  I87
  PU12_P0_2   35     EN  ISL99390FRZTR5935  I87

PVCCIN_CPU0_VDD3   @S9S_MB_2U_LIB.S9S_MB_2U(SCH_1):PVCCIN_CPU0_VDD3
  PC271    1      A  Q_CAP       I26
  PR147    2      B  Q_RES       I27
  PU11_P0_3    3    VCC  ISL99390FRZTR5935  I30
  PU11_P0_3   35     EN  ISL99390FRZTR5935  I30

PVCCIN_CPU0_VDD4   @S9S_MB_2U_LIB.S9S_MB_2U(SCH_1):PVCCIN_CPU0_VDD4
  PC270    1      A  Q_CAP        I8
  PR146    2      B  Q_RES       I10
  PU10_P0_4    3    VCC  ISL99390FRZTR5935  I14
  PU10_P0_4   35     EN  ISL99390FRZTR5935  I14

PVCCIN_CPU0_VDD5   @S9S_MB_2U_LIB.S9S_MB_2U(SCH_1):PVCCIN_CPU0_VDD5
  PC249    1      A  Q_CAP       I30
  PR141    2      B  Q_RES       I32
  PU9_P0_5    3    VCC  ISL99390FRZTR5935  I31
  PU9_P0_5   35     EN  ISL99390FRZTR5935  I31

PVCCIN_CPU0_VDD6   @S9S_MB_2U_LIB.S9S_MB_2U(SCH_1):PVCCIN_CPU0_VDD6
  PC248    1      A  Q_CAP       I10
  PR140    2      B  Q_RES       I11
  PU8_P0_6    3    VCC  ISL99390FRZTR5935  I62
  PU8_P0_6   35     EN  ISL99390FRZTR5935  I62

PVCCIN_CPU0_VDD7   @S9S_MB_2U_LIB.S9S_MB_2U(SCH_1):PVCCIN_CPU0_VDD7
  PC227    1      A  Q_CAP       I25
  PR135    2      B  Q_RES       I26
  PU7_P0_7    3    VCC  ISL99390FRZTR5935  I20
  PU7_P0_7   35     EN  ISL99390FRZTR5935  I20

PVCCIN_CPU0_VDD8   @S9S_MB_2U_LIB.S9S_MB_2U(SCH_1):PVCCIN_CPU0_VDD8
  PC226    1      A  Q_CAP        I9
  PR134    2      B  Q_RES       I10
  PU6_P0_8    3    VCC  ISL99390FRZTR5935  I64
  PU6_P0_8   35     EN  ISL99390FRZTR5935  I64

PVCCIN_CPU0_VIN_CSNIN   @S9S_MB_2U_LIB.S9S_MB_2U(SCH_1):PVCCIN_CPU0_VIN_CSNIN
  PC330    1      A  Q_CAP       I45
  PR156    2      B  Q_RES        I6
  PR166    1      A  Q_RES       I44
  PU14    46  VINSEN||VSYS  RAA229126GNPHA0  I48

PVCCIN_CPU0_VOS1   @S9S_MB_2U_LIB.S9S_MB_2U(SCH_1):PVCCIN_CPU0_VOS1
  PR155    1      A  Q_RES       I112
  PU13_P0_1    1    VOS  ISL99390FRZTR5935  I21

PVCCIN_CPU0_VOS2   @S9S_MB_2U_LIB.S9S_MB_2U(SCH_1):PVCCIN_CPU0_VOS2
  PR154    1      A  Q_RES       I124
  PU12_P0_2    1    VOS  ISL99390FRZTR5935  I87

PVCCIN_CPU0_VOS3   @S9S_MB_2U_LIB.S9S_MB_2U(SCH_1):PVCCIN_CPU0_VOS3
  PR149    1      A  Q_RES       I76
  PU11_P0_3    1    VOS  ISL99390FRZTR5935  I30

PVCCIN_CPU0_VOS4   @S9S_MB_2U_LIB.S9S_MB_2U(SCH_1):PVCCIN_CPU0_VOS4
  PR148    1      A  Q_RES       I92
  PU10_P0_4    1    VOS  ISL99390FRZTR5935  I14

PVCCIN_CPU0_VOS5   @S9S_MB_2U_LIB.S9S_MB_2U(SCH_1):PVCCIN_CPU0_VOS5
  PR143    1      A  Q_RES       I76
  PU9_P0_5    1    VOS  ISL99390FRZTR5935  I31

PVCCIN_CPU0_VOS6   @S9S_MB_2U_LIB.S9S_MB_2U(SCH_1):PVCCIN_CPU0_VOS6
  PR142    1      A  Q_RES       I92
  PU8_P0_6    1    VOS  ISL99390FRZTR5935  I62

PVCCIN_CPU0_VOS7   @S9S_MB_2U_LIB.S9S_MB_2U(SCH_1):PVCCIN_CPU0_VOS7
  PR137    1      A  Q_RES       I84
  PU7_P0_7    1    VOS  ISL99390FRZTR5935  I20

PVCCIN_CPU0_VOS8   @S9S_MB_2U_LIB.S9S_MB_2U(SCH_1):PVCCIN_CPU0_VOS8
  PR136    1      A  Q_RES       I99
  PU6_P0_8    1    VOS  ISL99390FRZTR5935  I64

PVCCIN_CPU0_VREF   @S9S_MB_2U_LIB.S9S_MB_2U(SCH_1):PVCCIN_CPU0_VREF
  PC335    1      A  Q_CAP       I74
  PC1173    1      A  Q_CAP       I117
  PC1340    2      B  Q_CAP       I13
  PC1341    2      B  Q_CAP       I29
  PC1342    2      B  Q_CAP        I8
  PC1343    2      B  Q_CAP       I27
  PC1344    2      B  Q_CAP       I16
  PC1345    2      B  Q_CAP       I28
  PC1349    2      B  Q_CAP       I46
  PC1350    2      B  Q_CAP       I29
  PC1351    2      B  Q_CAP       I39
  PC1352    2      B  Q_CAP       I23
  PC1355    2      B  Q_CAP       I10
  PC1356    2      B  Q_CAP       I33
  PR159    1      A  Q_RES        I7
  PU10_P0_4   39  REFIN  ISL99390FRZTR5935  I14
  PU11_P0_3   39  REFIN  ISL99390FRZTR5935  I30
  PU12_P0_2   39  REFIN  ISL99390FRZTR5935  I87
  PU13_P0_1   39  REFIN  ISL99390FRZTR5935  I21
  PU14    48   VCCS  RAA229126GNPHA0  I48
  PU69_P0_1   39  REFIN  ISL99390FRZTR5935  I35
  PU6_P0_8   39  REFIN  ISL99390FRZTR5935  I64
  PU70_P0_2   39  REFIN  ISL99390FRZTR5935  I30
  PU71_P0_3   39  REFIN  ISL99390FRZTR5935  I40
  PU72_P0_4   39  REFIN  ISL99390FRZTR5935  I24
  PU7_P0_7   39  REFIN  ISL99390FRZTR5935  I20
  PU8_P0_6   39  REFIN  ISL99390FRZTR5935  I62
  PU9_P0_5   39  REFIN  ISL99390FRZTR5935  I31

PVCCIN_CPU0_VR_FAULT   @S9S_MB_2U_LIB.S9S_MB_2U(SCH_1):PVCCIN_CPU0_VR_FAULT
  PR172    2      B  Q_RES       I53
  PU14    41    CFP  RAA229126GNPHA0  I48

PVCCIN_CPU1     @S9S_MB_2U_LIB.S9S_MB_2U(SCH_1):PVCCIN_CPU1
  C221     1      A  Q_CAP       I27
  C222     1      A  Q_CAP       I25
  C223     1      A  Q_CAP       I23
  C224     1      A  Q_CAP       I15
  C225     1      A  Q_CAP       I13
  C226     1      A  Q_CAP       I31
  C227     1      A  Q_CAP       I30
  C228     1      A  Q_CAP       I28
  C229     1      A  Q_CAP       I21
  C230     1      A  Q_CAP       I18
  C231     1      A  Q_CAP       I33
  C232     1      A  Q_CAP       I32
  C233     1      A  Q_CAP       I29
  C234     1      A  Q_CAP       I22
  C235     1      A  Q_CAP       I20
  C236     1      A  Q_CAP       I52
  C237     1      A  Q_CAP       I51
  C238     1      A  Q_CAP       I49
  C239     1      A  Q_CAP       I37
  C240     1      A  Q_CAP       I35
  C241     1      A  Q_CAP       I54
  C242     1      A  Q_CAP       I53
  C243     1      A  Q_CAP       I50
  C244     1      A  Q_CAP       I38
  C245     1      A  Q_CAP       I36
  C246     1      A  Q_CAP       I59
  C247     1      A  Q_CAP       I58
  C248     1      A  Q_CAP       I55
  C249     1      A  Q_CAP       I46
  C250     1      A  Q_CAP       I41
  C251     1      A  Q_CAP       I61
  C252     1      A  Q_CAP       I60
  C253     1      A  Q_CAP       I56
  C254     1      A  Q_CAP       I47
  C255     1      A  Q_CAP       I44
  C256     1      A  Q_CAP       I63
  C257     1      A  Q_CAP       I62
  C258     1      A  Q_CAP       I57
  C259     1      A  Q_CAP       I48
  C260     1      A  Q_CAP       I45
  C261     1      A  Q_CAP       I89
  C262     1      A  Q_CAP       I88
  C263     1      A  Q_CAP       I84
  C264     1      A  Q_CAP       I76
  C265     1      A  Q_CAP       I72
  C266     1      A  Q_CAP       I92
  C267     1      A  Q_CAP       I90
  C268     1      A  Q_CAP       I86
  C269     1      A  Q_CAP       I78
  C270     1      A  Q_CAP       I75
  C271     1      A  Q_CAP       I98
  C272     1      A  Q_CAP       I96
  C273     1      A  Q_CAP       I93
  C274     1      A  Q_CAP       I81
  C275     1      A  Q_CAP       I100
  C276     1      A  Q_CAP       I99
  C277     1      A  Q_CAP       I95
  C278     1      A  Q_CAP       I83
  C279     1      A  Q_CAP       I112
  C280     1      A  Q_CAP       I111
  C281     1      A  Q_CAP       I109
  C282     1      A  Q_CAP       I103
  C283     1      A  Q_CAP       I114
  C284     1      A  Q_CAP       I113
  C285     1      A  Q_CAP       I110
  C286     1      A  Q_CAP       I104
  C287     1      A  Q_CAP       I120
  C288     1      A  Q_CAP       I118
  C289     1      A  Q_CAP       I115
  C290     1      A  Q_CAP       I106
  C291     1      A  Q_CAP       I121
  C292     1      A  Q_CAP       I119
  C293     1      A  Q_CAP       I116
  C294     1      A  Q_CAP       I107
  C295     1      A  Q_CAP       I123
  C296     1      A  Q_CAP       I122
  C297     1      A  Q_CAP       I117
  C298     1      A  Q_CAP       I108
  C299     1      A  Q_CAP       I132
  C300     1      A  Q_CAP       I131
  C301     1      A  Q_CAP       I129
  C302     1      A  Q_CAP       I125
  C303     1      A  Q_CAP       I134
  C304     1      A  Q_CAP       I133
  C305     1      A  Q_CAP       I130
  C306     1      A  Q_CAP       I126
  C307     1      A  Q_CAP       I140
  C308     1      A  Q_CAP       I138
  C309     1      A  Q_CAP       I136
  C311     1      A  Q_CAP       I35
  C312     1      A  Q_CAP       I32
  C313     1      A  Q_CAP       I128
  C314     1      A  Q_CAP       I40
  C315     1      A  Q_CAP       I37
  C316     1      A  Q_CAP       I129
  C317     1      A  Q_CAP       I41
  C318     1      A  Q_CAP       I39
  C320     1      A  Q_CAP       I59
  C321     1      A  Q_CAP       I56
  C322     1      A  Q_CAP       I115
  C323     1      A  Q_CAP       I60
  C324     1      A  Q_CAP       I58
  C325     1      A  Q_CAP       I114
  C326     1      A  Q_CAP       I67
  C327     1      A  Q_CAP       I62
  C328     1      A  Q_CAP       I112
  C329     1      A  Q_CAP       I68
  C330     1      A  Q_CAP       I65
  C332     1      A  Q_CAP       I69
  C333     1      A  Q_CAP       I66
  C335     1      A  Q_CAP       I80
  C336     1      A  Q_CAP       I76
  C337     1      A  Q_CAP       I121
  C338     1      A  Q_CAP       I82
  C339     1      A  Q_CAP       I79
  C340     1      A  Q_CAP       I120
  C341     1      A  Q_CAP       I125
  C342     1      A  Q_CAP       I109
  C343     1      A  Q_CAP       I124
  C344     1      A  Q_CAP       I110
  C345     1      A  Q_CAP       I123
  C346     1      A  Q_CAP       I111
  C347     1      A  Q_CAP       I122
  C348     1      A  Q_CAP       I119
  C349     1      A  Q_CAP       I124
  C350     1      A  Q_CAP       I118
  C351     1      A  Q_CAP       I126
  C352     1      A  Q_CAP       I117
  C353     1      A  Q_CAP       I125
  C354     1      A  Q_CAP       I116
  C480     1      A  Q_CAP       I119
  C483     1      A  Q_CAP       I118
  PC189    1      A  Q_CAPP      I54
  PC1990    1      A  Q_CAPP      I53
  PC495_P1_8    1      A  Q_CAP       I103
  PC496_P1_7    1      A  Q_CAP       I84
  PC497_P1_8    1      A  Q_CAP       I102
  PC498_P1_7    1      A  Q_CAP       I83
  PC499_P1_8    1      A  Q_CAP       I101
  PC500_P1_7    1      A  Q_CAP       I81
  PC519_P1_6    1      A  Q_CAP       I95
  PC520_P1_5    1      A  Q_CAP       I79
  PC521_P1_6    1      A  Q_CAP       I94
  PC522_P1_5    1      A  Q_CAP       I78
  PC541_P1_4    1      A  Q_CAP       I96
  PC542_P1_3    1      A  Q_CAP       I79
  PC543_P1_4    1      A  Q_CAP       I94
  PC544_P1_3    1      A  Q_CAP       I77
  PC572_P1_1    1      A  Q_CAP       I64
  PC574_P1_1    1      A  Q_CAP       I65
  PC575_P1_2    1      A  Q_CAP       I100
  PC576_P1_1    1      A  Q_CAP       I68
  PC577_P1_2    1      A  Q_CAP       I99
  PC578_P1_1    1      A  Q_CAP       I69
  PC83     1      A  Q_CAPP      I105
  PC580    1      A  Q_CAPP      I55
  PC583    1      A  Q_CAPP      I56
  PC586    1      A  Q_CAPP      I79
  PC587    1      A  Q_CAPP      I75
  PC589    1      A  Q_CAPP      I81
  PC590    1      A  Q_CAPP      I77
  PL24     4      4  Q_INDUCTOR4P_14  I95
  PL25     4      4  Q_INDUCTOR4P_14  I76
  PL26     4      4  Q_INDUCTOR4P_14  I90
  PL27     4      4  Q_INDUCTOR4P_14  I73
  PL28     4      4  Q_INDUCTOR4P_14  I90
  PL29     4      4  Q_INDUCTOR4P_14  I74
  PL30     4      4  Q_INDUCTOR4P_14  I103
  PL31     4      4  Q_INDUCTOR4P_14  I89
  PR289    2      B  Q_RES       I98
  PR290    2      B  Q_RES       I79
  PR295    2      B  Q_RES       I96
  PR296    2      B  Q_RES       I80
  PR301    2      B  Q_RES       I92
  PR302    2      B  Q_RES       I80
  PR329    2      B  Q_RES       I102
  PR330    2      B  Q_RES       I90
  PR578    2      B  Q_RES       I188
  U1     BD91  VCCIN0  SOCKET4677_AZIFS054P001C01   I1
  U1     BE86  VCCIN1  SOCKET4677_AZIFS054P001C01   I1
  U1     BE88  VCCIN2  SOCKET4677_AZIFS054P001C01   I1
  U1     BE90  VCCIN3  SOCKET4677_AZIFS054P001C01   I1
  U1     BF85  VCCIN4  SOCKET4677_AZIFS054P001C01   I1
  U1     BF87  VCCIN5  SOCKET4677_AZIFS054P001C01   I1
  U1     BF89  VCCIN6  SOCKET4677_AZIFS054P001C01   I1
  U1     BF91  VCCIN7  SOCKET4677_AZIFS054P001C01   I1
  U1     BG84  VCCIN8  SOCKET4677_AZIFS054P001C01   I1
  U1     BG86  VCCIN9  SOCKET4677_AZIFS054P001C01   I1
  U1     BG88  VCCIN10  SOCKET4677_AZIFS054P001C01   I1
  U1     BG90  VCCIN11  SOCKET4677_AZIFS054P001C01   I1
  U1     BH85  VCCIN12  SOCKET4677_AZIFS054P001C01   I1
  U1     BH87  VCCIN13  SOCKET4677_AZIFS054P001C01   I1
  U1     BH89  VCCIN14  SOCKET4677_AZIFS054P001C01   I1
  U1     BH91  VCCIN15  SOCKET4677_AZIFS054P001C01   I1
  U1     BK81  VCCIN16  SOCKET4677_AZIFS054P001C01   I1
  U1     BK83  VCCIN17  SOCKET4677_AZIFS054P001C01   I1
  U1     BK85  VCCIN18  SOCKET4677_AZIFS054P001C01   I1
  U1     BK87  VCCIN19  SOCKET4677_AZIFS054P001C01   I1
  U1     BK89  VCCIN20  SOCKET4677_AZIFS054P001C01   I1
  U1     BK91  VCCIN21  SOCKET4677_AZIFS054P001C01   I1
  U1     BL80  VCCIN22  SOCKET4677_AZIFS054P001C01   I1
  U1     BL82  VCCIN23  SOCKET4677_AZIFS054P001C01   I1
  U1     BL84  VCCIN24  SOCKET4677_AZIFS054P001C01   I1
  U1     BL86  VCCIN25  SOCKET4677_AZIFS054P001C01   I1
  U1     BL88  VCCIN26  SOCKET4677_AZIFS054P001C01   I1
  U1     BL90  VCCIN27  SOCKET4677_AZIFS054P001C01   I1
  U1     BM79  VCCIN28  SOCKET4677_AZIFS054P001C01   I1
  U1     BM81  VCCIN29  SOCKET4677_AZIFS054P001C01   I1
  U1     BM83  VCCIN30  SOCKET4677_AZIFS054P001C01   I1
  U1     BM85  VCCIN31  SOCKET4677_AZIFS054P001C01   I1
  U1     BM87  VCCIN32  SOCKET4677_AZIFS054P001C01   I1
  U1     BM89  VCCIN33  SOCKET4677_AZIFS054P001C01   I1
  U1     BM91  VCCIN34  SOCKET4677_AZIFS054P001C01   I1
  U1     BN33  VCCIN35  SOCKET4677_AZIFS054P001C01   I1
  U1     BN35  VCCIN36  SOCKET4677_AZIFS054P001C01   I1
  U1     BN37  VCCIN37  SOCKET4677_AZIFS054P001C01   I1
  U1     BN39  VCCIN38  SOCKET4677_AZIFS054P001C01   I1
  U1     BN41  VCCIN39  SOCKET4677_AZIFS054P001C01   I1
  U1     BN43  VCCIN40  SOCKET4677_AZIFS054P001C01   I3
  U1     BN45  VCCIN41  SOCKET4677_AZIFS054P001C01   I3
  U1     BN48  VCCIN42  SOCKET4677_AZIFS054P001C01   I3
  U1     BN50  VCCIN43  SOCKET4677_AZIFS054P001C01   I3
  U1     BN52  VCCIN44  SOCKET4677_AZIFS054P001C01   I3
  U1     BN54  VCCIN45  SOCKET4677_AZIFS054P001C01   I3
  U1     BN56  VCCIN46  SOCKET4677_AZIFS054P001C01   I3
  U1     BN58  VCCIN47  SOCKET4677_AZIFS054P001C01   I3
  U1     BN60  VCCIN48  SOCKET4677_AZIFS054P001C01   I3
  U1     BN78  VCCIN49  SOCKET4677_AZIFS054P001C01   I3
  U1     BN80  VCCIN50  SOCKET4677_AZIFS054P001C01   I3
  U1     BN82  VCCIN51  SOCKET4677_AZIFS054P001C01   I3
  U1     BN84  VCCIN52  SOCKET4677_AZIFS054P001C01   I3
  U1     BN86  VCCIN53  SOCKET4677_AZIFS054P001C01   I3
  U1     BN88  VCCIN54  SOCKET4677_AZIFS054P001C01   I3
  U1     BN90  VCCIN55  SOCKET4677_AZIFS054P001C01   I3
  U1     BP32  VCCIN56  SOCKET4677_AZIFS054P001C01   I3
  U1     BP34  VCCIN57  SOCKET4677_AZIFS054P001C01   I3
  U1     BP36  VCCIN58  SOCKET4677_AZIFS054P001C01   I3
  U1     BP38  VCCIN59  SOCKET4677_AZIFS054P001C01   I3
  U1     BP40  VCCIN60  SOCKET4677_AZIFS054P001C01   I3
  U1     BP42  VCCIN61  SOCKET4677_AZIFS054P001C01   I3
  U1     BP44  VCCIN62  SOCKET4677_AZIFS054P001C01   I3
  U1     BP47  VCCIN63  SOCKET4677_AZIFS054P001C01   I3
  U1     BP49  VCCIN64  SOCKET4677_AZIFS054P001C01   I3
  U1     BP51  VCCIN65  SOCKET4677_AZIFS054P001C01   I3
  U1     BP53  VCCIN66  SOCKET4677_AZIFS054P001C01   I3
  U1     BP55  VCCIN67  SOCKET4677_AZIFS054P001C01   I3
  U1     BP57  VCCIN68  SOCKET4677_AZIFS054P001C01   I3
  U1     BP59  VCCIN69  SOCKET4677_AZIFS054P001C01   I3
  U1     BP61  VCCIN70  SOCKET4677_AZIFS054P001C01   I3
  U1     BP79  VCCIN71  SOCKET4677_AZIFS054P001C01   I3
  U1     BP81  VCCIN72  SOCKET4677_AZIFS054P001C01   I3
  U1     BP83  VCCIN73  SOCKET4677_AZIFS054P001C01   I3
  U1     BP85  VCCIN74  SOCKET4677_AZIFS054P001C01   I3
  U1     BP87  VCCIN75  SOCKET4677_AZIFS054P001C01   I3
  U1     BP89  VCCIN76  SOCKET4677_AZIFS054P001C01   I3
  U1     BR60  VCCIN77  SOCKET4677_AZIFS054P001C01   I3
  U1     BR62  VCCIN78  SOCKET4677_AZIFS054P001C01   I3
  U1     BR78  VCCIN79  SOCKET4677_AZIFS054P001C01   I3
  U1     BT32  VCCIN80  SOCKET4677_AZIFS054P001C01   I3
  U1     BT34  VCCIN81  SOCKET4677_AZIFS054P001C01   I3
  U1     BT36  VCCIN82  SOCKET4677_AZIFS054P001C01   I3
  U1     BT38  VCCIN83  SOCKET4677_AZIFS054P001C01   I3
  U1     BT40  VCCIN84  SOCKET4677_AZIFS054P001C01   I3
  U1     BT42  VCCIN85  SOCKET4677_AZIFS054P001C01   I3
  U1     BT44  VCCIN86  SOCKET4677_AZIFS054P001C01   I3
  U1     BT47  VCCIN87  SOCKET4677_AZIFS054P001C01   I3
  U1     BT49  VCCIN88  SOCKET4677_AZIFS054P001C01   I3
  U1     BT51  VCCIN89  SOCKET4677_AZIFS054P001C01   I3
  U1     BT53  VCCIN90  SOCKET4677_AZIFS054P001C01   I3
  U1     BT55  VCCIN91  SOCKET4677_AZIFS054P001C01   I3
  U1     BT57  VCCIN92  SOCKET4677_AZIFS054P001C01   I3
  U1     BT59  VCCIN93  SOCKET4677_AZIFS054P001C01   I3
  U1     BT61  VCCIN94  SOCKET4677_AZIFS054P001C01   I3
  U1     BT63  VCCIN95  SOCKET4677_AZIFS054P001C01   I3
  U1     BT65  VCCIN96  SOCKET4677_AZIFS054P001C01   I3
  U1     BT67  VCCIN97  SOCKET4677_AZIFS054P001C01   I3
  U1     BT69  VCCIN98  SOCKET4677_AZIFS054P001C01   I3
  U1     BT71  VCCIN99  SOCKET4677_AZIFS054P001C01   I3
  U1     BT73  VCCIN100  SOCKET4677_AZIFS054P001C01   I3
  U1     BT75  VCCIN101  SOCKET4677_AZIFS054P001C01   I3
  U1     BT77  VCCIN102  SOCKET4677_AZIFS054P001C01   I3
  U1     BT79  VCCIN103  SOCKET4677_AZIFS054P001C01   I3
  U1     BT81  VCCIN104  SOCKET4677_AZIFS054P001C01   I3
  U1     BT83  VCCIN105  SOCKET4677_AZIFS054P001C01   I3
  U1     BT85  VCCIN106  SOCKET4677_AZIFS054P001C01   I3
  U1     BT87  VCCIN107  SOCKET4677_AZIFS054P001C01   I3
  U1     BT89  VCCIN108  SOCKET4677_AZIFS054P001C01   I3
  U1     BU33  VCCIN109  SOCKET4677_AZIFS054P001C01   I3
  U1     BU35  VCCIN110  SOCKET4677_AZIFS054P001C01   I3
  U1     BU37  VCCIN111  SOCKET4677_AZIFS054P001C01   I3
  U1     BU39  VCCIN112  SOCKET4677_AZIFS054P001C01   I3
  U1     BU41  VCCIN113  SOCKET4677_AZIFS054P001C01   I3
  U1     BU43  VCCIN114  SOCKET4677_AZIFS054P001C01   I3
  U1     BU45  VCCIN115  SOCKET4677_AZIFS054P001C01   I3
  U1     BU48  VCCIN116  SOCKET4677_AZIFS054P001C01   I3
  U1     BU50  VCCIN117  SOCKET4677_AZIFS054P001C01   I3
  U1     BU52  VCCIN118  SOCKET4677_AZIFS054P001C01   I3
  U1     BU54  VCCIN119  SOCKET4677_AZIFS054P001C01   I3
  U1     BU56  VCCIN120  SOCKET4677_AZIFS054P001C01   I3
  U1     BU58  VCCIN121  SOCKET4677_AZIFS054P001C01   I3
  U1     BU60  VCCIN122  SOCKET4677_AZIFS054P001C01   I3
  U1     BU62  VCCIN123  SOCKET4677_AZIFS054P001C01   I3
  U1     BU64  VCCIN124  SOCKET4677_AZIFS054P001C01   I3
  U1     BU66  VCCIN125  SOCKET4677_AZIFS054P001C01   I3
  U1     BU68  VCCIN126  SOCKET4677_AZIFS054P001C01   I3
  U1     BU70  VCCIN127  SOCKET4677_AZIFS054P001C01   I3
  U1     BU72  VCCIN128  SOCKET4677_AZIFS054P001C01   I3
  U1     BU74  VCCIN129  SOCKET4677_AZIFS054P001C01   I3
  U1     BU76  VCCIN130  SOCKET4677_AZIFS054P001C01   I3
  U1     BU78  VCCIN131  SOCKET4677_AZIFS054P001C01   I3
  U1     BU80  VCCIN132  SOCKET4677_AZIFS054P001C01   I3
  U1     BU82  VCCIN133  SOCKET4677_AZIFS054P001C01   I3
  U1     BU84  VCCIN134  SOCKET4677_AZIFS054P001C01   I3
  U1     BU86  VCCIN135  SOCKET4677_AZIFS054P001C01   I3
  U1     BU88  VCCIN136  SOCKET4677_AZIFS054P001C01   I3
  U1     BU90  VCCIN137  SOCKET4677_AZIFS054P001C01   I3
  U1     BV32  VCCIN138  SOCKET4677_AZIFS054P001C01   I3
  U1     BV34  VCCIN139  SOCKET4677_AZIFS054P001C01   I3
  U1     BV36  VCCIN140  SOCKET4677_AZIFS054P001C01   I3
  U1     BV38  VCCIN141  SOCKET4677_AZIFS054P001C01   I3
  U1     BV40  VCCIN142  SOCKET4677_AZIFS054P001C01   I3
  U1     BV42  VCCIN143  SOCKET4677_AZIFS054P001C01   I3
  U1     BV44  VCCIN144  SOCKET4677_AZIFS054P001C01   I3
  U1     BV47  VCCIN145  SOCKET4677_AZIFS054P001C01   I3
  U1     BV49  VCCIN146  SOCKET4677_AZIFS054P001C01   I3
  U1     BV51  VCCIN147  SOCKET4677_AZIFS054P001C01   I3
  U1     BV53  VCCIN148  SOCKET4677_AZIFS054P001C01   I3
  U1     BV55  VCCIN149  SOCKET4677_AZIFS054P001C01   I3
  U1     BV57  VCCIN150  SOCKET4677_AZIFS054P001C01   I3
  U1     BV59  VCCIN151  SOCKET4677_AZIFS054P001C01   I3
  U1     BV61  VCCIN152  SOCKET4677_AZIFS054P001C01   I3
  U1     BV63  VCCIN153  SOCKET4677_AZIFS054P001C01   I3
  U1     BV65  VCCIN154  SOCKET4677_AZIFS054P001C01   I3
  U1     BV67  VCCIN155  SOCKET4677_AZIFS054P001C01   I3
  U1     BV69  VCCIN156  SOCKET4677_AZIFS054P001C01   I3
  U1     BV71  VCCIN157  SOCKET4677_AZIFS054P001C01   I3
  U1     BV73  VCCIN158  SOCKET4677_AZIFS054P001C01   I3
  U1     BV75  VCCIN159  SOCKET4677_AZIFS054P001C01   I3
  U1     BV77  VCCIN160  SOCKET4677_AZIFS054P001C01   I3
  U1     BV79  VCCIN161  SOCKET4677_AZIFS054P001C01   I3
  U1     BV81  VCCIN162  SOCKET4677_AZIFS054P001C01   I3
  U1     BV83  VCCIN163  SOCKET4677_AZIFS054P001C01   I3
  U1     BV85  VCCIN164  SOCKET4677_AZIFS054P001C01   I3
  U1     BV87  VCCIN165  SOCKET4677_AZIFS054P001C01   I3
  U1     BV89  VCCIN166  SOCKET4677_AZIFS054P001C01   I3
  U1     BW33  VCCIN167  SOCKET4677_AZIFS054P001C01   I3
  U1     BW35  VCCIN168  SOCKET4677_AZIFS054P001C01   I3
  U1     BW37  VCCIN169  SOCKET4677_AZIFS054P001C01   I3
  U1     BW39  VCCIN170  SOCKET4677_AZIFS054P001C01   I3
  U1     BW41  VCCIN171  SOCKET4677_AZIFS054P001C01   I3
  U1     BW43  VCCIN172  SOCKET4677_AZIFS054P001C01   I3
  U1     BW45  VCCIN173  SOCKET4677_AZIFS054P001C01   I3
  U1     BW48  VCCIN174  SOCKET4677_AZIFS054P001C01   I3
  U1     BW50  VCCIN175  SOCKET4677_AZIFS054P001C01   I3
  U1     BW52  VCCIN176  SOCKET4677_AZIFS054P001C01   I3
  U1     BW54  VCCIN177  SOCKET4677_AZIFS054P001C01   I3
  U1     BW56  VCCIN178  SOCKET4677_AZIFS054P001C01   I3
  U1     BW58  VCCIN179  SOCKET4677_AZIFS054P001C01   I3
  U1     BW60  VCCIN180  SOCKET4677_AZIFS054P001C01   I3
  U1     BW62  VCCIN181  SOCKET4677_AZIFS054P001C01   I3
  U1     BW64  VCCIN182  SOCKET4677_AZIFS054P001C01   I3
  U1     BW66  VCCIN183  SOCKET4677_AZIFS054P001C01   I3
  U1     BW68  VCCIN184  SOCKET4677_AZIFS054P001C01   I3
  U1     BW70  VCCIN185  SOCKET4677_AZIFS054P001C01   I3
  U1     BW72  VCCIN186  SOCKET4677_AZIFS054P001C01   I3
  U1     BW74  VCCIN187  SOCKET4677_AZIFS054P001C01   I3
  U1     BW76  VCCIN188  SOCKET4677_AZIFS054P001C01   I3
  U1     BW78  VCCIN189  SOCKET4677_AZIFS054P001C01   I3
  U1     BW80  VCCIN190  SOCKET4677_AZIFS054P001C01   I1
  U1     BW82  VCCIN191  SOCKET4677_AZIFS054P001C01   I1
  U1     BW84  VCCIN192  SOCKET4677_AZIFS054P001C01   I1
  U1     BW86  VCCIN193  SOCKET4677_AZIFS054P001C01   I1
  U1     BW88  VCCIN194  SOCKET4677_AZIFS054P001C01   I1
  U1     BW90  VCCIN195  SOCKET4677_AZIFS054P001C01   I1
  U1     BY32  VCCIN196  SOCKET4677_AZIFS054P001C01   I1
  U1     BY34  VCCIN197  SOCKET4677_AZIFS054P001C01   I1
  U1     BY36  VCCIN198  SOCKET4677_AZIFS054P001C01   I1
  U1     BY38  VCCIN199  SOCKET4677_AZIFS054P001C01   I1
  U1     BY40  VCCIN200  SOCKET4677_AZIFS054P001C01   I1
  U1     BY42  VCCIN201  SOCKET4677_AZIFS054P001C01   I1
  U1     BY44  VCCIN202  SOCKET4677_AZIFS054P001C01   I1
  U1     BY47  VCCIN203  SOCKET4677_AZIFS054P001C01   I1
  U1     BY49  VCCIN204  SOCKET4677_AZIFS054P001C01   I1
  U1     BY51  VCCIN205  SOCKET4677_AZIFS054P001C01   I1
  U1     BY53  VCCIN206  SOCKET4677_AZIFS054P001C01   I1
  U1     BY55  VCCIN207  SOCKET4677_AZIFS054P001C01   I1
  U1     BY57  VCCIN208  SOCKET4677_AZIFS054P001C01   I1
  U1     BY59  VCCIN209  SOCKET4677_AZIFS054P001C01   I1
  U1     BY61  VCCIN210  SOCKET4677_AZIFS054P001C01   I1
  U1     BY63  VCCIN211  SOCKET4677_AZIFS054P001C01   I1
  U1     BY65  VCCIN212  SOCKET4677_AZIFS054P001C01   I1
  U1     BY67  VCCIN213  SOCKET4677_AZIFS054P001C01   I1
  U1     BY69  VCCIN214  SOCKET4677_AZIFS054P001C01   I1
  U1     BY71  VCCIN215  SOCKET4677_AZIFS054P001C01   I1
  U1     BY73  VCCIN216  SOCKET4677_AZIFS054P001C01   I1
  U1     BY75  VCCIN217  SOCKET4677_AZIFS054P001C01   I1
  U1     BY77  VCCIN218  SOCKET4677_AZIFS054P001C01   I1
  U1     BY79  VCCIN219  SOCKET4677_AZIFS054P001C01   I1
  U1     BY81  VCCIN220  SOCKET4677_AZIFS054P001C01   I1
  U1     BY83  VCCIN221  SOCKET4677_AZIFS054P001C01   I1
  U1     BY85  VCCIN222  SOCKET4677_AZIFS054P001C01   I1
  U1     BY87  VCCIN223  SOCKET4677_AZIFS054P001C01   I1
  U1     BY89  VCCIN224  SOCKET4677_AZIFS054P001C01   I1
  U1     CA33  VCCIN225  SOCKET4677_AZIFS054P001C01   I1
  U1     CA35  VCCIN226  SOCKET4677_AZIFS054P001C01   I1
  U1     CA37  VCCIN227  SOCKET4677_AZIFS054P001C01   I1
  U1     CA39  VCCIN228  SOCKET4677_AZIFS054P001C01   I1
  U1     CA41  VCCIN229  SOCKET4677_AZIFS054P001C01   I1
  U1     CA43  VCCIN230  SOCKET4677_AZIFS054P001C01   I1
  U1     CA45  VCCIN231  SOCKET4677_AZIFS054P001C01   I1
  U1     CA48  VCCIN232  SOCKET4677_AZIFS054P001C01   I1
  U1     CA50  VCCIN233  SOCKET4677_AZIFS054P001C01   I1
  U1     CA52  VCCIN234  SOCKET4677_AZIFS054P001C01   I1
  U1     CA54  VCCIN235  SOCKET4677_AZIFS054P001C01   I1
  U1     CA56  VCCIN236  SOCKET4677_AZIFS054P001C01   I1
  U1     CA58  VCCIN237  SOCKET4677_AZIFS054P001C01   I1
  U1     CA60  VCCIN238  SOCKET4677_AZIFS054P001C01   I1
  U1     CA62  VCCIN239  SOCKET4677_AZIFS054P001C01   I1
  U1     CA64  VCCIN240  SOCKET4677_AZIFS054P001C01   I1
  U1     CA66  VCCIN241  SOCKET4677_AZIFS054P001C01   I1
  U1     CA68  VCCIN242  SOCKET4677_AZIFS054P001C01   I1
  U1     CA70  VCCIN243  SOCKET4677_AZIFS054P001C01   I1
  U1     CA72  VCCIN244  SOCKET4677_AZIFS054P001C01   I1
  U1     CA74  VCCIN245  SOCKET4677_AZIFS054P001C01   I1
  U1     CA76  VCCIN246  SOCKET4677_AZIFS054P001C01   I1
  U1     CA78  VCCIN247  SOCKET4677_AZIFS054P001C01   I1
  U1     CA80  VCCIN248  SOCKET4677_AZIFS054P001C01   I1
  U1     CA82  VCCIN249  SOCKET4677_AZIFS054P001C01   I1
  U1     CA84  VCCIN250  SOCKET4677_AZIFS054P001C01   I1
  U1     CA86  VCCIN251  SOCKET4677_AZIFS054P001C01   I1
  U1     CA88  VCCIN252  SOCKET4677_AZIFS054P001C01   I1
  U1     CA90  VCCIN253  SOCKET4677_AZIFS054P001C01   I1
  U1     CB61  VCCIN254  SOCKET4677_AZIFS054P001C01   I1
  U1     CB75  VCCIN255  SOCKET4677_AZIFS054P001C01   I1
  U1     CB77  VCCIN256  SOCKET4677_AZIFS054P001C01   I1
  U1     CC33  VCCIN257  SOCKET4677_AZIFS054P001C01   I1
  U1     CC35  VCCIN258  SOCKET4677_AZIFS054P001C01   I1
  U1     CC37  VCCIN259  SOCKET4677_AZIFS054P001C01   I1
  U1     CC39  VCCIN260  SOCKET4677_AZIFS054P001C01   I1
  U1     CC41  VCCIN261  SOCKET4677_AZIFS054P001C01   I1
  U1     CC43  VCCIN262  SOCKET4677_AZIFS054P001C01   I1
  U1     CC45  VCCIN263  SOCKET4677_AZIFS054P001C01   I1
  U1     CC48  VCCIN264  SOCKET4677_AZIFS054P001C01   I1
  U1     CC50  VCCIN265  SOCKET4677_AZIFS054P001C01   I1
  U1     CC52  VCCIN266  SOCKET4677_AZIFS054P001C01   I1
  U1     CC54  VCCIN267  SOCKET4677_AZIFS054P001C01   I1
  U1     CC56  VCCIN268  SOCKET4677_AZIFS054P001C01   I1
  U1     CC58  VCCIN269  SOCKET4677_AZIFS054P001C01   I1
  U1     CC60  VCCIN270  SOCKET4677_AZIFS054P001C01   I1
  U1     CC76  VCCIN271  SOCKET4677_AZIFS054P001C01   I1
  U1     CC78  VCCIN272  SOCKET4677_AZIFS054P001C01   I1
  U1     CC80  VCCIN273  SOCKET4677_AZIFS054P001C01   I1
  U1     CC82  VCCIN274  SOCKET4677_AZIFS054P001C01   I1
  U1     CC84  VCCIN275  SOCKET4677_AZIFS054P001C01   I1
  U1     CC86  VCCIN276  SOCKET4677_AZIFS054P001C01   I1
  U1     CC88  VCCIN277  SOCKET4677_AZIFS054P001C01   I1
  U1     CC90  VCCIN278  SOCKET4677_AZIFS054P001C01   I1
  U1     CD32  VCCIN279  SOCKET4677_AZIFS054P001C01   I1
  U1     CD34  VCCIN280  SOCKET4677_AZIFS054P001C01   I1
  U1     CD36  VCCIN281  SOCKET4677_AZIFS054P001C01   I1
  U1     CD38  VCCIN282  SOCKET4677_AZIFS054P001C01   I1
  U1     CD40  VCCIN283  SOCKET4677_AZIFS054P001C01   I1
  U1     CD42  VCCIN284  SOCKET4677_AZIFS054P001C01   I1
  U1     CD44  VCCIN285  SOCKET4677_AZIFS054P001C01   I1
  U1     CD47  VCCIN286  SOCKET4677_AZIFS054P001C01   I1
  U1     CD49  VCCIN287  SOCKET4677_AZIFS054P001C01   I1
  U1     CD51  VCCIN288  SOCKET4677_AZIFS054P001C01   I1
  U1     CD53  VCCIN289  SOCKET4677_AZIFS054P001C01   I1
  U1     CD55  VCCIN290  SOCKET4677_AZIFS054P001C01   I1
  U1     CD57  VCCIN291  SOCKET4677_AZIFS054P001C01   I1
  U1     CD59  VCCIN292  SOCKET4677_AZIFS054P001C01   I1
  U1     CD79  VCCIN293  SOCKET4677_AZIFS054P001C01   I1
  U1     CD81  VCCIN294  SOCKET4677_AZIFS054P001C01   I1
  U1     CD83  VCCIN295  SOCKET4677_AZIFS054P001C01   I1
  U1     CD85  VCCIN296  SOCKET4677_AZIFS054P001C01   I1
  U1     CD87  VCCIN297  SOCKET4677_AZIFS054P001C01   I1
  U1     CD89  VCCIN298  SOCKET4677_AZIFS054P001C01   I1
  U1     CE80  VCCIN299  SOCKET4677_AZIFS054P001C01   I1
  U1     CE82  VCCIN300  SOCKET4677_AZIFS054P001C01   I1
  U1     CE84  VCCIN301  SOCKET4677_AZIFS054P001C01   I1
  U1     CE86  VCCIN302  SOCKET4677_AZIFS054P001C01   I1
  U1     CE88  VCCIN303  SOCKET4677_AZIFS054P001C01   I1
  U1     CE90  VCCIN304  SOCKET4677_AZIFS054P001C01   I1
  U1     CF79  VCCIN305  SOCKET4677_AZIFS054P001C01   I1
  U1     CF81  VCCIN306  SOCKET4677_AZIFS054P001C01   I1
  U1     CF83  VCCIN307  SOCKET4677_AZIFS054P001C01   I1
  U1     CF85  VCCIN308  SOCKET4677_AZIFS054P001C01   I1
  U1     CF87  VCCIN309  SOCKET4677_AZIFS054P001C01   I1
  U1     CF89  VCCIN310  SOCKET4677_AZIFS054P001C01   I1
  U1     CF91  VCCIN311  SOCKET4677_AZIFS054P001C01   I1
  U1     CG80  VCCIN312  SOCKET4677_AZIFS054P001C01   I1
  U1     CG82  VCCIN313  SOCKET4677_AZIFS054P001C01   I1
  U1     CG84  VCCIN314  SOCKET4677_AZIFS054P001C01   I1
  U1     CG86  VCCIN315  SOCKET4677_AZIFS054P001C01   I1
  U1     CG88  VCCIN316  SOCKET4677_AZIFS054P001C01   I1
  U1     CG90  VCCIN317  SOCKET4677_AZIFS054P001C01   I1
  U1     CH81  VCCIN318  SOCKET4677_AZIFS054P001C01   I1
  U1     CH91  VCCIN319  SOCKET4677_AZIFS054P001C01   I1
  U1     CJ82  VCCIN320  SOCKET4677_AZIFS054P001C01   I1
  U1     CJ84  VCCIN321  SOCKET4677_AZIFS054P001C01   I1
  U1     CJ86  VCCIN322  SOCKET4677_AZIFS054P001C01   I1
  U1     CJ88  VCCIN323  SOCKET4677_AZIFS054P001C01   I1
  U1     CJ90  VCCIN324  SOCKET4677_AZIFS054P001C01   I1
  U1     CK83  VCCIN325  SOCKET4677_AZIFS054P001C01   I1
  U1     CK85  VCCIN326  SOCKET4677_AZIFS054P001C01   I1
  U1     CK87  VCCIN327  SOCKET4677_AZIFS054P001C01   I1
  U1     CK89  VCCIN328  SOCKET4677_AZIFS054P001C01   I1
  U1     CK91  VCCIN329  SOCKET4677_AZIFS054P001C01   I1
  U1     CL84  VCCIN330  SOCKET4677_AZIFS054P001C01   I1
  U1     CL86  VCCIN331  SOCKET4677_AZIFS054P001C01   I1
  U1     CL88  VCCIN332  SOCKET4677_AZIFS054P001C01   I1
  U1     CL90  VCCIN333  SOCKET4677_AZIFS054P001C01   I1
  U1     CM87  VCCIN334  SOCKET4677_AZIFS054P001C01   I1
  U1     CM89  VCCIN339  SOCKET4677_AZIFS054P001C01   I1
  U1     CM91  VCCIN335  SOCKET4677_AZIFS054P001C01   I1
  U1     CN88  VCCIN336  SOCKET4677_AZIFS054P001C01   I1
  U1     CN90  VCCIN337  SOCKET4677_AZIFS054P001C01   I1
  U1     CP89  VCCIN338  SOCKET4677_AZIFS054P001C01   I1

PVCCIN_CPU1_ADDR   @S9S_MB_2U_LIB.S9S_MB_2U(SCH_1):PVCCIN_CPU1_ADDR
  PR306    2      B  Q_RES       I161
  PR318    1      A  Q_RES       I165
  PU29    42  ADDR_CFG  RAA229126GNPHA0  I211

PVCCIN_CPU1_ATSEN   @S9S_MB_2U_LIB.S9S_MB_2U(SCH_1):PVCCIN_CPU1_ATSEN
  PC554    1      A  Q_CAP       I221
  PR637    1      A  Q_RES       I260
  PU23_P1_8   36  TOUT_FLT  ISL99390FRZTR5935   I9
  PU24_P1_7   36  TOUT_FLT  ISL99390FRZTR5935  I37
  PU25_P1_6   36  TOUT_FLT  ISL99390FRZTR5935  I23
  PU26_P1_5   36  TOUT_FLT  ISL99390FRZTR5935  I32
  PU27_P1_4   36  TOUT_FLT  ISL99390FRZTR5935   I9
  PU28_P1_3   36  TOUT_FLT  ISL99390FRZTR5935  I18
  PU29    43  TEMP0  RAA229126GNPHA0  I211
  PU30_P1_2   36  TOUT_FLT  ISL99390FRZTR5935  I18
  PU31_P1_1   36  TOUT_FLT  ISL99390FRZTR5935  I20
  PU75_P1_1   36  TOUT_FLT  ISL99390FRZTR5935  I278
  PU76_P1_2   36  TOUT_FLT  ISL99390FRZTR5935  I221
  PU77_P1_3   36  TOUT_FLT  ISL99390FRZTR5935  I27
  PU78_P1_4   36  TOUT_FLT  ISL99390FRZTR5935  I24

PVCCIN_CPU1_CSPIN   @S9S_MB_2U_LIB.S9S_MB_2U(SCH_1):PVCCIN_CPU1_CSPIN
  PC547    1      A  Q_CAP       I201
  PR304    2      B  Q_RES       I167
  PR305    1      A  Q_RES       I199
  PU29    45  VMON||IINSEN||VSYS||ISYS  RAA229126GNPHA0  I211

PVCCIN_CPU1_EN_R   @S9S_MB_2U_LIB.S9S_MB_2U(SCH_1):PVCCIN_CPU1_EN_R
  PC550    1      A  Q_CAP       I242
  PR309    2      B  Q_RES       I196
  PU29    17    EN0  RAA229126GNPHA0  I211

PVCCIN_CPU1_IMON1   @S9S_MB_2U_LIB.S9S_MB_2U(SCH_1):PVCCIN_CPU1_IMON1
  PU29    27   CS11  RAA229126GNPHA0  I211
  PU31_P1_1   38   IOUT  ISL99390FRZTR5935  I20

PVCCIN_CPU1_IMON2   @S9S_MB_2U_LIB.S9S_MB_2U(SCH_1):PVCCIN_CPU1_IMON2
  PU29    28   CS10  RAA229126GNPHA0  I211
  PU30_P1_2   38   IOUT  ISL99390FRZTR5935  I18

PVCCIN_CPU1_IMON3   @S9S_MB_2U_LIB.S9S_MB_2U(SCH_1):PVCCIN_CPU1_IMON3
  PU28_P1_3   38   IOUT  ISL99390FRZTR5935  I18
  PU29    29    CS9  RAA229126GNPHA0  I211

PVCCIN_CPU1_IMON4   @S9S_MB_2U_LIB.S9S_MB_2U(SCH_1):PVCCIN_CPU1_IMON4
  PU27_P1_4   38   IOUT  ISL99390FRZTR5935   I9
  PU29    30    CS8  RAA229126GNPHA0  I211

PVCCIN_CPU1_IMON5   @S9S_MB_2U_LIB.S9S_MB_2U(SCH_1):PVCCIN_CPU1_IMON5
  PU26_P1_5   38   IOUT  ISL99390FRZTR5935  I32
  PU29    31    CS7  RAA229126GNPHA0  I211

PVCCIN_CPU1_IMON6   @S9S_MB_2U_LIB.S9S_MB_2U(SCH_1):PVCCIN_CPU1_IMON6
  PU25_P1_6   38   IOUT  ISL99390FRZTR5935  I23
  PU29    32    CS6  RAA229126GNPHA0  I211

PVCCIN_CPU1_IMON7   @S9S_MB_2U_LIB.S9S_MB_2U(SCH_1):PVCCIN_CPU1_IMON7
  PU24_P1_7   38   IOUT  ISL99390FRZTR5935  I37
  PU29    33    CS5  RAA229126GNPHA0  I211

PVCCIN_CPU1_IMON8   @S9S_MB_2U_LIB.S9S_MB_2U(SCH_1):PVCCIN_CPU1_IMON8
  PU23_P1_8   38   IOUT  ISL99390FRZTR5935   I9
  PU29    34    CS4  RAA229126GNPHA0  I211

PVCCIN_CPU1_ISYS_R   @S9S_MB_2U_LIB.S9S_MB_2U(SCH_1):PVCCIN_CPU1_ISYS_R
  PR452    1      A  Q_RES       I263
  PR453    1      A  Q_RES       I262
  PU29    44  TEMP1||ISYS  RAA229126GNPHA0  I211

PVCCIN_CPU1_LSET1   @S9S_MB_2U_LIB.S9S_MB_2U(SCH_1):PVCCIN_CPU1_LSET1
  PR326    1      A  Q_RES       I12
  PU31_P1_1   37   LSET  ISL99390FRZTR5935  I20

PVCCIN_CPU1_LSET2   @S9S_MB_2U_LIB.S9S_MB_2U(SCH_1):PVCCIN_CPU1_LSET2
  PR325    1      A  Q_RES        I2
  PU30_P1_2   37   LSET  ISL99390FRZTR5935  I18

PVCCIN_CPU1_LSET3   @S9S_MB_2U_LIB.S9S_MB_2U(SCH_1):PVCCIN_CPU1_LSET3
  PR298    1      A  Q_RES       I20
  PU28_P1_3   37   LSET  ISL99390FRZTR5935  I18

PVCCIN_CPU1_LSET4   @S9S_MB_2U_LIB.S9S_MB_2U(SCH_1):PVCCIN_CPU1_LSET4
  PR297    1      A  Q_RES        I2
  PU27_P1_4   37   LSET  ISL99390FRZTR5935   I9

PVCCIN_CPU1_LSET5   @S9S_MB_2U_LIB.S9S_MB_2U(SCH_1):PVCCIN_CPU1_LSET5
  PR292    1      A  Q_RES       I13
  PU26_P1_5   37   LSET  ISL99390FRZTR5935  I32

PVCCIN_CPU1_LSET6   @S9S_MB_2U_LIB.S9S_MB_2U(SCH_1):PVCCIN_CPU1_LSET6
  PR291    1      A  Q_RES        I2
  PU25_P1_6   37   LSET  ISL99390FRZTR5935  I23

PVCCIN_CPU1_LSET7   @S9S_MB_2U_LIB.S9S_MB_2U(SCH_1):PVCCIN_CPU1_LSET7
  PR286    1      A  Q_RES       I18
  PU24_P1_7   37   LSET  ISL99390FRZTR5935  I37

PVCCIN_CPU1_LSET8   @S9S_MB_2U_LIB.S9S_MB_2U(SCH_1):PVCCIN_CPU1_LSET8
  PR285    1      A  Q_RES        I2
  PU23_P1_8   37   LSET  ISL99390FRZTR5935   I9

PVCCIN_CPU1_PIN_ALERT   @S9S_MB_2U_LIB.S9S_MB_2U(SCH_1):PVCCIN_CPU1_PIN_ALERT
  PR241    2      B  Q_RES       I214
  PU29    19  NPINALERT||NPSYS_CRIT  RAA229126GNPHA0  I211

PVCCIN_CPU1_PVCC   @S9S_MB_2U_LIB.S9S_MB_2U(SCH_1):PVCCIN_CPU1_PVCC
  PC481_P1_8    1      A  Q_CAP       I28
  PC482_P1_7    1      A  Q_CAP       I36
  PC503_P1_6    1      A  Q_CAP       I29
  PC504_P1_5    1      A  Q_CAP       I34
  PC525_P1_4    1      A  Q_CAP       I16
  PC526_P1_3    1      A  Q_CAP       I30
  PC558_P1_2    1      A  Q_CAP       I16
  PC559_P1_1    1      A  Q_CAP       I32
  PR287    1      A  Q_RES       I26
  PR288    1      A  Q_RES       I34
  PR293    1      A  Q_RES       I10
  PR294    1      A  Q_RES       I21
  PR299    1      A  Q_RES       I12
  PR300    1      A  Q_RES       I27
  PR327    1      A  Q_RES       I13
  PR328    1      A  Q_RES       I31
  PR639    2      B  Q_RES       I25
  PR640    2      B  Q_RES       I34
  PU23_P1_8    4   PVCC  ISL99390FRZTR5935   I9
  PU24_P1_7    4   PVCC  ISL99390FRZTR5935  I37
  PU25_P1_6    4   PVCC  ISL99390FRZTR5935  I23
  PU26_P1_5    4   PVCC  ISL99390FRZTR5935  I32
  PU27_P1_4    4   PVCC  ISL99390FRZTR5935   I9
  PU28_P1_3    4   PVCC  ISL99390FRZTR5935  I18
  PU30_P1_2    4   PVCC  ISL99390FRZTR5935  I18
  PU31_P1_1    4   PVCC  ISL99390FRZTR5935  I20

PVCCIN_CPU1_PWM1   @S9S_MB_2U_LIB.S9S_MB_2U(SCH_1):PVCCIN_CPU1_PWM1
  PU29    12  PWM11  RAA229126GNPHA0  I211
  PU31_P1_1   34    PWM  ISL99390FRZTR5935  I20

PVCCIN_CPU1_PWM2   @S9S_MB_2U_LIB.S9S_MB_2U(SCH_1):PVCCIN_CPU1_PWM2
  PU29    11  PWM10  RAA229126GNPHA0  I211
  PU30_P1_2   34    PWM  ISL99390FRZTR5935  I18

PVCCIN_CPU1_PWM3   @S9S_MB_2U_LIB.S9S_MB_2U(SCH_1):PVCCIN_CPU1_PWM3
  PU28_P1_3   34    PWM  ISL99390FRZTR5935  I18
  PU29    10   PWM9  RAA229126GNPHA0  I211

PVCCIN_CPU1_PWM4   @S9S_MB_2U_LIB.S9S_MB_2U(SCH_1):PVCCIN_CPU1_PWM4
  PU27_P1_4   34    PWM  ISL99390FRZTR5935   I9
  PU29     9   PWM8  RAA229126GNPHA0  I211

PVCCIN_CPU1_PWM5   @S9S_MB_2U_LIB.S9S_MB_2U(SCH_1):PVCCIN_CPU1_PWM5
  PU26_P1_5   34    PWM  ISL99390FRZTR5935  I32
  PU29     8   PWM7  RAA229126GNPHA0  I211

PVCCIN_CPU1_PWM6   @S9S_MB_2U_LIB.S9S_MB_2U(SCH_1):PVCCIN_CPU1_PWM6
  PU25_P1_6   34    PWM  ISL99390FRZTR5935  I23
  PU29     7   PWM6  RAA229126GNPHA0  I211

PVCCIN_CPU1_PWM7   @S9S_MB_2U_LIB.S9S_MB_2U(SCH_1):PVCCIN_CPU1_PWM7
  PU24_P1_7   34    PWM  ISL99390FRZTR5935  I37
  PU29     6   PWM5  RAA229126GNPHA0  I211

PVCCIN_CPU1_PWM8   @S9S_MB_2U_LIB.S9S_MB_2U(SCH_1):PVCCIN_CPU1_PWM8
  PU23_P1_8   34    PWM  ISL99390FRZTR5935   I9
  PU29     5   PWM4  RAA229126GNPHA0  I211

PVCCIN_CPU1_VCC   @S9S_MB_2U_LIB.S9S_MB_2U(SCH_1):PVCCIN_CPU1_VCC
  PC552    1      A  Q_CAP       I254
  PC555    1      A  Q_CAP       I258
  PR323    1      A  Q_RES       I278
  PU29    47    VCC  RAA229126GNPHA0  I211

PVCCIN_CPU1_VDD1   @S9S_MB_2U_LIB.S9S_MB_2U(SCH_1):PVCCIN_CPU1_VDD1
  PC557    1      A  Q_CAP       I29
  PR328    2      B  Q_RES       I31
  PU31_P1_1    3    VCC  ISL99390FRZTR5935  I20
  PU31_P1_1   35     EN  ISL99390FRZTR5935  I20

PVCCIN_CPU1_VDD2   @S9S_MB_2U_LIB.S9S_MB_2U(SCH_1):PVCCIN_CPU1_VDD2
  PC556    1      A  Q_CAP        I8
  PR327    2      B  Q_RES       I13
  PU30_P1_2    3    VCC  ISL99390FRZTR5935  I18
  PU30_P1_2   35     EN  ISL99390FRZTR5935  I18

PVCCIN_CPU1_VDD3   @S9S_MB_2U_LIB.S9S_MB_2U(SCH_1):PVCCIN_CPU1_VDD3
  PC524    1      A  Q_CAP       I26
  PR300    2      B  Q_RES       I27
  PU28_P1_3    3    VCC  ISL99390FRZTR5935  I18
  PU28_P1_3   35     EN  ISL99390FRZTR5935  I18

PVCCIN_CPU1_VDD4   @S9S_MB_2U_LIB.S9S_MB_2U(SCH_1):PVCCIN_CPU1_VDD4
  PC523    1      A  Q_CAP       I11
  PR299    2      B  Q_RES       I12
  PU27_P1_4    3    VCC  ISL99390FRZTR5935   I9
  PU27_P1_4   35     EN  ISL99390FRZTR5935   I9

PVCCIN_CPU1_VDD5   @S9S_MB_2U_LIB.S9S_MB_2U(SCH_1):PVCCIN_CPU1_VDD5
  PC502    1      A  Q_CAP       I20
  PR294    2      B  Q_RES       I21
  PU26_P1_5    3    VCC  ISL99390FRZTR5935  I32
  PU26_P1_5   35     EN  ISL99390FRZTR5935  I32

PVCCIN_CPU1_VDD6   @S9S_MB_2U_LIB.S9S_MB_2U(SCH_1):PVCCIN_CPU1_VDD6
  PC501    1      A  Q_CAP        I8
  PR293    2      B  Q_RES       I10
  PU25_P1_6    3    VCC  ISL99390FRZTR5935  I23
  PU25_P1_6   35     EN  ISL99390FRZTR5935  I23

PVCCIN_CPU1_VDD7   @S9S_MB_2U_LIB.S9S_MB_2U(SCH_1):PVCCIN_CPU1_VDD7
  PC480    1      A  Q_CAP       I32
  PR288    2      B  Q_RES       I34
  PU24_P1_7    3    VCC  ISL99390FRZTR5935  I37
  PU24_P1_7   35     EN  ISL99390FRZTR5935  I37

PVCCIN_CPU1_VDD8   @S9S_MB_2U_LIB.S9S_MB_2U(SCH_1):PVCCIN_CPU1_VDD8
  PC479    1      A  Q_CAP       I25
  PR287    2      B  Q_RES       I26
  PU23_P1_8    3    VCC  ISL99390FRZTR5935   I9
  PU23_P1_8   35     EN  ISL99390FRZTR5935   I9

PVCCIN_CPU1_VIN_CSNIN   @S9S_MB_2U_LIB.S9S_MB_2U(SCH_1):PVCCIN_CPU1_VIN_CSNIN
  PC548    1      A  Q_CAP       I209
  PR303    2      B  Q_RES       I166
  PR313    1      A  Q_RES       I208
  PU29    46  VINSEN||VSYS  RAA229126GNPHA0  I211

PVCCIN_CPU1_VOS1   @S9S_MB_2U_LIB.S9S_MB_2U(SCH_1):PVCCIN_CPU1_VOS1
  PR330    1      A  Q_RES       I90
  PU31_P1_1    1    VOS  ISL99390FRZTR5935  I20

PVCCIN_CPU1_VOS2   @S9S_MB_2U_LIB.S9S_MB_2U(SCH_1):PVCCIN_CPU1_VOS2
  PR329    1      A  Q_RES       I102
  PU30_P1_2    1    VOS  ISL99390FRZTR5935  I18

PVCCIN_CPU1_VOS3   @S9S_MB_2U_LIB.S9S_MB_2U(SCH_1):PVCCIN_CPU1_VOS3
  PR302    1      A  Q_RES       I80
  PU28_P1_3    1    VOS  ISL99390FRZTR5935  I18

PVCCIN_CPU1_VOS4   @S9S_MB_2U_LIB.S9S_MB_2U(SCH_1):PVCCIN_CPU1_VOS4
  PR301    1      A  Q_RES       I92
  PU27_P1_4    1    VOS  ISL99390FRZTR5935   I9

PVCCIN_CPU1_VOS5   @S9S_MB_2U_LIB.S9S_MB_2U(SCH_1):PVCCIN_CPU1_VOS5
  PR296    1      A  Q_RES       I80
  PU26_P1_5    1    VOS  ISL99390FRZTR5935  I32

PVCCIN_CPU1_VOS6   @S9S_MB_2U_LIB.S9S_MB_2U(SCH_1):PVCCIN_CPU1_VOS6
  PR295    1      A  Q_RES       I96
  PU25_P1_6    1    VOS  ISL99390FRZTR5935  I23

PVCCIN_CPU1_VOS7   @S9S_MB_2U_LIB.S9S_MB_2U(SCH_1):PVCCIN_CPU1_VOS7
  PR290    1      A  Q_RES       I79
  PU24_P1_7    1    VOS  ISL99390FRZTR5935  I37

PVCCIN_CPU1_VOS8   @S9S_MB_2U_LIB.S9S_MB_2U(SCH_1):PVCCIN_CPU1_VOS8
  PR289    1      A  Q_RES       I98
  PU23_P1_8    1    VOS  ISL99390FRZTR5935   I9

PVCCIN_CPU1_VREF   @S9S_MB_2U_LIB.S9S_MB_2U(SCH_1):PVCCIN_CPU1_VREF
  PC553    1      A  Q_CAP       I253
  PC1194    1      A  Q_CAP       I255
  PC1338    2      B  Q_CAP       I10
  PC1339    2      B  Q_CAP       I30
  PC1358    2      B  Q_CAP        I8
  PC1359    2      B  Q_CAP       I23
  PC1360    2      B  Q_CAP       I28
  PC1361    2      B  Q_CAP       I31
  PC1362    2      B  Q_CAP        I8
  PC1363    2      B  Q_CAP       I31
  PC1367    2      B  Q_CAP       I231
  PC1368    2      B  Q_CAP       I209
  PC1369    2      B  Q_CAP       I40
  PC1370    2      B  Q_CAP       I23
  PR306    1      A  Q_RES       I161
  PU23_P1_8   39  REFIN  ISL99390FRZTR5935   I9
  PU24_P1_7   39  REFIN  ISL99390FRZTR5935  I37
  PU25_P1_6   39  REFIN  ISL99390FRZTR5935  I23
  PU26_P1_5   39  REFIN  ISL99390FRZTR5935  I32
  PU27_P1_4   39  REFIN  ISL99390FRZTR5935   I9
  PU28_P1_3   39  REFIN  ISL99390FRZTR5935  I18
  PU29    48   VCCS  RAA229126GNPHA0  I211
  PU30_P1_2   39  REFIN  ISL99390FRZTR5935  I18
  PU31_P1_1   39  REFIN  ISL99390FRZTR5935  I20
  PU75_P1_1   39  REFIN  ISL99390FRZTR5935  I278
  PU76_P1_2   39  REFIN  ISL99390FRZTR5935  I221
  PU77_P1_3   39  REFIN  ISL99390FRZTR5935  I27
  PU78_P1_4   39  REFIN  ISL99390FRZTR5935  I24

PVCCIN_CPU1_VR_FAULT   @S9S_MB_2U_LIB.S9S_MB_2U(SCH_1):PVCCIN_CPU1_VR_FAULT
  PR243    2      B  Q_RES       I215
  PU29    41    CFP  RAA229126GNPHA0  I211

PVCCIO_PECI_BMC   @S9S_MB_2U_LIB.S9S_MB_2U(SCH_1):PVCCIO_PECI_BMC
  J41    B28  GND_B28  SCONN168_623403212  I115
  R142     2      B  Q_RES       I99

PVCCIO_PLDIO2   @S9S_MB_2U_LIB.S9S_MB_2U(SCH_1):PVCCIO_PLDIO2
  C1120    1      A  Q_CAP       I265
  C1129    1      A  Q_CAP       I263
  C1135    1      A  Q_CAP       I262
  R511     2      B  Q_RES       I266
  R512     2      B  Q_RES       I267
  U122   P11  VCCIO4_2  10M04SAU324I7G  I164
  U122   P12  VCCIO4_1  10M04SAU324I7G  I164

PVCCIO_PLDIO5   @S9S_MB_2U_LIB.S9S_MB_2U(SCH_1):PVCCIO_PLDIO5
  C1160    1      A  Q_CAP       I256
  C1166    1      A  Q_CAP       I255
  C1169    1      A  Q_CAP       I254
  R513     2      B  Q_RES       I258
  R514     2      B  Q_RES       I259
  R1425    2      B  Q_RES       I197
  R1426    2      B  Q_RES       I198
  R1427    2      B  Q_RES       I199
  R1428    2      B  Q_RES       I202
  R1429    2      B  Q_RES       I205
  R1430    2      B  Q_RES       I203
  R1431    2      B  Q_RES       I213
  R1432    2      B  Q_RES       I214
  R1433    2      B  Q_RES       I215
  U122    N9  VCCIO3_4  10M04SAU324I7G  I164
  U122    P7  VCCIO3_3  10M04SAU324I7G  I164
  U122    P8  VCCIO3_2  10M04SAU324I7G  I164
  U122    P9  VCCIO3_1  10M04SAU324I7G  I164

PVNN_MAIN_CPU0   @S9S_MB_2U_LIB.S9S_MB_2U(SCH_1):PVNN_MAIN_CPU0
  C395     1      A  Q_CAP       I108
  C590     1      A  Q_CAP       I171
  C1362    1      A  Q_CAP       I119
  C1363    1      A  Q_CAP       I51
  C1364    1      A  Q_CAP       I53
  C1399    1      A  Q_CAP       I111
  C1400    1      A  Q_CAP       I112
  C1405    1      A  Q_CAP       I238
  C1406    1      A  Q_CAP       I239
  C1407    1      A  Q_CAP       I240
  PC237    2      B  Q_CAP       I179
  PC1206    1      A  Q_CAP       I188
  PC1276    1      A  Q_CAP       I183
  PC1277    1      A  Q_CAP       I184
  PC1278    1      A  Q_CAP       I185
  PC1279    1      A  Q_CAP       I186
  PL120    2      2  Q_INDUCTOR  I180
  PR501    2      B  Q_RES       I182
  R324     1      A  Q_RES        I3
  U2     BA19  VCCVNN0  SOCKET4677_AZIFS054P001C01   I8
  U2     BE19  VCCVNN1  SOCKET4677_AZIFS054P001C01   I8
  U2     BJ19  VCCVNN2  SOCKET4677_AZIFS054P001C01   I8
  U2     BN19  VCCVNN3  SOCKET4677_AZIFS054P001C01   I8

PVNN_MAIN_CPU0_CS   @S9S_MB_2U_LIB.S9S_MB_2U(SCH_1):PVNN_MAIN_CPU0_CS
  PR1303    1      A  Q_RES       I161
  PU81     4     CS  MPQ8626GDZ  I190

PVNN_MAIN_CPU0_FB_RC   @S9S_MB_2U_LIB.S9S_MB_2U(SCH_1):PVNN_MAIN_CPU0_FB_RC
  PC237    1      A  Q_CAP       I179
  PR50     1      A  Q_RES       I172
  PR501    1      A  Q_RES       I182
  PU81     6     FB  MPQ8626GDZ  I190

PVNN_MAIN_CPU0_MODE   @S9S_MB_2U_LIB.S9S_MB_2U(SCH_1):PVNN_MAIN_CPU0_MODE
  PR1301    1      A  Q_RES       I162
  PU81    12   MODE  MPQ8626GDZ  I190

PVNN_MAIN_CPU0_REF   @S9S_MB_2U_LIB.S9S_MB_2U(SCH_1):PVNN_MAIN_CPU0_REF
  PC27     1      A  Q_CAP       I169
  PU81     8  TRK_REF  MPQ8626GDZ  I190

PVNN_MAIN_CPU0_VCC   @S9S_MB_2U_LIB.S9S_MB_2U(SCH_1):PVNN_MAIN_CPU0_VCC
  PC2221    1      A  Q_CAP       I159
  PU81    13    VCC  MPQ8626GDZ  I190

PVNN_MAIN_CPU1   @S9S_MB_2U_LIB.S9S_MB_2U(SCH_1):PVNN_MAIN_CPU1
  C310     1      A  Q_CAP       I148
  C1353    1      A  Q_CAP       I149
  C1365    1      A  Q_CAP       I47
  C1366    1      A  Q_CAP       I49
  C1387    1      A  Q_CAP       I141
  C1389    1      A  Q_CAP       I143
  C1391    1      A  Q_CAP       I147
  C1393    1      A  Q_CAP       I148
  C1403    1      A  Q_CAP       I146
  C1404    1      A  Q_CAP       I147
  PC238    2      B  Q_CAP       I189
  PC1207    1      A  Q_CAP       I196
  PC1284    1      A  Q_CAP       I184
  PC1285    1      A  Q_CAP       I192
  PC1286    1      A  Q_CAP       I193
  PC1287    1      A  Q_CAP       I194
  PL121    2      2  Q_INDUCTOR  I182
  PR502    2      B  Q_RES       I190
  R330     1      A  Q_RES        I9
  U1     BA19  VCCVNN0  SOCKET4677_AZIFS054P001C01   I8
  U1     BE19  VCCVNN1  SOCKET4677_AZIFS054P001C01   I8
  U1     BJ19  VCCVNN2  SOCKET4677_AZIFS054P001C01   I8
  U1     BN19  VCCVNN3  SOCKET4677_AZIFS054P001C01   I8

PVNN_MAIN_CPU1_CS   @S9S_MB_2U_LIB.S9S_MB_2U(SCH_1):PVNN_MAIN_CPU1_CS
  PR2222    1      A  Q_RES       I177
  PU82     4     CS  MPQ8626GDZ  I198

PVNN_MAIN_CPU1_FB_RC   @S9S_MB_2U_LIB.S9S_MB_2U(SCH_1):PVNN_MAIN_CPU1_FB_RC
  PC238    1      A  Q_CAP       I189
  PR51     1      A  Q_RES       I180
  PR502    1      A  Q_RES       I190
  PU82     6     FB  MPQ8626GDZ  I198

PVNN_MAIN_CPU1_MODE   @S9S_MB_2U_LIB.S9S_MB_2U(SCH_1):PVNN_MAIN_CPU1_MODE
  PR2220    1      A  Q_RES       I171
  PU82    12   MODE  MPQ8626GDZ  I198

PVNN_MAIN_CPU1_REF   @S9S_MB_2U_LIB.S9S_MB_2U(SCH_1):PVNN_MAIN_CPU1_REF
  PC28     1      A  Q_CAP       I179
  PU82     8  TRK_REF  MPQ8626GDZ  I198

PVNN_MAIN_CPU1_VCC   @S9S_MB_2U_LIB.S9S_MB_2U(SCH_1):PVNN_MAIN_CPU1_VCC
  PC2222    1      A  Q_CAP       I174
  PU82    13    VCC  MPQ8626GDZ  I198

PVNN_TERM_CPU0   @S9S_MB_2U_LIB.S9S_MB_2U(SCH_1):PVNN_TERM_CPU0
  C559     1      A  Q_CAP       I20
  C567     1      A  Q_CAP       I25
  C1302    1      A  Q_CAP       I101
  C2443    1      A  Q_CAP       I20
  C2444    1      A  Q_CAP       I24
  PC327    1      A  Q_CAP       I104
  PC328    1      A  Q_CAP       I106
  PR528    2      B  Q_RES       I102
  PR529    2      B  Q_RES       I101
  PR530    2      B  Q_RES       I100
  R18      1      A  Q_RES       I35
  R19      1      A  Q_RES       I36
  R94      1      A  Q_RES       I25
  R95      1      A  Q_RES       I23
  R96      1      A  Q_RES       I22
  R97      1      A  Q_RES       I114
  R142     1      A  Q_RES       I99
  R146     1      A  Q_RES        I6
  R183     2      B  Q_RES       I62
  R185     2      B  Q_RES       I60
  R197     1      A  Q_RES       I53
  R199     1      A  Q_RES       I111
  R200     1      A  Q_RES       I102
  R219     1      A  Q_RES       I54
  R243     1      A  Q_RES       I171
  R249     1      A  Q_RES       I27
  R250     1      A  Q_RES       I29
  R251     1      A  Q_RES       I28
  R252     1      A  Q_RES       I30
  R253     1      A  Q_RES       I31
  R254     1      A  Q_RES       I32
  R275     1      A  Q_RES       I68
  R276     1      A  Q_RES       I66
  R277     1      A  Q_RES       I62
  R278     1      A  Q_RES       I61
  R279     1      A  Q_RES       I54
  R280     1      A  Q_RES       I57
  R281     1      A  Q_RES       I58
  R282     1      A  Q_RES       I53
  R296     1      A  Q_RES       I65
  R301     1      A  Q_RES       I73
  R323     2      B  Q_RES        I4
  R324     2      B  Q_RES        I3
  R328     2      B  Q_RES       I93
  R513     1      A  Q_RES       I258
  R548     2      B  Q_RES       I94
  R555     2      B  Q_RES       I98
  R556     2      B  Q_RES       I100
  R557     2      B  Q_RES       I74
  R558     2      B  Q_RES       I73
  R559     2      B  Q_RES       I69
  R560     2      B  Q_RES       I70
  R561     1      A  Q_RES       I21
  R679     1      A  Q_RES       I85
  R680     1      A  Q_RES       I89
  R681     1      A  Q_RES       I87
  R686     1      A  Q_RES       I86
  R741     1      A  Q_RES       I66
  R744     1      A  Q_RES       I77
  R757     1      A  Q_RES       I166
  R758     1      A  Q_RES       I168
  R759     1      A  Q_RES       I169
  R760     1      A  Q_RES       I174
  R761     1      A  Q_RES       I175
  R779     1      A  Q_RES       I95
  R910     1      A  Q_RES       I24
  R911     1      A  Q_RES       I22
  R969     1      A  Q_RES       I43
  R971     1      A  Q_RES       I42
  R1006    1      A  Q_RES        I8
  R1009    1      A  Q_RES       I136
  R1232    1      A  Q_RES       I156
  R1233    1      A  Q_RES       I158
  R1242    1      A  Q_RES       I13
  R1485    1      A  Q_RES       I75
  R1486    1      A  Q_RES       I74
  R1717    1      A  Q_RES       I26
  R1735    1      A  Q_RES       I25
  R1956    2      B  Q_RES       I146
  R2322    1      A  Q_RES       I22
  U28      1   VCCA  PCA9617ADP  I39
  U30      1   VCCA  PCA9617ADP  I28

PVNN_TERM_CPU1   @S9S_MB_2U_LIB.S9S_MB_2U(SCH_1):PVNN_TERM_CPU1
  C560     1      A  Q_CAP       I42
  C568     1      A  Q_CAP       I35
  PC545    1      A  Q_CAP       I271
  PC546    1      A  Q_CAP       I273
  PC1336    1      A  Q_CAP       I210
  PC1337    1      A  Q_CAP       I215
  PR575    2      B  Q_RES       I272
  PR576    2      B  Q_RES       I269
  PR577    2      B  Q_RES       I268
  PR1718    1      A  Q_RES       I216
  PR1747    1      A  Q_RES       I217
  R49      1      A  Q_RES       I34
  R50      1      A  Q_RES       I35
  R90      1      A  Q_RES       I135
  R91      1      A  Q_RES       I136
  R92      1      A  Q_RES       I140
  R93      1      A  Q_RES       I141
  R155     2      B  Q_RES       I26
  R157     2      B  Q_RES       I24
  R198     1      A  Q_RES       I54
  R201     1      A  Q_RES       I108
  R202     1      A  Q_RES       I110
  R220     1      A  Q_RES       I63
  R244     1      A  Q_RES       I173
  R255     1      A  Q_RES       I42
  R256     1      A  Q_RES       I48
  R257     1      A  Q_RES       I43
  R258     1      A  Q_RES       I44
  R259     1      A  Q_RES       I45
  R260     1      A  Q_RES       I46
  R261     1      A  Q_RES       I101
  R262     1      A  Q_RES       I100
  R263     1      A  Q_RES       I125
  R264     1      A  Q_RES       I98
  R265     1      A  Q_RES       I97
  R266     1      A  Q_RES       I96
  R267     1      A  Q_RES       I95
  R268     1      A  Q_RES       I94
  R298     1      A  Q_RES       I67
  R303     1      A  Q_RES       I76
  R329     2      B  Q_RES        I8
  R330     2      B  Q_RES        I9
  R662     1      A  Q_RES       I49
  R663     1      A  Q_RES       I48
  R664     1      A  Q_RES       I47
  R669     1      A  Q_RES       I46
  R742     1      A  Q_RES       I78
  R743     1      A  Q_RES       I65
  R963     1      A  Q_RES       I48
  R964     1      A  Q_RES       I46
  R970     1      A  Q_RES       I50
  R972     1      A  Q_RES       I49
  R1007    1      A  Q_RES       I12
  R1008    1      A  Q_RES       I139
  R1229    1      A  Q_RES       I169
  R1230    1      A  Q_RES       I170
  R1244    1      A  Q_RES       I16
  R1957    2      B  Q_RES       I148
  R2345    1      A  Q_RES       I39
  R2354    1      A  Q_RES       I38
  U29      1   VCCA  PCA9617ADP  I43
  U31      1   VCCA  PCA9617ADP  I37

PVPP_HBM_CPU0   @S9S_MB_2U_LIB.S9S_MB_2U(SCH_1):PVPP_HBM_CPU0
  C1396    1      A  Q_CAP       I227
  C1397    1      A  Q_CAP       I229
  C1398    1      A  Q_CAP       I230
  C1436    1      A  Q_CAP       I242
  PC1254    1      A  Q_CAP       I34
  PC1255    1      A  Q_CAP       I37
  PC1256    1      A  Q_CAP       I38
  PC1257    1      A  Q_CAP       I39
  PC1258    1      A  Q_CAPP      I42
  PJ64     2      2  Q_SHORT     I57
  PL118    2      2  Q_INDUCTOR  I24
  U2     CC68  VPP_HBM0  SOCKET4677_AZIFS054P001C01   I8
  U2     CD67  VPP_HBM1  SOCKET4677_AZIFS054P001C01   I8
  U2     CE68  VPP_HBM2  SOCKET4677_AZIFS054P001C01   I8
  U2     CF67  VPP_HBM3  SOCKET4677_AZIFS054P001C01   I8
  U2     CG68  VPP_HBM4  SOCKET4677_AZIFS054P001C01   I8

PVPP_HBM_CPU0_CS   @S9S_MB_2U_LIB.S9S_MB_2U(SCH_1):PVPP_HBM_CPU0_CS
  PR1336    1      A  Q_RES       I12
  PU79     3     CS  MPQ8633AGLEC807Z  I13

PVPP_HBM_CPU0_FB   @S9S_MB_2U_LIB.S9S_MB_2U(SCH_1):PVPP_HBM_CPU0_FB
  PC1253    1      A  Q_CAP       I52
  PR1310    1      A  Q_RES       I49
  PR1337    1      A  Q_RES       I53
  PU79     7     FB  MPQ8633AGLEC807Z  I13
  R2336    1      A  Q_RES       I51

PVPP_HBM_CPU0_REF   @S9S_MB_2U_LIB.S9S_MB_2U(SCH_1):PVPP_HBM_CPU0_REF
  PC1251    1      A  Q_CAP       I46
  PC2001    1      A  Q_CAP       I48
  PU79     5  TRK_REF  MPQ8633AGLEC807Z  I13

PVPP_HBM_CPU0_VCC   @S9S_MB_2U_LIB.S9S_MB_2U(SCH_1):PVPP_HBM_CPU0_VCC
  PC2643    1      A  Q_CAP        I2
  PR1335    2      B  Q_RES        I5
  PU79     4   MODE  MPQ8633AGLEC807Z  I13
  PU79    19    VCC  MPQ8633AGLEC807Z  I13

PVPP_HBM_CPU1   @S9S_MB_2U_LIB.S9S_MB_2U(SCH_1):PVPP_HBM_CPU1
  C1388    1      A  Q_CAP       I139
  C1390    1      A  Q_CAP       I140
  C1392    1      A  Q_CAP       I145
  C1437    1      A  Q_CAP       I149
  PC1267    1      A  Q_CAP       I30
  PC1268    1      A  Q_CAP       I31
  PC1269    1      A  Q_CAP       I32
  PC1270    1      A  Q_CAP       I35
  PC1771    1      A  Q_CAPP      I36
  PJ66     2      2  Q_SHORT     I56
  PL119    2      2  Q_INDUCTOR  I41
  U1     CC68  VPP_HBM0  SOCKET4677_AZIFS054P001C01   I8
  U1     CD67  VPP_HBM1  SOCKET4677_AZIFS054P001C01   I8
  U1     CE68  VPP_HBM2  SOCKET4677_AZIFS054P001C01   I8
  U1     CF67  VPP_HBM3  SOCKET4677_AZIFS054P001C01   I8
  U1     CG68  VPP_HBM4  SOCKET4677_AZIFS054P001C01   I8

PVPP_HBM_CPU1_CS   @S9S_MB_2U_LIB.S9S_MB_2U(SCH_1):PVPP_HBM_CPU1_CS
  PR1339    1      A  Q_RES       I14
  PU80     3     CS  MPQ8633AGLEC807Z  I15

PVPP_HBM_CPU1_FB   @S9S_MB_2U_LIB.S9S_MB_2U(SCH_1):PVPP_HBM_CPU1_FB
  PC1266    1      A  Q_CAP       I52
  PR1314    1      A  Q_RES       I49
  PR1340    1      A  Q_RES       I54
  PU80     7     FB  MPQ8633AGLEC807Z  I15
  R2381    1      A  Q_RES       I51

PVPP_HBM_CPU1_REF   @S9S_MB_2U_LIB.S9S_MB_2U(SCH_1):PVPP_HBM_CPU1_REF
  PC1264    1      A  Q_CAP       I48
  PC2002    1      A  Q_CAP       I47
  PU80     5  TRK_REF  MPQ8633AGLEC807Z  I15

PVPP_HBM_CPU1_VCC   @S9S_MB_2U_LIB.S9S_MB_2U(SCH_1):PVPP_HBM_CPU1_VCC
  PC644    1      A  Q_CAP        I7
  PR1338    2      B  Q_RES        I8
  PU80     4   MODE  MPQ8633AGLEC807Z  I15
  PU80    19    VCC  MPQ8633AGLEC807Z  I15

PWRGD_CHA_CPU0_DIMM1   @S9S_MB_2U_LIB.S9S_MB_2U(SCH_1):PWRGD_CHA_CPU0_DIMM1
  J1     147  PWR_GOOD||FAIL_N  SCONN288_ADR50001P013C01  I198
  R877     1      A  Q_RES       I34

PWRGD_CHA_CPU0_DIMM2   @S9S_MB_2U_LIB.S9S_MB_2U(SCH_1):PWRGD_CHA_CPU0_DIMM2
  J2     147  PWR_GOOD||FAIL_N  SCONN288_ADR50001P003C01  I177
  R878     1      A  Q_RES       I59

PWRGD_CHA_CPU1_DIMM1   @S9S_MB_2U_LIB.S9S_MB_2U(SCH_1):PWRGD_CHA_CPU1_DIMM1
  J17    147  PWR_GOOD||FAIL_N  SCONN288_ADR50001P013C01  I12
  R893     1      A  Q_RES       I104

PWRGD_CHA_CPU1_DIMM2   @S9S_MB_2U_LIB.S9S_MB_2U(SCH_1):PWRGD_CHA_CPU1_DIMM2
  J18    147  PWR_GOOD||FAIL_N  SCONN288_ADR50001P003C01  I24
  R894     1      A  Q_RES       I105

PWRGD_CHB_CPU0_DIMM1   @S9S_MB_2U_LIB.S9S_MB_2U(SCH_1):PWRGD_CHB_CPU0_DIMM1
  J3     147  PWR_GOOD||FAIL_N  SCONN288_ADR50001P013C01  I11
  R879     1      A  Q_RES       I63

PWRGD_CHB_CPU0_DIMM2   @S9S_MB_2U_LIB.S9S_MB_2U(SCH_1):PWRGD_CHB_CPU0_DIMM2
  J4     147  PWR_GOOD||FAIL_N  SCONN288_ADR50001P003C01  I23
  R880     1      A  Q_RES       I61

PWRGD_CHB_CPU1_DIMM1   @S9S_MB_2U_LIB.S9S_MB_2U(SCH_1):PWRGD_CHB_CPU1_DIMM1
  J19    147  PWR_GOOD||FAIL_N  SCONN288_ADR50001P013C01  I25
  R895     1      A  Q_RES       I106

PWRGD_CHB_CPU1_DIMM2   @S9S_MB_2U_LIB.S9S_MB_2U(SCH_1):PWRGD_CHB_CPU1_DIMM2
  J20    147  PWR_GOOD||FAIL_N  SCONN288_ADR50001P003C01  I47
  R896     1      A  Q_RES       I107

PWRGD_CHC_CPU0_DIMM1   @S9S_MB_2U_LIB.S9S_MB_2U(SCH_1):PWRGD_CHC_CPU0_DIMM1
  J5     147  PWR_GOOD||FAIL_N  SCONN288_ADR50001P013C01  I24
  R881     1      A  Q_RES       I71

PWRGD_CHC_CPU0_DIMM2   @S9S_MB_2U_LIB.S9S_MB_2U(SCH_1):PWRGD_CHC_CPU0_DIMM2
  J6     147  PWR_GOOD||FAIL_N  SCONN288_ADR50001P003C01  I46
  R882     1      A  Q_RES       I72

PWRGD_CHC_CPU1_DIMM1   @S9S_MB_2U_LIB.S9S_MB_2U(SCH_1):PWRGD_CHC_CPU1_DIMM1
  J21    147  PWR_GOOD||FAIL_N  SCONN288_ADR50001P013C01  I13
  R897     1      A  Q_RES       I109

PWRGD_CHC_CPU1_DIMM2   @S9S_MB_2U_LIB.S9S_MB_2U(SCH_1):PWRGD_CHC_CPU1_DIMM2
  J22    147  PWR_GOOD||FAIL_N  SCONN288_ADR50001P003C01  I51
  R898     1      A  Q_RES       I108

PWRGD_CHD_CPU0_DIMM1   @S9S_MB_2U_LIB.S9S_MB_2U(SCH_1):PWRGD_CHD_CPU0_DIMM1
  J7     147  PWR_GOOD||FAIL_N  SCONN288_ADR50001P013C01  I12
  R883     1      A  Q_RES       I73

PWRGD_CHD_CPU0_DIMM2   @S9S_MB_2U_LIB.S9S_MB_2U(SCH_1):PWRGD_CHD_CPU0_DIMM2
  J8     147  PWR_GOOD||FAIL_N  SCONN288_ADR50001P003C01  I50
  R884     1      A  Q_RES       I74

PWRGD_CHD_CPU1_DIMM1   @S9S_MB_2U_LIB.S9S_MB_2U(SCH_1):PWRGD_CHD_CPU1_DIMM1
  J23    147  PWR_GOOD||FAIL_N  SCONN288_ADR50001P013C01  I25
  R899     1      A  Q_RES       I110

PWRGD_CHD_CPU1_DIMM2   @S9S_MB_2U_LIB.S9S_MB_2U(SCH_1):PWRGD_CHD_CPU1_DIMM2
  J24    147  PWR_GOOD||FAIL_N  SCONN288_ADR50001P003C01  I178
  R900     1      A  Q_RES       I111

PWRGD_CHE_CPU0_DIMM1   @S9S_MB_2U_LIB.S9S_MB_2U(SCH_1):PWRGD_CHE_CPU0_DIMM1
  J9     147  PWR_GOOD||FAIL_N  SCONN288_ADR50001P013C01  I12
  R885     1      A  Q_RES       I81

PWRGD_CHE_CPU0_DIMM2   @S9S_MB_2U_LIB.S9S_MB_2U(SCH_1):PWRGD_CHE_CPU0_DIMM2
  J10    147  PWR_GOOD||FAIL_N  SCONN288_ADR50001P003C01  I13
  R886     1      A  Q_RES       I82

PWRGD_CHE_CPU1_DIMM1   @S9S_MB_2U_LIB.S9S_MB_2U(SCH_1):PWRGD_CHE_CPU1_DIMM1
  J25    147  PWR_GOOD||FAIL_N  SCONN288_ADR50001P013C01  I180
  R901     1      A  Q_RES       I112

PWRGD_CHE_CPU1_DIMM2   @S9S_MB_2U_LIB.S9S_MB_2U(SCH_1):PWRGD_CHE_CPU1_DIMM2
  J26    147  PWR_GOOD||FAIL_N  SCONN288_ADR50001P003C01  I180
  R902     1      A  Q_RES       I113

PWRGD_CHF_CPU0_DIMM1   @S9S_MB_2U_LIB.S9S_MB_2U(SCH_1):PWRGD_CHF_CPU0_DIMM1
  J11    147  PWR_GOOD||FAIL_N  SCONN288_ADR50001P013C01  I25
  R887     1      A  Q_RES       I83

PWRGD_CHF_CPU0_DIMM2   @S9S_MB_2U_LIB.S9S_MB_2U(SCH_1):PWRGD_CHF_CPU0_DIMM2
  J12    147  PWR_GOOD||FAIL_N  SCONN288_ADR50001P003C01  I24
  R888     1      A  Q_RES       I84

PWRGD_CHF_CPU1_DIMM1   @S9S_MB_2U_LIB.S9S_MB_2U(SCH_1):PWRGD_CHF_CPU1_DIMM1
  J27    147  PWR_GOOD||FAIL_N  SCONN288_ADR50001P013C01  I179
  R903     1      A  Q_RES       I114

PWRGD_CHF_CPU1_DIMM2   @S9S_MB_2U_LIB.S9S_MB_2U(SCH_1):PWRGD_CHF_CPU1_DIMM2
  J28    147  PWR_GOOD||FAIL_N  SCONN288_ADR50001P003C01  I47
  R904     1      A  Q_RES       I115

PWRGD_CHG_CPU0_DIMM1   @S9S_MB_2U_LIB.S9S_MB_2U(SCH_1):PWRGD_CHG_CPU0_DIMM1
  J13    147  PWR_GOOD||FAIL_N  SCONN288_ADR50001P013C01  I11
  R889     1      A  Q_RES       I86

PWRGD_CHG_CPU0_DIMM2   @S9S_MB_2U_LIB.S9S_MB_2U(SCH_1):PWRGD_CHG_CPU0_DIMM2
  J14    147  PWR_GOOD||FAIL_N  SCONN288_ADR50001P003C01  I47
  R890     1      A  Q_RES       I85

PWRGD_CHG_CPU1_DIMM1   @S9S_MB_2U_LIB.S9S_MB_2U(SCH_1):PWRGD_CHG_CPU1_DIMM1
  J29    147  PWR_GOOD||FAIL_N  SCONN288_ADR50001P013C01  I179
  R905     1      A  Q_RES       I116

PWRGD_CHG_CPU1_DIMM2   @S9S_MB_2U_LIB.S9S_MB_2U(SCH_1):PWRGD_CHG_CPU1_DIMM2
  J30    147  PWR_GOOD||FAIL_N  SCONN288_ADR50001P003C01  I179
  R906     1      A  Q_RES       I117

PWRGD_CHH_CPU0_DIMM1   @S9S_MB_2U_LIB.S9S_MB_2U(SCH_1):PWRGD_CHH_CPU0_DIMM1
  J15    147  PWR_GOOD||FAIL_N  SCONN288_ADR50001P013C01  I48
  R891     1      A  Q_RES       I87

PWRGD_CHH_CPU0_DIMM2   @S9S_MB_2U_LIB.S9S_MB_2U(SCH_1):PWRGD_CHH_CPU0_DIMM2
  J16    147  PWR_GOOD||FAIL_N  SCONN288_ADR50001P003C01   I6
  R892     1      A  Q_RES       I76

PWRGD_CHH_CPU1_DIMM1   @S9S_MB_2U_LIB.S9S_MB_2U(SCH_1):PWRGD_CHH_CPU1_DIMM1
  J31    147  PWR_GOOD||FAIL_N  SCONN288_ADR50001P013C01  I180
  R907     1      A  Q_RES       I118

PWRGD_CHH_CPU1_DIMM2   @S9S_MB_2U_LIB.S9S_MB_2U(SCH_1):PWRGD_CHH_CPU1_DIMM2
  J32    147  PWR_GOOD||FAIL_N  SCONN288_ADR50001P003C01  I179
  R908     1      A  Q_RES       I119

PWRGD_CPU0_BUF_R   @S9S_MB_2U_LIB.S9S_MB_2U(SCH_1):PWRGD_CPU0_BUF_R
  R168     2      B  Q_RES       I43
  R183     1      A  Q_RES       I62
  R184     1      A  Q_RES       I56

PWRGD_CPU0_LVC1   @S9S_MB_2U_LIB.S9S_MB_2U(SCH_1):PWRGD_CPU0_LVC1
  R184     2      B  Q_RES       I56
  U2     AV20  CPUPWRGOOD  SOCKET4677_AZIFS054P001C01   I1

PWRGD_CPU0_LVC1_R   @S9S_MB_2U_LIB.S9S_MB_2U(SCH_1):PWRGD_CPU0_LVC1_R
  R168     1      A  Q_RES       I43
  R992     1      A  Q_RES       I21
  U122    U3  DIFFIO_RX_B2N  10M04SAU324I7G  I93

PWRGD_CPU1_BUF_R   @S9S_MB_2U_LIB.S9S_MB_2U(SCH_1):PWRGD_CPU1_BUF_R
  R130     2      B  Q_RES        I5
  R155     1      A  Q_RES       I26
  R156     1      A  Q_RES       I25

PWRGD_CPU1_LVC1   @S9S_MB_2U_LIB.S9S_MB_2U(SCH_1):PWRGD_CPU1_LVC1
  R156     2      B  Q_RES       I25
  U1     AV20  CPUPWRGOOD  SOCKET4677_AZIFS054P001C01  I29

PWRGD_CPU1_LVC1_R   @S9S_MB_2U_LIB.S9S_MB_2U(SCH_1):PWRGD_CPU1_LVC1_R
  R130     1      A  Q_RES        I5
  R1398    1      A  Q_RES       I22
  U122    R4  DIFFIO_TX_RX_B1N  10M04SAU324I7G  I155

PWRGD_CPUPWRGD_GTL   @S9S_MB_2U_LIB.S9S_MB_2U(SCH_1):PWRGD_CPUPWRGD_GTL
  R315     1      A  Q_RES       I92
  U4     G10  CPUPWRGD  EMMITSBURG_REV0P9  I36

PWRGD_CPUPWRGD_LVC1   @S9S_MB_2U_LIB.S9S_MB_2U(SCH_1):PWRGD_CPUPWRGD_LVC1
  R1443    1      A  Q_RES       I49
  U122    U7  DIFFIO_RX_B11N  10M04SAU324I7G  I93

PWRGD_CPUPWRGD_LVC1_R   @S9S_MB_2U_LIB.S9S_MB_2U(SCH_1):PWRGD_CPUPWRGD_LVC1_R
  R315     2      B  Q_RES       I92
  R1443    2      B  Q_RES       I49

PWRGD_DRAMPWRGD_CPU0_AB_LVC1_R   @S9S_MB_2U_LIB.S9S_MB_2U(SCH_1):PWRGD_DRAMPWRGD_CPU0_AB_LVC1_R
  R160     2      B  Q_RES       I17
  R175     1      A  Q_RES       I74
  U2     A43  DDR01_DRAM_PWR_OK  SOCKET4677_AZIFS054P001C01   I1

PWRGD_DRAMPWRGD_CPU0_AB_R_LVC1   @S9S_MB_2U_LIB.S9S_MB_2U(SCH_1):PWRGD_DRAMPWRGD_CPU0_AB_R_LVC1
  R160     1      A  Q_RES       I17
  R1302    1      A  Q_RES       I12
  U122   P10  DIFFIO_TX_RX_B18N  10M04SAU324I7G  I155

PWRGD_DRAMPWRGD_CPU0_CD_LVC1_R   @S9S_MB_2U_LIB.S9S_MB_2U(SCH_1):PWRGD_DRAMPWRGD_CPU0_CD_LVC1_R
  R162     2      B  Q_RES       I19
  R177     1      A  Q_RES       I72
  U2     F47  DDR23_DRAM_PWR_OK  SOCKET4677_AZIFS054P001C01   I1

PWRGD_DRAMPWRGD_CPU0_CD_R_LVC1   @S9S_MB_2U_LIB.S9S_MB_2U(SCH_1):PWRGD_DRAMPWRGD_CPU0_CD_R_LVC1
  R162     1      A  Q_RES       I19
  R1326    1      A  Q_RES       I11
  U122   M10  DIFFIO_TX_RX_B20N  10M04SAU324I7G  I155

PWRGD_DRAMPWRGD_CPU0_EF_LVC1_R   @S9S_MB_2U_LIB.S9S_MB_2U(SCH_1):PWRGD_DRAMPWRGD_CPU0_EF_LVC1_R
  R164     2      B  Q_RES       I26
  R179     1      A  Q_RES       I70
  U2     CY44  DDR45_DRAM_PWR_OK  SOCKET4677_AZIFS054P001C01   I1

PWRGD_DRAMPWRGD_CPU0_EF_R_LVC1   @S9S_MB_2U_LIB.S9S_MB_2U(SCH_1):PWRGD_DRAMPWRGD_CPU0_EF_R_LVC1
  R164     1      A  Q_RES       I26
  R1327    1      A  Q_RES       I14
  U122   N11  DIFFIO_TX_RX_B18P  10M04SAU324I7G  I155

PWRGD_DRAMPWRGD_CPU0_GH_LVC1_R   @S9S_MB_2U_LIB.S9S_MB_2U(SCH_1):PWRGD_DRAMPWRGD_CPU0_GH_LVC1_R
  R166     2      B  Q_RES       I33
  R181     1      A  Q_RES       I68
  U2     CW45  DDR67_DRAM_PWR_OK  SOCKET4677_AZIFS054P001C01   I1

PWRGD_DRAMPWRGD_CPU0_GH_R_LVC1   @S9S_MB_2U_LIB.S9S_MB_2U(SCH_1):PWRGD_DRAMPWRGD_CPU0_GH_R_LVC1
  R166     1      A  Q_RES       I33
  R1328    1      A  Q_RES       I13
  U122   L10  DIFFIO_TX_RX_B20P  10M04SAU324I7G  I155

PWRGD_DRAMPWRGD_CPU1_AB_LVC1_R   @S9S_MB_2U_LIB.S9S_MB_2U(SCH_1):PWRGD_DRAMPWRGD_CPU1_AB_LVC1_R
  R122     2      B  Q_RES       I17
  R135     1      A  Q_RES       I62
  U1     A43  DDR01_DRAM_PWR_OK  SOCKET4677_AZIFS054P001C01  I29

PWRGD_DRAMPWRGD_CPU1_AB_R_LVC1   @S9S_MB_2U_LIB.S9S_MB_2U(SCH_1):PWRGD_DRAMPWRGD_CPU1_AB_R_LVC1
  R122     1      A  Q_RES       I17
  R1329    1      A  Q_RES       I15
  U122   U15  DIFFIO_RX_B26P  10M04SAU324I7G  I93

PWRGD_DRAMPWRGD_CPU1_CD_LVC1_R   @S9S_MB_2U_LIB.S9S_MB_2U(SCH_1):PWRGD_DRAMPWRGD_CPU1_CD_LVC1_R
  R124     2      B  Q_RES       I15
  R137     1      A  Q_RES       I60
  U1     F47  DDR23_DRAM_PWR_OK  SOCKET4677_AZIFS054P001C01  I29

PWRGD_DRAMPWRGD_CPU1_CD_R_LVC1   @S9S_MB_2U_LIB.S9S_MB_2U(SCH_1):PWRGD_DRAMPWRGD_CPU1_CD_R_LVC1
  R124     1      A  Q_RES       I15
  R1330    1      A  Q_RES       I16
  U122   U17  DIFFIO_TX_RX_B27P  10M04SAU324I7G  I155

PWRGD_DRAMPWRGD_CPU1_EF_LVC1_R   @S9S_MB_2U_LIB.S9S_MB_2U(SCH_1):PWRGD_DRAMPWRGD_CPU1_EF_LVC1_R
  R126     2      B  Q_RES       I13
  R151     1      A  Q_RES       I58
  U1     CY44  DDR45_DRAM_PWR_OK  SOCKET4677_AZIFS054P001C01  I29

PWRGD_DRAMPWRGD_CPU1_EF_R_LVC1   @S9S_MB_2U_LIB.S9S_MB_2U(SCH_1):PWRGD_DRAMPWRGD_CPU1_EF_R_LVC1
  R126     1      A  Q_RES       I13
  R1388    1      A  Q_RES       I17
  U122   U13  DIFFIO_RX_B19P  10M04SAU324I7G  I93

PWRGD_DRAMPWRGD_CPU1_GH_LVC1_R   @S9S_MB_2U_LIB.S9S_MB_2U(SCH_1):PWRGD_DRAMPWRGD_CPU1_GH_LVC1_R
  R128     2      B  Q_RES        I7
  R153     1      A  Q_RES       I56
  U1     CW45  DDR67_DRAM_PWR_OK  SOCKET4677_AZIFS054P001C01  I29

PWRGD_DRAMPWRGD_CPU1_GH_R_LVC1   @S9S_MB_2U_LIB.S9S_MB_2U(SCH_1):PWRGD_DRAMPWRGD_CPU1_GH_R_LVC1
  R128     1      A  Q_RES        I7
  R1389    1      A  Q_RES       I19
  U122   V17  DIFFIO_RX_B28P  10M04SAU324I7G  I93

PWRGD_DSW_PWROK   @S9S_MB_2U_LIB.S9S_MB_2U(SCH_1):PWRGD_DSW_PWROK
  C1319    1      A  Q_CAP       I47
  R1693    2      B  Q_RES       I50
  R1694    2      B  Q_RES       I46
  R1695    1      A  Q_RES       I45
  U4     BE8  DSW_PWROK  EMMITSBURG_REV0P9  I36

PWRGD_DSW_PWROK_R1   @S9S_MB_2U_LIB.S9S_MB_2U(SCH_1):PWRGD_DSW_PWROK_R1
  C1318    1      A  Q_CAP       I54
  R1691    2      B  Q_RES       I59
  R1692    1      A  Q_RES       I56
  U94      4  ENOUT  ADM1086AKSZREEL7   I1
  U95      2      A  SN74LVC1G07DCKR  I41
  U117     4  SENSE_OUT  TPS3897PDRYR  I37

PWRGD_DSW_PWROK_R2   @S9S_MB_2U_LIB.S9S_MB_2U(SCH_1):PWRGD_DSW_PWROK_R2
  R1693    1      A  Q_RES       I50
  U95      4      Y  SN74LVC1G07DCKR  I41

PWRGD_FAIL_CPU0_AB   @S9S_MB_2U_LIB.S9S_MB_2U(SCH_1):PWRGD_FAIL_CPU0_AB
  R877     2      B  Q_RES       I34
  R878     2      B  Q_RES       I59
  R879     2      B  Q_RES       I63
  R880     2      B  Q_RES       I61
  R940     2      B  Q_RES       I145
  U122    D4  DIFFIO_RX_L1N||ADC1IN1  10M04SAU324I7G  I93

PWRGD_FAIL_CPU0_CD   @S9S_MB_2U_LIB.S9S_MB_2U(SCH_1):PWRGD_FAIL_CPU0_CD
  R881     2      B  Q_RES       I71
  R882     2      B  Q_RES       I72
  R883     2      B  Q_RES       I73
  R884     2      B  Q_RES       I74
  R941     2      B  Q_RES       I146
  U122    C2  DIFFIO_RX_L2N||ADC1IN9  10M04SAU324I7G  I93

PWRGD_FAIL_CPU0_EF   @S9S_MB_2U_LIB.S9S_MB_2U(SCH_1):PWRGD_FAIL_CPU0_EF
  R885     2      B  Q_RES       I81
  R886     2      B  Q_RES       I82
  R887     2      B  Q_RES       I83
  R888     2      B  Q_RES       I84
  R942     2      B  Q_RES       I147
  U122    E4  DIFFIO_RX_L1P||ADC1IN2  10M04SAU324I7G  I93

PWRGD_FAIL_CPU0_GH   @S9S_MB_2U_LIB.S9S_MB_2U(SCH_1):PWRGD_FAIL_CPU0_GH
  R889     2      B  Q_RES       I86
  R890     2      B  Q_RES       I85
  R891     2      B  Q_RES       I87
  R892     2      B  Q_RES       I76
  R943     2      B  Q_RES       I148
  U122    D2  DIFFIO_RX_L2P||ADC1IN16  10M04SAU324I7G  I93

PWRGD_FAIL_CPU1_AB   @S9S_MB_2U_LIB.S9S_MB_2U(SCH_1):PWRGD_FAIL_CPU1_AB
  R893     2      B  Q_RES       I104
  R894     2      B  Q_RES       I105
  R895     2      B  Q_RES       I106
  R896     2      B  Q_RES       I107
  R944     2      B  Q_RES       I153
  U122    G6  DIFFIO_RX_L3N||ADC1IN3  10M04SAU324I7G  I93

PWRGD_FAIL_CPU1_CD   @S9S_MB_2U_LIB.S9S_MB_2U(SCH_1):PWRGD_FAIL_CPU1_CD
  R897     2      B  Q_RES       I109
  R898     2      B  Q_RES       I108
  R899     2      B  Q_RES       I110
  R900     2      B  Q_RES       I111
  R945     2      B  Q_RES       I154
  U122    B1  DIFFIO_RX_L4N||ADC1IN11  10M04SAU324I7G  I93

PWRGD_FAIL_CPU1_EF   @S9S_MB_2U_LIB.S9S_MB_2U(SCH_1):PWRGD_FAIL_CPU1_EF
  R901     2      B  Q_RES       I112
  R902     2      B  Q_RES       I113
  R903     2      B  Q_RES       I114
  R904     2      B  Q_RES       I115
  R946     2      B  Q_RES       I156
  U122    H6  DIFFIO_RX_L3P||ADC1IN4  10M04SAU324I7G  I93

PWRGD_FAIL_CPU1_GH   @S9S_MB_2U_LIB.S9S_MB_2U(SCH_1):PWRGD_FAIL_CPU1_GH
  R905     2      B  Q_RES       I116
  R906     2      B  Q_RES       I117
  R907     2      B  Q_RES       I118
  R908     2      B  Q_RES       I119
  R947     2      B  Q_RES       I157
  U122    C1  DIFFIO_RX_L4P||ADC1IN12  10M04SAU324I7G  I93

PWRGD_HSC_P12V_PWROK   @S9S_MB_2U_LIB.S9S_MB_2U(SCH_1):PWRGD_HSC_P12V_PWROK
  J44     17     17  CONN24_52SH90245BRD  I125
  R955     1      A  Q_RES       I208
  R2186    1      A  Q_RES       I213

PWRGD_P1V05_PCH_AUX   @S9S_MB_2U_LIB.S9S_MB_2U(SCH_1):PWRGD_P1V05_PCH_AUX
  PR1650    2      B  Q_RES       I39
  U122    N4  DIFFIO_RX_L27N||PLL_L_CLKOUTN  10M04SAU324I7G  I139

PWRGD_P1V05_PCH_AUX_R   @S9S_MB_2U_LIB.S9S_MB_2U(SCH_1):PWRGD_P1V05_PCH_AUX_R
  PR186    2      B  Q_RES       I38
  PR1650    1      A  Q_RES       I39
  PR2390    1      A  Q_RES       I40
  PU73     9  PGOOD  MPQ8633BGLEC838Z  I34

PWRGD_P1V8_PCH_AUX   @S9S_MB_2U_LIB.S9S_MB_2U(SCH_1):PWRGD_P1V8_PCH_AUX
  PC2287    1      A  Q_CAP       I36
  PR1651    2      B  Q_RES       I35
  R1444    1      A  Q_RES       I54

PWRGD_P1V8_PCH_AUX_PLD   @S9S_MB_2U_LIB.S9S_MB_2U(SCH_1):PWRGD_P1V8_PCH_AUX_PLD
  R1444    2      B  Q_RES       I54
  U122    P4  DIFFIO_RX_L27P||PLL_L_CLKOUTP  10M04SAU324I7G  I139

PWRGD_P1V8_PCH_AUX_R   @S9S_MB_2U_LIB.S9S_MB_2U(SCH_1):PWRGD_P1V8_PCH_AUX_R
  PR1302    2      B  Q_RES       I33
  PR1651    1      A  Q_RES       I35
  PU74    13     PG  NB695GDZ    I20

PWRGD_P3V3      @S9S_MB_2U_LIB.S9S_MB_2U(SCH_1):PWRGD_P3V3
  R1682    2      B  Q_RES       I88
  R1698    1      A  Q_RES       I89
  R1706    2      B  Q_RES       I68
  U122    U2  DIFFIO_RX_L28P  10M04SAU324I7G  I93

PWRGD_P3V3_AUX   @S9S_MB_2U_LIB.S9S_MB_2U(SCH_1):PWRGD_P3V3_AUX
  PR73     2      B  Q_RES       I31
  PU9      2  PGOOD  NCP3284MNTXG  I23
  R1919    1      A  Q_RES       I127
  R1950    2      B  Q_RES       I35

PWRGD_P3V3_AUX_PLD   @S9S_MB_2U_LIB.S9S_MB_2U(SCH_1):PWRGD_P3V3_AUX_PLD
  R1919    2      B  Q_RES       I127
  U122    M1  DIFFIO_RX_L19N  10M04SAU324I7G  I93

PWRGD_P3V3_R    @S9S_MB_2U_LIB.S9S_MB_2U(SCH_1):PWRGD_P3V3_R
  R1682    1      A  Q_RES       I88
  U79      8     PG  SLG55221120010VTR  I62

PWRGD_P5V       @S9S_MB_2U_LIB.S9S_MB_2U(SCH_1):PWRGD_P5V
  R1655    2      B  Q_RES       I71
  U79      2     ON  SLG55221120010VTR  I62
  U99      1  RESET#  RT9818C44GV  I70

PWRGD_P5V_AUX   @S9S_MB_2U_LIB.S9S_MB_2U(SCH_1):PWRGD_P5V_AUX
  PR90     2      B  Q_RES       I27
  PU9     27     EN  NCP3284MNTXG  I23
  PU181    9  PGOOD  MPQ8633BGLEC838Z  I19

PWRGD_PCH_PWROK   @S9S_MB_2U_LIB.S9S_MB_2U(SCH_1):PWRGD_PCH_PWROK
  R1403    1      A  Q_RES       I24
  R1442    2      B  Q_RES       I48
  U4     BE4  PCH_PWROK  EMMITSBURG_REV0P9  I36

PWRGD_PCH_PWROK_R   @S9S_MB_2U_LIB.S9S_MB_2U(SCH_1):PWRGD_PCH_PWROK_R
  C1211    1      A  Q_CAP       I240
  R1442    1      A  Q_RES       I48
  U122   H11  DIFFIO_RX_R26P||DPCLK3  10M04SAU324I7G  I139

PWRGD_PLT_AUX_CPU0_LVT3   @S9S_MB_2U_LIB.S9S_MB_2U(SCH_1):PWRGD_PLT_AUX_CPU0_LVT3
  R67      2      B  Q_RES       I12
  R69      1      A  Q_RES       I16
  U2     CV20  PLT_AUX_PWRGOOD  SOCKET4677_AZIFS054P001C01   I1

PWRGD_PLT_AUX_CPU0_LVT3_R   @S9S_MB_2U_LIB.S9S_MB_2U(SCH_1):PWRGD_PLT_AUX_CPU0_LVT3_R
  R67      1      A  Q_RES       I12
  U122   N15  DIFFIO_RX_R5P  10M04SAU324I7G  I155

PWRGD_PLT_AUX_CPU1_LVT3   @S9S_MB_2U_LIB.S9S_MB_2U(SCH_1):PWRGD_PLT_AUX_CPU1_LVT3
  R68      2      B  Q_RES       I13
  R70      1      A  Q_RES       I17
  U1     CV20  PLT_AUX_PWRGOOD  SOCKET4677_AZIFS054P001C01   I5

PWRGD_PLT_AUX_CPU1_LVT3_R   @S9S_MB_2U_LIB.S9S_MB_2U(SCH_1):PWRGD_PLT_AUX_CPU1_LVT3_R
  R68      1      A  Q_RES       I13
  U122   N16  DIFFIO_RX_R6P  10M04SAU324I7G  I155

PWRGD_PS_PWROK   @S9S_MB_2U_LIB.S9S_MB_2U(SCH_1):PWRGD_PS_PWROK
  R1816    1      A  Q_RES       I605
  R2186    2      B  Q_RES       I213

PWRGD_PS_PWROK_PLD   @S9S_MB_2U_LIB.S9S_MB_2U(SCH_1):PWRGD_PS_PWROK_PLD
  R955     2      B  Q_RES       I208
  R1446    1      A  Q_RES       I61

PWRGD_PS_PWROK_PLD_R   @S9S_MB_2U_LIB.S9S_MB_2U(SCH_1):PWRGD_PS_PWROK_PLD_R
  R1446    2      B  Q_RES       I61
  U122   N14  DIFFIO_RX_R1P  10M04SAU324I7G  I93

PWRGD_PS_PWROK_R   @S9S_MB_2U_LIB.S9S_MB_2U(SCH_1):PWRGD_PS_PWROK_R
  J41    A44  PERN8  SCONN168_623403212  I115
  R1816    2      B  Q_RES       I605

PWRGD_PVCCD_HV_CPU0   @S9S_MB_2U_LIB.S9S_MB_2U(SCH_1):PWRGD_PVCCD_HV_CPU0
  PR362    1      A  Q_RES       I44
  U122    M2  DIFFIO_RX_L19P  10M04SAU324I7G  I93

PWRGD_PVCCD_HV_CPU0_R   @S9S_MB_2U_LIB.S9S_MB_2U(SCH_1):PWRGD_PVCCD_HV_CPU0_R
  PC626    1      A  Q_CAP       I45
  PR361    2      B  Q_RES       I43
  PR362    2      B  Q_RES       I44
  PU35    12    PG0  ISL69260IRAZT  I51

PWRGD_PVCCD_HV_CPU1   @S9S_MB_2U_LIB.S9S_MB_2U(SCH_1):PWRGD_PVCCD_HV_CPU1
  PR207    1      A  Q_RES       I232
  U122    M3  DIFFIO_RX_L18P||CLK0P  10M04SAU324I7G  I139

PWRGD_PVCCD_HV_CPU1_R   @S9S_MB_2U_LIB.S9S_MB_2U(SCH_1):PWRGD_PVCCD_HV_CPU1_R
  PC388    1      A  Q_CAP       I253
  PR206    2      B  Q_RES       I233
  PR207    2      B  Q_RES       I232
  PU18    12    PG0  ISL69260IRAZT  I243

PWRGD_PVCCFA_EHV_CPU0   @S9S_MB_2U_LIB.S9S_MB_2U(SCH_1):PWRGD_PVCCFA_EHV_CPU0
  PR118    1      A  Q_RES       I30
  U122    M4  DIFFIO_RX_L22N||DPCLK0  10M04SAU324I7G  I139

PWRGD_PVCCFA_EHV_CPU0_R   @S9S_MB_2U_LIB.S9S_MB_2U(SCH_1):PWRGD_PVCCFA_EHV_CPU0_R
  PC220    1      A  Q_CAP       I38
  PR117    2      B  Q_RES       I31
  PR118    2      B  Q_RES       I30
  PU5     16    PG1  ISL69260IRAZT  I51

PWRGD_PVCCFA_EHV_CPU1   @S9S_MB_2U_LIB.S9S_MB_2U(SCH_1):PWRGD_PVCCFA_EHV_CPU1
  PR271    1      A  Q_RES       I16
  U122    K8  DIFFIO_RX_L20N||CLK1N  10M04SAU324I7G  I139

PWRGD_PVCCFA_EHV_CPU1_R   @S9S_MB_2U_LIB.S9S_MB_2U(SCH_1):PWRGD_PVCCFA_EHV_CPU1_R
  PC473    1      A  Q_CAP       I58
  PR270    2      B  Q_RES       I17
  PR271    2      B  Q_RES       I16
  PU22    16    PG1  ISL69260IRAZT  I61

PWRGD_PVCCFA_EHV_FIVRA_CPU0   @S9S_MB_2U_LIB.S9S_MB_2U(SCH_1):PWRGD_PVCCFA_EHV_FIVRA_CPU0
  PR336    1      A  Q_RES       I39
  U122    N1  DIFFIO_RX_L21N  10M04SAU324I7G  I93

PWRGD_PVCCFA_EHV_FIVRA_CPU0_R   @S9S_MB_2U_LIB.S9S_MB_2U(SCH_1):PWRGD_PVCCFA_EHV_FIVRA_CPU0_R
  PC593    1      A  Q_CAP       I42
  PR335    2      B  Q_RES       I40
  PR336    2      B  Q_RES       I39
  PU14    20    PG1  RAA229126GNPHA0  I48

PWRGD_PVCCFA_EHV_FIVRA_CPU1   @S9S_MB_2U_LIB.S9S_MB_2U(SCH_1):PWRGD_PVCCFA_EHV_FIVRA_CPU1
  PR233    1      A  Q_RES       I202
  U122    L8  DIFFIO_RX_L20P||CLK1P  10M04SAU324I7G  I139

PWRGD_PVCCFA_EHV_FIVRA_CPU1_R   @S9S_MB_2U_LIB.S9S_MB_2U(SCH_1):PWRGD_PVCCFA_EHV_FIVRA_CPU1_R
  PC421    1      A  Q_CAP       I205
  PR232    2      B  Q_RES       I203
  PR233    2      B  Q_RES       I202
  PU29    20    PG1  RAA229126GNPHA0  I211

PWRGD_PVCCINFAON_CPU0   @S9S_MB_2U_LIB.S9S_MB_2U(SCH_1):PWRGD_PVCCINFAON_CPU0
  PR110    1      A  Q_RES       I67
  U122    N3  DIFFIO_RX_L22P||DPCLK1  10M04SAU324I7G  I139

PWRGD_PVCCINFAON_CPU0_R   @S9S_MB_2U_LIB.S9S_MB_2U(SCH_1):PWRGD_PVCCINFAON_CPU0_R
  PC218    1      A  Q_CAP       I69
  PR109    2      B  Q_RES       I68
  PR110    2      B  Q_RES       I67
  PU5     12    PG0  ISL69260IRAZT  I51

PWRGD_PVCCINFAON_CPU1   @S9S_MB_2U_LIB.S9S_MB_2U(SCH_1):PWRGD_PVCCINFAON_CPU1
  PR263    1      A  Q_RES       I50
  U122    R2   IO_2  10M04SAU324I7G  I155

PWRGD_PVCCINFAON_CPU1_R   @S9S_MB_2U_LIB.S9S_MB_2U(SCH_1):PWRGD_PVCCINFAON_CPU1_R
  PC471    1      A  Q_CAP       I76
  PR262    2      B  Q_RES       I52
  PR263    2      B  Q_RES       I50
  PU22    12    PG0  ISL69260IRAZT  I61

PWRGD_PVCCIN_CPU0   @S9S_MB_2U_LIB.S9S_MB_2U(SCH_1):PWRGD_PVCCIN_CPU0
  PR161    1      A  Q_RES       I70
  U122    P1  DIFFIO_RX_L21P  10M04SAU324I7G  I93

PWRGD_PVCCIN_CPU0_R   @S9S_MB_2U_LIB.S9S_MB_2U(SCH_1):PWRGD_PVCCIN_CPU0_R
  PC333    1      A  Q_CAP       I72
  PR160    2      B  Q_RES       I71
  PR161    2      B  Q_RES       I70
  PU14    16    PG0  RAA229126GNPHA0  I48

PWRGD_PVCCIN_CPU1   @S9S_MB_2U_LIB.S9S_MB_2U(SCH_1):PWRGD_PVCCIN_CPU1
  PR308    1      A  Q_RES       I197
  U122    R1  IO_2||VREFB2N0  10M04SAU324I7G  I139

PWRGD_PVCCIN_CPU1_R   @S9S_MB_2U_LIB.S9S_MB_2U(SCH_1):PWRGD_PVCCIN_CPU1_R
  PC551    1      A  Q_CAP       I244
  PR307    2      B  Q_RES       I198
  PR308    2      B  Q_RES       I197
  PU29    16    PG0  RAA229126GNPHA0  I211

PWRGD_PVNN_MAIN_CPU0   @S9S_MB_2U_LIB.S9S_MB_2U(SCH_1):PWRGD_PVNN_MAIN_CPU0
  C1296    1      A  Q_CAP       I178
  R1652    2      B  Q_RES       I173
  U17      1    1OE  74CBTLV3126PW  I80
  U17      4    2OE  74CBTLV3126PW  I80
  U17     10    3OE  74CBTLV3126PW  I80
  U17     13    4OE  74CBTLV3126PW  I80
  U18      1    1OE  74CBTLV3126PW  I129
  U18      4    2OE  74CBTLV3126PW  I129
  U18     10    3OE  74CBTLV3126PW  I129
  U18     13    4OE  74CBTLV3126PW  I129
  U122    R3  DIFFIO_RX_L23N  10M04SAU324I7G  I93

PWRGD_PVNN_MAIN_CPU0_R   @S9S_MB_2U_LIB.S9S_MB_2U(SCH_1):PWRGD_PVNN_MAIN_CPU0_R
  PR1317    2      B  Q_RES       I174
  PU81     9  PGOOD  MPQ8626GDZ  I190
  R1652    1      A  Q_RES       I173

PWRGD_PVNN_MAIN_CPU1   @S9S_MB_2U_LIB.S9S_MB_2U(SCH_1):PWRGD_PVNN_MAIN_CPU1
  C1297    1      A  Q_CAP       I186
  R2387    2      B  Q_RES       I183
  U122    P2  DIFFIO_RX_L24N  10M04SAU324I7G  I93

PWRGD_PVNN_MAIN_CPU1_R   @S9S_MB_2U_LIB.S9S_MB_2U(SCH_1):PWRGD_PVNN_MAIN_CPU1_R
  PR1320    2      B  Q_RES       I187
  PU82     9  PGOOD  MPQ8626GDZ  I198
  R2387    1      A  Q_RES       I183

PWRGD_PVNN_PCH_AUX   @S9S_MB_2U_LIB.S9S_MB_2U(SCH_1):PWRGD_PVNN_PCH_AUX
  PR2390    2      B  Q_RES       I40
  U122    T3  DIFFIO_RX_L23P  10M04SAU324I7G  I93

PWRGD_PVPP_HBM_CPU0   @S9S_MB_2U_LIB.S9S_MB_2U(SCH_1):PWRGD_PVPP_HBM_CPU0
  R2334    2      B  Q_RES       I28
  U122    P3  DIFFIO_RX_L24P  10M04SAU324I7G  I93

PWRGD_PVPP_HBM_CPU0_R   @S9S_MB_2U_LIB.S9S_MB_2U(SCH_1):PWRGD_PVPP_HBM_CPU0_R
  C1301    1      A  Q_CAP       I27
  PR1309    2      B  Q_RES       I25
  PU79     9  PGOOD  MPQ8633AGLEC807Z  I13
  R2334    1      A  Q_RES       I28

PWRGD_PVPP_HBM_CPU1   @S9S_MB_2U_LIB.S9S_MB_2U(SCH_1):PWRGD_PVPP_HBM_CPU1
  R2380    2      B  Q_RES       I40
  U122    L7  DIFFIO_RX_L25N  10M04SAU324I7G  I93

PWRGD_PVPP_HBM_CPU1_R   @S9S_MB_2U_LIB.S9S_MB_2U(SCH_1):PWRGD_PVPP_HBM_CPU1_R
  C2446    1      A  Q_CAP       I39
  PR1313    2      B  Q_RES       I23
  PU80     9  PGOOD  MPQ8633AGLEC807Z  I15
  R2380    1      A  Q_RES       I40

PWRGD_S0_PWROK_CPU0_LVC1   @S9S_MB_2U_LIB.S9S_MB_2U(SCH_1):PWRGD_S0_PWROK_CPU0_LVC1
  R1218    1      A  Q_RES       I26
  U2     CH71  S0_PWROK  SOCKET4677_AZIFS054P001C01   I1

PWRGD_S0_PWROK_CPU0_LVC1_R   @S9S_MB_2U_LIB.S9S_MB_2U(SCH_1):PWRGD_S0_PWROK_CPU0_LVC1_R
  R9       1      A  Q_RES       I57
  R1218    2      B  Q_RES       I26
  U122   U11  DIFFIO_RX_B17P  10M04SAU324I7G  I93

PWRGD_S0_PWROK_CPU1_LVC1   @S9S_MB_2U_LIB.S9S_MB_2U(SCH_1):PWRGD_S0_PWROK_CPU1_LVC1
  R1219    1      A  Q_RES       I27
  U1     CH71  S0_PWROK  SOCKET4677_AZIFS054P001C01   I5

PWRGD_S0_PWROK_CPU1_LVC1_R   @S9S_MB_2U_LIB.S9S_MB_2U(SCH_1):PWRGD_S0_PWROK_CPU1_LVC1_R
  R316     1      A  Q_RES       I59
  R1219    2      B  Q_RES       I27
  U122    U5  DIFFIO_RX_B6N  10M04SAU324I7G  I93

PWRGD_SYS_PWROK   @S9S_MB_2U_LIB.S9S_MB_2U(SCH_1):PWRGD_SYS_PWROK
  J41    A48  PERP9  SCONN168_623403212  I115
  R1402    1      A  Q_RES       I23
  R1423    2      B  Q_RES       I44
  U4     AL10  SYS_PWROK  EMMITSBURG_REV0P9  I36

PWRGD_SYS_PWROK_R   @S9S_MB_2U_LIB.S9S_MB_2U(SCH_1):PWRGD_SYS_PWROK_R
  C1209    1      A  Q_CAP       I236
  R1423    1      A  Q_RES       I44
  U122   H12  DIFFIO_RX_R26N||DPCLK2  10M04SAU324I7G  I139

RISER1_CLK0_EN_N   @S9S_MB_2U_LIB.S9S_MB_2U(SCH_1):RISER1_CLK0_EN_N
  J55    B11  SIGNAL_B11  SCONN140_G64V3431BHR  I150
  R2173    2      B  Q_RES       I133

RISER1_CLK1_EN_N   @S9S_MB_2U_LIB.S9S_MB_2U(SCH_1):RISER1_CLK1_EN_N
  J55    B12  SIGNAL_B12  SCONN140_G64V3431BHR  I150
  R2174    2      B  Q_RES       I134

RISER1_TYPE_ID   @S9S_MB_2U_LIB.S9S_MB_2U(SCH_1):RISER1_TYPE_ID
  J55     A9  SIGNAL_A9  SCONN140_G64V3431BHR  I150
  R2167    2      B  Q_RES        I1

RISER2_CLK2_EN_N   @S9S_MB_2U_LIB.S9S_MB_2U(SCH_1):RISER2_CLK2_EN_N
  J89    A31    A31  SCONN280_ME1028040102011  I239
  R1576    2      B  Q_RES       I304
  U13    A26   OE3#  9SQ440NQQI8  I180

RISER2_CLK3_EN_N   @S9S_MB_2U_LIB.S9S_MB_2U(SCH_1):RISER2_CLK3_EN_N
  J89    B27    B27  SCONN280_ME1028040102011  I239
  R1575    2      B  Q_RES       I308
  U13    B19   OE4#  9SQ440NQQI8  I180

RISER2_TYPE_ID   @S9S_MB_2U_LIB.S9S_MB_2U(SCH_1):RISER2_TYPE_ID
  J89    B31    B31  SCONN280_ME1028040102011  I239
  R388     2      B  Q_RES       I108
  U4     AA7  GPP_M_2  EMMITSBURG_REV0P9  I22

RISER2_USB2_4_DN   @S9S_MB_2U_LIB.S9S_MB_2U(SCH_1):RISER2_USB2_4_DN
  J89    B20    B20  SCONN280_ME1028040102011  I239
  R2130    2      B  Q_RES       I322

RISER2_USB2_4_DP   @S9S_MB_2U_LIB.S9S_MB_2U(SCH_1):RISER2_USB2_4_DP
  J89    B21    B21  SCONN280_ME1028040102011  I239
  R2131    2      B  Q_RES       I323

RISER3_CLK4_EN_N   @S9S_MB_2U_LIB.S9S_MB_2U(SCH_1):RISER3_CLK4_EN_N
  J57    B11  SIGNAL_B11  SCONN140_G64V3431BHR  I242
  R1579    2      B  Q_RES       I343
  U13    B15   OE5#  9SQ440NQQI8  I180

RISER3_CLK5_EN_N   @S9S_MB_2U_LIB.S9S_MB_2U(SCH_1):RISER3_CLK5_EN_N
  J57    B12  SIGNAL_B12  SCONN140_G64V3431BHR  I242
  R1580    2      B  Q_RES       I341
  U13    B14   OE6#  9SQ440NQQI8  I180

RISER3_TYPE_ID   @S9S_MB_2U_LIB.S9S_MB_2U(SCH_1):RISER3_TYPE_ID
  J57     A9  SIGNAL_A9  SCONN140_G64V3431BHR  I242
  R391     2      B  Q_RES       I108
  U4      W7  GPP_M_4  EMMITSBURG_REV0P9  I22

RMII_BMC_OCP_RX_ER   @S9S_MB_2U_LIB.S9S_MB_2U(SCH_1):RMII_BMC_OCP_RX_ER
  J41    B23  PETN2  SCONN168_623403212  I115
  R1356    1      A  Q_RES       I96

RMII_BMC_OCP_TXD_0   @S9S_MB_2U_LIB.S9S_MB_2U(SCH_1):RMII_BMC_OCP_TXD_0
  J41    B21  PETP1  SCONN168_623403212  I115
  R1295    2      B  Q_RES       I103
  R1354    1      A  Q_RES       I91

RMII_BMC_OCP_TXD_1   @S9S_MB_2U_LIB.S9S_MB_2U(SCH_1):RMII_BMC_OCP_TXD_1
  J41    B22  GND_B22  SCONN168_623403212  I115
  R1296    2      B  Q_RES       I104
  R1355    1      A  Q_RES       I93

RMII_BMC_OCP_TX_EN   @S9S_MB_2U_LIB.S9S_MB_2U(SCH_1):RMII_BMC_OCP_TX_EN
  J41    B20  PETN1  SCONN168_623403212  I115
  R1294    2      B  Q_RES       I102
  R1353    1      A  Q_RES       I92

RMII_OCP_BMC_CRSDV   @S9S_MB_2U_LIB.S9S_MB_2U(SCH_1):RMII_OCP_BMC_CRSDV
  J41    B19  GND_B19  SCONN168_623403212  I115
  R1291    2      B  Q_RES       I99
  R1350    1      A  Q_RES       I82

RMII_OCP_BMC_RXD_0   @S9S_MB_2U_LIB.S9S_MB_2U(SCH_1):RMII_OCP_BMC_RXD_0
  J41    B24  PETP2  SCONN168_623403212  I115
  R1292    2      B  Q_RES       I100
  R1351    1      A  Q_RES       I86

RMII_OCP_BMC_RXD_1   @S9S_MB_2U_LIB.S9S_MB_2U(SCH_1):RMII_OCP_BMC_RXD_1
  J41    B25  GND_B25  SCONN168_623403212  I115
  R1293    2      B  Q_RES       I101
  R1352    1      A  Q_RES       I87

ROT_P1_RST_IND_N   @S9S_MB_2U_LIB.S9S_MB_2U(SCH_1):ROT_P1_RST_IND_N
  J41    A53  PERN11  SCONN168_623403212  I115
  R1798    2      B  Q_RES       I615

ROT_P1_RST_IND_N_R   @S9S_MB_2U_LIB.S9S_MB_2U(SCH_1):ROT_P1_RST_IND_N_R
  R1798    1      A  Q_RES       I615
  U122    F2  DIFFIO_RX_L7P||ADC1IN8  10M04SAU324I7G  I93

RST_CPU0_BUF_R_N   @S9S_MB_2U_LIB.S9S_MB_2U(SCH_1):RST_CPU0_BUF_R_N
  R171     2      B  Q_RES       I52
  R185     1      A  Q_RES       I60
  R186     1      A  Q_RES       I61

RST_CPU0_DRAM_AB_N   @S9S_MB_2U_LIB.S9S_MB_2U(SCH_1):RST_CPU0_DRAM_AB_N
  R851     1      A  Q_RES       I12
  R932     1      A  Q_RES       I80
  U2     AU50  DDR01_RESET_N  SOCKET4677_AZIFS054P001C01  I57

RST_CPU0_DRAM_AB_PLD_N   @S9S_MB_2U_LIB.S9S_MB_2U(SCH_1):RST_CPU0_DRAM_AB_PLD_N
  R851     2      B  Q_RES       I12
  U122   U12  DIFFIO_RX_B19N  10M04SAU324I7G  I93

RST_CPU0_DRAM_CD_N   @S9S_MB_2U_LIB.S9S_MB_2U(SCH_1):RST_CPU0_DRAM_CD_N
  R852     1      A  Q_RES       I11
  R934     1      A  Q_RES       I79
  U2     AV51  DDR23_RESET_N  SOCKET4677_AZIFS054P001C01  I57

RST_CPU0_DRAM_CD_PLD_N   @S9S_MB_2U_LIB.S9S_MB_2U(SCH_1):RST_CPU0_DRAM_CD_PLD_N
  R852     2      B  Q_RES       I11
  U122   R13  DIFFIO_TX_RX_B23P  10M04SAU324I7G  I155

RST_CPU0_DRAM_EF_N   @S9S_MB_2U_LIB.S9S_MB_2U(SCH_1):RST_CPU0_DRAM_EF_N
  R853     1      A  Q_RES       I10
  R936     1      A  Q_RES       I78
  U2     CY42  DDR45_RESET_N  SOCKET4677_AZIFS054P001C01  I57

RST_CPU0_DRAM_EF_PLD_N   @S9S_MB_2U_LIB.S9S_MB_2U(SCH_1):RST_CPU0_DRAM_EF_PLD_N
  R853     2      B  Q_RES       I10
  U122   T14  DIFFIO_RX_B24P  10M04SAU324I7G  I93

RST_CPU0_DRAM_GH_N   @S9S_MB_2U_LIB.S9S_MB_2U(SCH_1):RST_CPU0_DRAM_GH_N
  R854     1      A  Q_RES        I9
  R938     1      A  Q_RES       I77
  U2     CY55  DDR67_RESET_N  SOCKET4677_AZIFS054P001C01  I57

RST_CPU0_DRAM_GH_PLD_N   @S9S_MB_2U_LIB.S9S_MB_2U(SCH_1):RST_CPU0_DRAM_GH_PLD_N
  R854     2      B  Q_RES        I9
  U122   R12  DIFFIO_TX_RX_B23N  10M04SAU324I7G  I155

RST_CPU0_LVC1_N   @S9S_MB_2U_LIB.S9S_MB_2U(SCH_1):RST_CPU0_LVC1_N
  R186     2      B  Q_RES       I61
  U2     BH61  RESET_N  SOCKET4677_AZIFS054P001C01   I1

RST_CPU0_LVC1_R_N   @S9S_MB_2U_LIB.S9S_MB_2U(SCH_1):RST_CPU0_LVC1_R_N
  R171     1      A  Q_RES       I52
  R1415    1      A  Q_RES        I4
  U122    U6  IO_3||VREFB3N0  10M04SAU324I7G  I139

RST_CPU1_BUF_R_N   @S9S_MB_2U_LIB.S9S_MB_2U(SCH_1):RST_CPU1_BUF_R_N
  R132     2      B  Q_RES        I3
  R157     1      A  Q_RES       I24
  R158     1      A  Q_RES       I23

RST_CPU1_DRAM_AB_N   @S9S_MB_2U_LIB.S9S_MB_2U(SCH_1):RST_CPU1_DRAM_AB_N
  R859     1      A  Q_RES       I50
  R933     1      A  Q_RES       I82
  U1     AU50  DDR01_RESET_N  SOCKET4677_AZIFS054P001C01  I51

RST_CPU1_DRAM_AB_PLD_N   @S9S_MB_2U_LIB.S9S_MB_2U(SCH_1):RST_CPU1_DRAM_AB_PLD_N
  R859     2      B  Q_RES       I50
  U122   T13  DIFFIO_RX_B24N  10M04SAU324I7G  I93

RST_CPU1_DRAM_CD_N   @S9S_MB_2U_LIB.S9S_MB_2U(SCH_1):RST_CPU1_DRAM_CD_N
  R860     1      A  Q_RES       I51
  R935     1      A  Q_RES       I86
  U1     AV51  DDR23_RESET_N  SOCKET4677_AZIFS054P001C01  I51

RST_CPU1_DRAM_CD_PLD_N   @S9S_MB_2U_LIB.S9S_MB_2U(SCH_1):RST_CPU1_DRAM_CD_PLD_N
  R860     2      B  Q_RES       I51
  U122   R14  DIFFIO_TX_RX_B25N  10M04SAU324I7G  I155

RST_CPU1_DRAM_EF_N   @S9S_MB_2U_LIB.S9S_MB_2U(SCH_1):RST_CPU1_DRAM_EF_N
  R861     1      A  Q_RES       I48
  R937     1      A  Q_RES       I85
  U1     CY42  DDR45_RESET_N  SOCKET4677_AZIFS054P001C01  I51

RST_CPU1_DRAM_EF_PLD_N   @S9S_MB_2U_LIB.S9S_MB_2U(SCH_1):RST_CPU1_DRAM_EF_PLD_N
  R861     2      B  Q_RES       I48
  U122   T15  DIFFIO_TX_RX_B25P  10M04SAU324I7G  I155

RST_CPU1_DRAM_GH_N   @S9S_MB_2U_LIB.S9S_MB_2U(SCH_1):RST_CPU1_DRAM_GH_N
  R862     1      A  Q_RES       I49
  R939     1      A  Q_RES       I83
  U1     CY55  DDR67_RESET_N  SOCKET4677_AZIFS054P001C01  I51

RST_CPU1_DRAM_GH_PLD_N   @S9S_MB_2U_LIB.S9S_MB_2U(SCH_1):RST_CPU1_DRAM_GH_PLD_N
  R862     2      B  Q_RES       I49
  U122   R10  DIFFIO_TX_RX_B21N  10M04SAU324I7G  I155

RST_CPU1_LVC1_N   @S9S_MB_2U_LIB.S9S_MB_2U(SCH_1):RST_CPU1_LVC1_N
  R158     2      B  Q_RES       I23
  U1     BH61  RESET_N  SOCKET4677_AZIFS054P001C01  I29

RST_CPU1_LVC1_R_N   @S9S_MB_2U_LIB.S9S_MB_2U(SCH_1):RST_CPU1_LVC1_R_N
  R132     1      A  Q_RES        I3
  R1416    1      A  Q_RES        I5
  U122    M9  DIFFIO_TX_RX_B14P  10M04SAU324I7G  I155

RST_ESPI_RESET_N   @S9S_MB_2U_LIB.S9S_MB_2U(SCH_1):RST_ESPI_RESET_N
  U4     BF17  GPPC_A_8_ESPI_RESET_N  EMMITSBURG_REV0P9  I93
  U61      1     B1  NC7SB3157   I39

RST_HP_OCP_V3_1_N   @S9S_MB_2U_LIB.S9S_MB_2U(SCH_1):RST_HP_OCP_V3_1_N
  U53      4      Y  SN74LVC1G08DBVR  I150
  U75      2      A  SN74LVC1G17DCKR   I1

RST_MB_STBY_N   @S9S_MB_2U_LIB.S9S_MB_2U(SCH_1):RST_MB_STBY_N
  J41    A46  GND_A46  SCONN168_623403212  I115
  R1206    2      B  Q_RES       I10

RST_MB_STBY_R_N   @S9S_MB_2U_LIB.S9S_MB_2U(SCH_1):RST_MB_STBY_R_N
  R1206    1      A  Q_RES       I10
  R1823    2      B  Q_RES       I152
  U122   C17  DIFFIO_RX_R34N  10M04SAU324I7G  I155

RST_M_AB_CPU0_FPGA_N   @S9S_MB_2U_LIB.S9S_MB_2U(SCH_1):RST_M_AB_CPU0_FPGA_N
  J1     207  RESET_N  SCONN288_ADR50001P013C01  I198
  J2     207  RESET_N  SCONN288_ADR50001P003C01  I177
  J3     207  RESET_N  SCONN288_ADR50001P013C01  I11
  J4     207  RESET_N  SCONN288_ADR50001P003C01  I23
  R836     2      B  Q_RES       I26
  R840     2      B  Q_RES       I119

RST_M_AB_CPU1_FPGA_N   @S9S_MB_2U_LIB.S9S_MB_2U(SCH_1):RST_M_AB_CPU1_FPGA_N
  J17    207  RESET_N  SCONN288_ADR50001P013C01  I12
  J18    207  RESET_N  SCONN288_ADR50001P003C01  I24
  J19    207  RESET_N  SCONN288_ADR50001P013C01  I25
  J20    207  RESET_N  SCONN288_ADR50001P003C01  I47
  R816     2      B  Q_RES       I37
  R820     2      B  Q_RES       I82

RST_M_CD_CPU0_FPGA_N   @S9S_MB_2U_LIB.S9S_MB_2U(SCH_1):RST_M_CD_CPU0_FPGA_N
  J5     207  RESET_N  SCONN288_ADR50001P013C01  I24
  J6     207  RESET_N  SCONN288_ADR50001P003C01  I46
  J7     207  RESET_N  SCONN288_ADR50001P013C01  I12
  J8     207  RESET_N  SCONN288_ADR50001P003C01  I50
  R837     2      B  Q_RES       I59
  R841     2      B  Q_RES       I121

RST_M_CD_CPU1_FPGA_N   @S9S_MB_2U_LIB.S9S_MB_2U(SCH_1):RST_M_CD_CPU1_FPGA_N
  J21    207  RESET_N  SCONN288_ADR50001P013C01  I13
  J22    207  RESET_N  SCONN288_ADR50001P003C01  I51
  J23    207  RESET_N  SCONN288_ADR50001P013C01  I25
  J24    207  RESET_N  SCONN288_ADR50001P003C01  I178
  R817     2      B  Q_RES       I26
  R821     2      B  Q_RES       I84

RST_M_EF_CPU0_FPGA_N   @S9S_MB_2U_LIB.S9S_MB_2U(SCH_1):RST_M_EF_CPU0_FPGA_N
  J9     207  RESET_N  SCONN288_ADR50001P013C01  I12
  J10    207  RESET_N  SCONN288_ADR50001P003C01  I13
  J11    207  RESET_N  SCONN288_ADR50001P013C01  I25
  J12    207  RESET_N  SCONN288_ADR50001P003C01  I24
  R838     2      B  Q_RES       I76
  R842     2      B  Q_RES       I123

RST_M_EF_CPU1_FPGA_N   @S9S_MB_2U_LIB.S9S_MB_2U(SCH_1):RST_M_EF_CPU1_FPGA_N
  J25    207  RESET_N  SCONN288_ADR50001P013C01  I180
  J26    207  RESET_N  SCONN288_ADR50001P003C01  I180
  J27    207  RESET_N  SCONN288_ADR50001P013C01  I179
  J28    207  RESET_N  SCONN288_ADR50001P003C01  I47
  R818     2      B  Q_RES       I22
  R822     2      B  Q_RES       I88

RST_M_GH_CPU0_FPGA_N   @S9S_MB_2U_LIB.S9S_MB_2U(SCH_1):RST_M_GH_CPU0_FPGA_N
  J13    207  RESET_N  SCONN288_ADR50001P013C01  I11
  J14    207  RESET_N  SCONN288_ADR50001P003C01  I47
  J15    207  RESET_N  SCONN288_ADR50001P013C01  I48
  J16    207  RESET_N  SCONN288_ADR50001P003C01   I6
  R835     2      B  Q_RES       I86
  R839     2      B  Q_RES       I125

RST_M_GH_CPU1_FPGA_N   @S9S_MB_2U_LIB.S9S_MB_2U(SCH_1):RST_M_GH_CPU1_FPGA_N
  J29    207  RESET_N  SCONN288_ADR50001P013C01  I179
  J30    207  RESET_N  SCONN288_ADR50001P003C01  I179
  J31    207  RESET_N  SCONN288_ADR50001P013C01  I180
  J32    207  RESET_N  SCONN288_ADR50001P003C01  I179
  R815     2      B  Q_RES       I11
  R819     2      B  Q_RES       I90

RST_OCP_V3_1_BUF_N   @S9S_MB_2U_LIB.S9S_MB_2U(SCH_1):RST_OCP_V3_1_BUF_N
  R419     1      A  Q_RES        I6
  R435     1      A  Q_RES        I8
  R1504    1      A  Q_RES       I10
  R1505    1      A  Q_RES       I13
  U75      4      Y  SN74LVC1G17DCKR   I1

RST_OCP_V3_1_N   @S9S_MB_2U_LIB.S9S_MB_2U(SCH_1):RST_OCP_V3_1_N
  R1514    2      B  Q_RES       I105
  U53      2      A  SN74LVC1G08DBVR  I150

RST_PCH_RSTBTN_R_N   @S9S_MB_2U_LIB.S9S_MB_2U(SCH_1):RST_PCH_RSTBTN_R_N
  R696     2      B  Q_RES       I63
  R697     2      B  Q_RES       I66
  U4     AJ10  SYS_RESET_N  EMMITSBURG_REV0P9  I36

RST_PCIE_BUF_E1S_0_PERST_N   @S9S_MB_2U_LIB.S9S_MB_2U(SCH_1):RST_PCIE_BUF_E1S_0_PERST_N
  R2113    1      A  Q_RES        I7
  U134     6     1Y  SN74LVC2G07DCKR   I1

RST_PCIE_BUF_E1S_1_PERST_N   @S9S_MB_2U_LIB.S9S_MB_2U(SCH_1):RST_PCIE_BUF_E1S_1_PERST_N
  R2114    1      A  Q_RES        I9
  U134     4     2Y  SN74LVC2G07DCKR   I1

RST_PCIE_BUF_E1S_2_PERST_N   @S9S_MB_2U_LIB.S9S_MB_2U(SCH_1):RST_PCIE_BUF_E1S_2_PERST_N
  R2115    1      A  Q_RES       I19
  U135     6     1Y  SN74LVC2G07DCKR  I24

RST_PCIE_BUF_E1S_3_PERST_N   @S9S_MB_2U_LIB.S9S_MB_2U(SCH_1):RST_PCIE_BUF_E1S_3_PERST_N
  R2116    1      A  Q_RES       I20
  U135     4     2Y  SN74LVC2G07DCKR  I24

RST_PCIE_CPU0_DEV_PERST_N   @S9S_MB_2U_LIB.S9S_MB_2U(SCH_1):RST_PCIE_CPU0_DEV_PERST_N
  R1417    1      A  Q_RES        I7
  R1512    1      A  Q_RES       I108
  R1513    1      A  Q_RES       I104
  R1514    1      A  Q_RES       I105
  R1515    1      A  Q_RES       I106
  R1516    1      A  Q_RES       I107
  R2050    1      A  Q_RES       I109
  R2129    1      A  Q_RES       I118
  U122   H15  DIFFIO_RX_R22N  10M04SAU324I7G  I93

RST_PCIE_CPU1_DEV_PERST_N   @S9S_MB_2U_LIB.S9S_MB_2U(SCH_1):RST_PCIE_CPU1_DEV_PERST_N
  R1418    1      A  Q_RES        I6
  R1518    1      A  Q_RES       I70
  R1519    1      A  Q_RES       I115
  R1520    1      A  Q_RES       I113
  R1521    1      A  Q_RES       I114
  U122   H16  DIFFIO_RX_R23N  10M04SAU324I7G  I93

RST_PCIE_E1S_0_PERST_N   @S9S_MB_2U_LIB.S9S_MB_2U(SCH_1):RST_PCIE_E1S_0_PERST_N
  J90    B10  PERST0#  CONN56_ME2005602311011  I105
  R2113    2      B  Q_RES        I7
  R2121    2      B  Q_RES       I11

RST_PCIE_E1S_1_PERST_N   @S9S_MB_2U_LIB.S9S_MB_2U(SCH_1):RST_PCIE_E1S_1_PERST_N
  J91    B10  PERST0#  CONN56_ME2005602311011  I123
  R2114    2      B  Q_RES        I9
  R2125    2      B  Q_RES       I12

RST_PCIE_E1S_2_PERST_N   @S9S_MB_2U_LIB.S9S_MB_2U(SCH_1):RST_PCIE_E1S_2_PERST_N
  J92    B10  PERST0#  CONN56_ME2005602311011  I105
  R2115    2      B  Q_RES       I19
  R2122    2      B  Q_RES       I18

RST_PCIE_E1S_3_PERST_N   @S9S_MB_2U_LIB.S9S_MB_2U(SCH_1):RST_PCIE_E1S_3_PERST_N
  J93    B10  PERST0#  CONN56_ME2005602311011  I123
  R2116    2      B  Q_RES       I20
  R2126    2      B  Q_RES       I17

RST_PCIE_E1S_PERST_N   @S9S_MB_2U_LIB.S9S_MB_2U(SCH_1):RST_PCIE_E1S_PERST_N
  R2129    2      B  Q_RES       I118
  U134     1     1A  SN74LVC2G07DCKR   I1
  U134     3     2A  SN74LVC2G07DCKR   I1
  U135     1     1A  SN74LVC2G07DCKR  I24
  U135     3     2A  SN74LVC2G07DCKR  I24

RST_PCIE_EDSFF1A_PERST_N   @S9S_MB_2U_LIB.S9S_MB_2U(SCH_1):RST_PCIE_EDSFF1A_PERST_N
  J62    B10  PERST0_N  SCONN84_123318136  I33
  R1515    2      B  Q_RES       I106

RST_PCIE_EDSFF1B_PERST_N   @S9S_MB_2U_LIB.S9S_MB_2U(SCH_1):RST_PCIE_EDSFF1B_PERST_N
  J87    B10  PERST0_N  SCONN84_123318136  I43
  R1516    2      B  Q_RES       I107

RST_PCIE_EDSFF2A_PERST_N   @S9S_MB_2U_LIB.S9S_MB_2U(SCH_1):RST_PCIE_EDSFF2A_PERST_N
  J33    B10  PERST0_N  SCONN84_123318136  I53
  R1512    2      B  Q_RES       I108

RST_PCIE_EDSFF2B_PERST_N   @S9S_MB_2U_LIB.S9S_MB_2U(SCH_1):RST_PCIE_EDSFF2B_PERST_N
  J34    B10  PERST0_N  SCONN84_123318136  I43
  R2050    2      B  Q_RES       I109

RST_PCIE_EDSFF3_PERST_N   @S9S_MB_2U_LIB.S9S_MB_2U(SCH_1):RST_PCIE_EDSFF3_PERST_N
  J35     A9  SIGNAL_A9  SCONN140_G64V3431BHR  I64
  R1520    2      B  Q_RES       I113

RST_PCIE_EDSFF4A_PERST_N   @S9S_MB_2U_LIB.S9S_MB_2U(SCH_1):RST_PCIE_EDSFF4A_PERST_N
  J88    B10  PERST0_N  SCONN84_123318136  I16
  R1521    2      B  Q_RES       I114

RST_PCIE_EDSFF4B_PERST_N   @S9S_MB_2U_LIB.S9S_MB_2U(SCH_1):RST_PCIE_EDSFF4B_PERST_N
  J61    B10  PERST0_N  SCONN84_123318136  I49
  R1519    2      B  Q_RES       I115

RST_PCIE_PCH_DEV_0_N   @S9S_MB_2U_LIB.S9S_MB_2U(SCH_1):RST_PCIE_PCH_DEV_0_N
  J59     50  PERST#  SCONN75K_APCI0155P004A  I178
  R485     2      B  Q_RES       I122

RST_PCIE_PCH_DEV_PERST_N   @S9S_MB_2U_LIB.S9S_MB_2U(SCH_1):RST_PCIE_PCH_DEV_PERST_N
  R485     1      A  Q_RES       I122
  R1419    1      A  Q_RES        I8
  U122   H17  DIFFIO_RX_R19P  10M04SAU324I7G  I93

RST_PCIE_RISER2_N   @S9S_MB_2U_LIB.S9S_MB_2U(SCH_1):RST_PCIE_RISER2_N
  J89    A30    A30  SCONN280_ME1028040102011  I239
  R1513    2      B  Q_RES       I104

RST_PCIE_RISER3_N   @S9S_MB_2U_LIB.S9S_MB_2U(SCH_1):RST_PCIE_RISER3_N
  J57    A10  GND_A10  SCONN140_G64V3431BHR  I242
  R1518    2      B  Q_RES       I70

RST_PERST0_OCP_SFF_N   @S9S_MB_2U_LIB.S9S_MB_2U(SCH_1):RST_PERST0_OCP_SFF_N
  J37    B10  PERST0#  SCONN168_623403212  I86
  R419     2      B  Q_RES        I6

RST_PERST1_OCP_SFF_N   @S9S_MB_2U_LIB.S9S_MB_2U(SCH_1):RST_PERST1_OCP_SFF_N
  J37    A11  PERST1#  SCONN168_623403212  I86
  R435     2      B  Q_RES        I8

RST_PERST2_OCP_SFF_N   @S9S_MB_2U_LIB.S9S_MB_2U(SCH_1):RST_PERST2_OCP_SFF_N
  J37    OCP_A1  PERST2#  SCONN168_623403212  I86
  R1504    2      B  Q_RES       I10

RST_PERST3_OCP_SFF_N   @S9S_MB_2U_LIB.S9S_MB_2U(SCH_1):RST_PERST3_OCP_SFF_N
  J37    OCP_A2  PERST3#  SCONN168_623403212  I86
  R1505    2      B  Q_RES       I13

RST_PFR_OVR_RTC   @S9S_MB_2U_LIB.S9S_MB_2U(SCH_1):RST_PFR_OVR_RTC
  Q34      G   GATE  MOSFET_N_GSD  I81
  R1839    1      A  Q_RES       I85
  R1843    2      B  Q_RES       I122

RST_PFR_OVR_RTC_R   @S9S_MB_2U_LIB.S9S_MB_2U(SCH_1):RST_PFR_OVR_RTC_R
  R1843    1      A  Q_RES       I122
  U122   T17  DIFFIO_RX_R9P  10M04SAU324I7G  I155

RST_PFR_OVR_SRTC   @S9S_MB_2U_LIB.S9S_MB_2U(SCH_1):RST_PFR_OVR_SRTC
  Q35      G   GATE  MOSFET_N_GSD  I86
  R1840    1      A  Q_RES       I89
  R1844    2      B  Q_RES       I123

RST_PFR_OVR_SRTC_R   @S9S_MB_2U_LIB.S9S_MB_2U(SCH_1):RST_PFR_OVR_SRTC_R
  R1844    1      A  Q_RES       I123
  U122   T18  DIFFIO_RX_R4N  10M04SAU324I7G  I155

RST_PLD_CPU0_DRAM_AB_N   @S9S_MB_2U_LIB.S9S_MB_2U(SCH_1):RST_PLD_CPU0_DRAM_AB_N
  C622     1      A  Q_CAP       I91
  R706     1      A  Q_RES       I103
  R836     1      A  Q_RES       I26
  U122   T11  IO_4||VREFB4N0  10M04SAU324I7G  I139

RST_PLD_CPU0_DRAM_CD_N   @S9S_MB_2U_LIB.S9S_MB_2U(SCH_1):RST_PLD_CPU0_DRAM_CD_N
  C623     1      A  Q_CAP       I94
  R707     1      A  Q_RES       I106
  R837     1      A  Q_RES       I59
  U122   R11  DIFFIO_TX_RX_B21P  10M04SAU324I7G  I155

RST_PLD_CPU0_DRAM_EF_N   @S9S_MB_2U_LIB.S9S_MB_2U(SCH_1):RST_PLD_CPU0_DRAM_EF_N
  C624     1      A  Q_CAP       I99
  R708     1      A  Q_RES       I109
  R838     1      A  Q_RES       I76
  U122   T12   IO_4  10M04SAU324I7G  I155

RST_PLD_CPU0_DRAM_GH_N   @S9S_MB_2U_LIB.S9S_MB_2U(SCH_1):RST_PLD_CPU0_DRAM_GH_N
  C621     1      A  Q_CAP       I102
  R705     1      A  Q_RES       I112
  R835     1      A  Q_RES       I86
  U122   V13  DIFFIO_RX_B22N  10M04SAU324I7G  I93

RST_PLD_CPU1_DRAM_AB_N   @S9S_MB_2U_LIB.S9S_MB_2U(SCH_1):RST_PLD_CPU1_DRAM_AB_N
  C614     1      A  Q_CAP       I65
  R703     1      A  Q_RES       I79
  R816     1      A  Q_RES       I37
  U122   V15  DIFFIO_RX_B26N  10M04SAU324I7G  I93

RST_PLD_CPU1_DRAM_CD_N   @S9S_MB_2U_LIB.S9S_MB_2U(SCH_1):RST_PLD_CPU1_DRAM_CD_N
  C615     1      A  Q_CAP       I62
  R701     1      A  Q_RES       I63
  R817     1      A  Q_RES       I26
  U122   U16  DIFFIO_TX_RX_B27N  10M04SAU324I7G  I155

RST_PLD_CPU1_DRAM_EF_N   @S9S_MB_2U_LIB.S9S_MB_2U(SCH_1):RST_PLD_CPU1_DRAM_EF_N
  C616     1      A  Q_CAP       I59
  R704     1      A  Q_RES       I75
  R818     1      A  Q_RES       I22
  U122   V14  DIFFIO_RX_B22P  10M04SAU324I7G  I93

RST_PLD_CPU1_DRAM_GH_N   @S9S_MB_2U_LIB.S9S_MB_2U(SCH_1):RST_PLD_CPU1_DRAM_GH_N
  C613     1      A  Q_CAP       I68
  R702     1      A  Q_RES       I76
  R815     1      A  Q_RES       I11
  U122   V16  DIFFIO_RX_B28N  10M04SAU324I7G  I93

RST_PLTRST_B_MUX_N   @S9S_MB_2U_LIB.S9S_MB_2U(SCH_1):RST_PLTRST_B_MUX_N
  R1470    2      B  Q_RES       I56
  U61      3     B0  NC7SB3157   I39

RST_PLTRST_B_N   @S9S_MB_2U_LIB.S9S_MB_2U(SCH_1):RST_PLTRST_B_N
  J41    A51  PERP10  SCONN168_623403212  I115
  R1469    2      B  Q_RES       I55

RST_PLTRST_N    @S9S_MB_2U_LIB.S9S_MB_2U(SCH_1):RST_PLTRST_N
  R1205    1      A  Q_RES        I7
  R1541    2      B  Q_RES       I92
  U4     AB4  GPP_D_11_PLTRST_N  EMMITSBURG_REV0P9  I93

RST_PLTRST_PLD_B_N   @S9S_MB_2U_LIB.S9S_MB_2U(SCH_1):RST_PLTRST_PLD_B_N
  R1420    1      A  Q_RES        I9
  R1469    1      A  Q_RES       I55
  R1470    1      A  Q_RES       I56
  U122   H18  DIFFIO_RX_R18P  10M04SAU324I7G  I93

RST_PLTRST_PLD_N   @S9S_MB_2U_LIB.S9S_MB_2U(SCH_1):RST_PLTRST_PLD_N
  R1205    2      B  Q_RES        I7
  U122   K11  DIFFIO_RX_R14N||CLK2N  10M04SAU324I7G  I139

RST_RSMRST_PCH_N   @S9S_MB_2U_LIB.S9S_MB_2U(SCH_1):RST_RSMRST_PCH_N
  R772     2      B  Q_RES       I118
  R1207    2      B  Q_RES       I15
  R1695    2      B  Q_RES       I45
  U4     BD9  RSMRST_N  EMMITSBURG_REV0P9  I36

RST_RSMRST_PLD_R_N   @S9S_MB_2U_LIB.S9S_MB_2U(SCH_1):RST_RSMRST_PLD_R_N
  R1207    1      A  Q_RES       I15
  R1421    1      A  Q_RES       I10
  U122   K12  DIFFIO_RX_R14P||CLK2P  10M04SAU324I7G  I139

RST_RTCRST_N    @S9S_MB_2U_LIB.S9S_MB_2U(SCH_1):RST_RTCRST_N
  C1177    1      A  Q_CAP       I67
  Q34      D  DRAIN  MOSFET_N_GSD  I81
  R1340    2      B  Q_RES       I57
  R1839    2      B  Q_RES       I85
  S2       7     B2  SW8S_DHNF04FTVTR  I35
  U4     BD7  RCTRST_N  EMMITSBURG_REV0P9  I27

RST_SGPIO_RESET_N   @S9S_MB_2U_LIB.S9S_MB_2U(SCH_1):RST_SGPIO_RESET_N
  J41    B39  PETN7  SCONN168_623403212  I115
  R1811    1      A  Q_RES       I110

RST_SGPIO_RESET_N_R   @S9S_MB_2U_LIB.S9S_MB_2U(SCH_1):RST_SGPIO_RESET_N_R
  R1811    2      B  Q_RES       I110
  U122   M18  DIFFIO_RX_R13N  10M04SAU324I7G  I93

RST_SMB_BUF_E1S_0_N   @S9S_MB_2U_LIB.S9S_MB_2U(SCH_1):RST_SMB_BUF_E1S_0_N
  R2117    1      A  Q_RES       I36
  U136     6     1Y  SN74LVC2G07DCKR  I46

RST_SMB_BUF_E1S_1_N   @S9S_MB_2U_LIB.S9S_MB_2U(SCH_1):RST_SMB_BUF_E1S_1_N
  R2118    1      A  Q_RES       I37
  U136     4     2Y  SN74LVC2G07DCKR  I46

RST_SMB_BUF_E1S_2_N   @S9S_MB_2U_LIB.S9S_MB_2U(SCH_1):RST_SMB_BUF_E1S_2_N
  R2119    1      A  Q_RES       I42
  U137     6     1Y  SN74LVC2G07DCKR  I48

RST_SMB_BUF_E1S_3_N   @S9S_MB_2U_LIB.S9S_MB_2U(SCH_1):RST_SMB_BUF_E1S_3_N
  R2120    1      A  Q_RES       I43
  U137     4     2Y  SN74LVC2G07DCKR  I48

RST_SMB_E1S_0_N   @S9S_MB_2U_LIB.S9S_MB_2U(SCH_1):RST_SMB_E1S_0_N
  J90     A9  SMBRST#  CONN56_ME2005602311011  I105
  R1673    2      B  Q_RES       I34
  R2117    2      B  Q_RES       I36
  R2123    2      B  Q_RES       I30

RST_SMB_E1S_1_N   @S9S_MB_2U_LIB.S9S_MB_2U(SCH_1):RST_SMB_E1S_1_N
  J91     A9  SMBRST#  CONN56_ME2005602311011  I123
  R2005    2      B  Q_RES       I66
  R2118    2      B  Q_RES       I37
  R2127    2      B  Q_RES       I29

RST_SMB_E1S_2_N   @S9S_MB_2U_LIB.S9S_MB_2U(SCH_1):RST_SMB_E1S_2_N
  J92     A9  SMBRST#  CONN56_ME2005602311011  I105
  R2006    2      B  Q_RES       I30
  R2119    2      B  Q_RES       I42
  R2124    2      B  Q_RES       I35

RST_SMB_E1S_3_N   @S9S_MB_2U_LIB.S9S_MB_2U(SCH_1):RST_SMB_E1S_3_N
  J93     A9  SMBRST#  CONN56_ME2005602311011  I123
  R2007    2      B  Q_RES       I54
  R2120    2      B  Q_RES       I43
  R2128    2      B  Q_RES       I34

RST_SMB_E1S_N   @S9S_MB_2U_LIB.S9S_MB_2U(SCH_1):RST_SMB_E1S_N
  U136     1     1A  SN74LVC2G07DCKR  I46
  U136     3     2A  SN74LVC2G07DCKR  I46
  U137     1     1A  SN74LVC2G07DCKR  I48
  U137     3     2A  SN74LVC2G07DCKR  I48

RST_SMB_EDSFF1A_N   @S9S_MB_2U_LIB.S9S_MB_2U(SCH_1):RST_SMB_EDSFF1A_N
  J62     A9  SMBRST_N  SCONN84_123318136  I33
  R1967    1      A  Q_RES       I76

RST_SMB_EDSFF1B_N   @S9S_MB_2U_LIB.S9S_MB_2U(SCH_1):RST_SMB_EDSFF1B_N
  J87     A9  SMBRST_N  SCONN84_123318136  I43
  R1977    1      A  Q_RES       I80

RST_SMB_EDSFF2A_N   @S9S_MB_2U_LIB.S9S_MB_2U(SCH_1):RST_SMB_EDSFF2A_N
  J33     A9  SMBRST_N  SCONN84_123318136  I53
  R1613    1      A  Q_RES       I97

RST_SMB_EDSFF2B_N   @S9S_MB_2U_LIB.S9S_MB_2U(SCH_1):RST_SMB_EDSFF2B_N
  J34     A9  SMBRST_N  SCONN84_123318136  I43
  R1615    1      A  Q_RES       I95

RST_SMB_EDSFF4A_N   @S9S_MB_2U_LIB.S9S_MB_2U(SCH_1):RST_SMB_EDSFF4A_N
  J88     A9  SMBRST_N  SCONN84_123318136  I16
  R1987    1      A  Q_RES       I12

RST_SRTCRST_N   @S9S_MB_2U_LIB.S9S_MB_2U(SCH_1):RST_SRTCRST_N
  C610     1      A  Q_CAP       I68
  Q35      D  DRAIN  MOSFET_N_GSD  I86
  R1202    2      B  Q_RES       I70
  R1840    2      B  Q_RES       I89
  U4     BF9  SRTCRST_N  EMMITSBURG_REV0P9  I27

RTC_EXT_CAP     @S9S_MB_2U_LIB.S9S_MB_2U(SCH_1):RTC_EXT_CAP
  C609     1      A  Q_CAP       I89
  U4     BF5  RTC_EXTCAP  EMMITSBURG_REV0P9  I78

SATA_P11_RX_C_DN   @S9S_MB_2U_LIB.S9S_MB_2U(SCH_1):SATA_P11_RX_C_DN
  C636     1      1  Q_CAP_SATA6G  I12
  J54      5      5  CONN7_ABASAT054KA1   I8

SATA_P11_RX_C_DP   @S9S_MB_2U_LIB.S9S_MB_2U(SCH_1):SATA_P11_RX_C_DP
  C637     1      1  Q_CAP_SATA6G  I13
  J54      6      6  CONN7_ABASAT054KA1   I8

SATA_P11_RX_DN   @S9S_MB_2U_LIB.S9S_MB_2U(SCH_1):SATA_P11_RX_DN
  C636     2      2  Q_CAP_SATA6G  I12
  U4     L40  SATA_11_PCIE3_11_RXN  EMMITSBURG_REV0P9  I119

SATA_P11_RX_DP   @S9S_MB_2U_LIB.S9S_MB_2U(SCH_1):SATA_P11_RX_DP
  C637     2      2  Q_CAP_SATA6G  I13
  U4     L42  SATA_11_PCIE3_11_RXP  EMMITSBURG_REV0P9  I119

SATA_P11_TX_C_DN   @S9S_MB_2U_LIB.S9S_MB_2U(SCH_1):SATA_P11_TX_C_DN
  C635     1      1  Q_CAP_SATA6G  I11
  J54      3      3  CONN7_ABASAT054KA1   I8

SATA_P11_TX_C_DP   @S9S_MB_2U_LIB.S9S_MB_2U(SCH_1):SATA_P11_TX_C_DP
  C634     1      1  Q_CAP_SATA6G  I10
  J54      2      2  CONN7_ABASAT054KA1   I8

SATA_P11_TX_DN   @S9S_MB_2U_LIB.S9S_MB_2U(SCH_1):SATA_P11_TX_DN
  C635     2      2  Q_CAP_SATA6G  I11
  U4     T37  SATA_11_PCIE3_11_TXN  EMMITSBURG_REV0P9  I119

SATA_P11_TX_DP   @S9S_MB_2U_LIB.S9S_MB_2U(SCH_1):SATA_P11_TX_DP
  C634     2      2  Q_CAP_SATA6G  I10
  U4     V37  SATA_11_PCIE3_11_TXP  EMMITSBURG_REV0P9  I119

SGPIO_BMC_CLK   @S9S_MB_2U_LIB.S9S_MB_2U(SCH_1):SGPIO_BMC_CLK
  R1752    2      B  Q_RES       I82
  U122   J12  DIFFIO_RX_R20N  10M04SAU324I7G  I93

SGPIO_BMC_DIN_R   @S9S_MB_2U_LIB.S9S_MB_2U(SCH_1):SGPIO_BMC_DIN_R
  R1753    2      B  Q_RES       I84
  U122   J11  DIFFIO_RX_R20P  10M04SAU324I7G  I93

SGPIO_BMC_DOUT   @S9S_MB_2U_LIB.S9S_MB_2U(SCH_1):SGPIO_BMC_DOUT
  R1751    2      B  Q_RES       I81
  U122   M17  DIFFIO_RX_R15P  10M04SAU324I7G  I93

SGPIO_BMC_LD_N   @S9S_MB_2U_LIB.S9S_MB_2U(SCH_1):SGPIO_BMC_LD_N
  R1754    2      B  Q_RES       I88
  U122   B18  DIFFIO_RX_R32N  10M04SAU324I7G  I93

SGPIO_CLK_0     @S9S_MB_2U_LIB.S9S_MB_2U(SCH_1):SGPIO_CLK_0
  J41    B30  PETN4  SCONN168_623403212  I115
  R1752    1      A  Q_RES       I82

SGPIO_CLK_1     @S9S_MB_2U_LIB.S9S_MB_2U(SCH_1):SGPIO_CLK_1
  J41    B35  GND_B35  SCONN168_623403212  I115
  R1756    1      A  Q_RES       I98

SGPIO_DEBUG_PLD_CLK   @S9S_MB_2U_LIB.S9S_MB_2U(SCH_1):SGPIO_DEBUG_PLD_CLK
  R1756    2      B  Q_RES       I98
  U122   M11  DIFFIO_RX_R3N  10M04SAU324I7G  I155

SGPIO_DEBUG_PLD_DIN   @S9S_MB_2U_LIB.S9S_MB_2U(SCH_1):SGPIO_DEBUG_PLD_DIN
  R1757    2      B  Q_RES       I99
  U122   M15  DIFFIO_RX_R5N  10M04SAU324I7G  I155

SGPIO_DEBUG_PLD_DOUT   @S9S_MB_2U_LIB.S9S_MB_2U(SCH_1):SGPIO_DEBUG_PLD_DOUT
  R1755    2      B  Q_RES       I96
  U122   M12  DIFFIO_RX_R3P  10M04SAU324I7G  I155

SGPIO_DEBUG_PLD_LD_N   @S9S_MB_2U_LIB.S9S_MB_2U(SCH_1):SGPIO_DEBUG_PLD_LD_N
  R1758    2      B  Q_RES       I91
  U122   M16  DIFFIO_RX_R6N  10M04SAU324I7G  I155

SGPIO_DI_0      @S9S_MB_2U_LIB.S9S_MB_2U(SCH_1):SGPIO_DI_0
  J41    B31  PETP4  SCONN168_623403212  I115
  R1753    1      A  Q_RES       I84

SGPIO_DI_1      @S9S_MB_2U_LIB.S9S_MB_2U(SCH_1):SGPIO_DI_1
  J41    B36  PETN6  SCONN168_623403212  I115
  R1757    1      A  Q_RES       I99

SGPIO_DO_0      @S9S_MB_2U_LIB.S9S_MB_2U(SCH_1):SGPIO_DO_0
  J41    B29  GND_B29  SCONN168_623403212  I115
  R1751    1      A  Q_RES       I81

SGPIO_DO_1      @S9S_MB_2U_LIB.S9S_MB_2U(SCH_1):SGPIO_DO_1
  J41    B34  PETP5  SCONN168_623403212  I115
  R1755    1      A  Q_RES       I96

SGPIO_LD_0      @S9S_MB_2U_LIB.S9S_MB_2U(SCH_1):SGPIO_LD_0
  J41    B32  GND_B32  SCONN168_623403212  I115
  R1754    1      A  Q_RES       I88

SGPIO_LD_1      @S9S_MB_2U_LIB.S9S_MB_2U(SCH_1):SGPIO_LD_1
  J41    B37  PETP6  SCONN168_623403212  I115
  R1758    1      A  Q_RES       I91

SGPIO_OCP_SFF_CLK_N   @S9S_MB_2U_LIB.S9S_MB_2U(SCH_1):SGPIO_OCP_SFF_CLK_N
  J37    OCP_B6    CLK  SCONN168_623403212  I86
  R423     1      A  Q_RES       I13

SGPIO_OCP_SFF_DATAIN_N   @S9S_MB_2U_LIB.S9S_MB_2U(SCH_1):SGPIO_OCP_SFF_DATAIN_N
  J37    OCP_B4  DATA_IN  SCONN168_623403212  I86
  R421     1      A  Q_RES       I11

SGPIO_OCP_SFF_DATAOUT_N   @S9S_MB_2U_LIB.S9S_MB_2U(SCH_1):SGPIO_OCP_SFF_DATAOUT_N
  J37    OCP_B5  DATA_OUT  SCONN168_623403212  I86
  R422     1      A  Q_RES       I12

SGPIO_OCP_SFF_LD_N   @S9S_MB_2U_LIB.S9S_MB_2U(SCH_1):SGPIO_OCP_SFF_LD_N
  J37    OCP_B3    LD#  SCONN168_623403212  I86
  R420     1      A  Q_RES       I10

SH_P1V05_PCH_AUX_N   @S9S_MB_2U_LIB.S9S_MB_2U(SCH_1):SH_P1V05_PCH_AUX_N
  PC1221    2      B  Q_CAP       I36
  PJ63     1      1  Q_SHORT     I15
  PR187    2      B  Q_RES       I13
  PU73     6   RGND  MPQ8633BGLEC838Z  I34

SH_P1V05_PCH_AUX_P   @S9S_MB_2U_LIB.S9S_MB_2U(SCH_1):SH_P1V05_PCH_AUX_P
  PC1223    2      B  Q_CAP       I42
  PJ62     1      1  Q_SHORT     I46
  PR1328    2      B  Q_RES       I41

SH_PVCCD_HV_CPU0   @S9S_MB_2U_LIB.S9S_MB_2U(SCH_1):SH_PVCCD_HV_CPU0
  PJ54     2      2  Q_SHORT     I79
  PR371    1      A  Q_RES       I41

SH_PVCCD_HV_CPU0_R   @S9S_MB_2U_LIB.S9S_MB_2U(SCH_1):SH_PVCCD_HV_CPU0_R
  PC627    1      A  Q_CAP       I18
  PR371    2      B  Q_RES       I41
  PU35    21  VSEN0  ISL69260IRAZT  I51

SH_PVCCD_HV_CPU1   @S9S_MB_2U_LIB.S9S_MB_2U(SCH_1):SH_PVCCD_HV_CPU1
  PJ48     2      2  Q_SHORT     I207
  PR216    1      A  Q_RES       I252

SH_PVCCD_HV_CPU1_R   @S9S_MB_2U_LIB.S9S_MB_2U(SCH_1):SH_PVCCD_HV_CPU1_R
  PC389    1      A  Q_CAP       I248
  PR216    2      B  Q_RES       I252
  PU18    21  VSEN0  ISL69260IRAZT  I243

SH_PVCCFA_EHV_CPU0   @S9S_MB_2U_LIB.S9S_MB_2U(SCH_1):SH_PVCCFA_EHV_CPU0
  PJ46     2      2  Q_SHORT      I9
  PR121    1      A  Q_RES       I45

SH_PVCCFA_EHV_CPU0_R   @S9S_MB_2U_LIB.S9S_MB_2U(SCH_1):SH_PVCCFA_EHV_CPU0_R
  PC216    1      A  Q_CAP       I46
  PR121    2      B  Q_RES       I45
  PU5     32  VSEN1  ISL69260IRAZT  I51

SH_PVCCFA_EHV_CPU1   @S9S_MB_2U_LIB.S9S_MB_2U(SCH_1):SH_PVCCFA_EHV_CPU1
  PJ51     2      2  Q_SHORT     I20
  PR274    1      A  Q_RES       I29

SH_PVCCFA_EHV_CPU1_R   @S9S_MB_2U_LIB.S9S_MB_2U(SCH_1):SH_PVCCFA_EHV_CPU1_R
  PC469    1      A  Q_CAP       I64
  PR274    2      B  Q_RES       I29
  PU22    32  VSEN1  ISL69260IRAZT  I61

SH_PVCCFA_EHV_FIVRA_CPU0   @S9S_MB_2U_LIB.S9S_MB_2U(SCH_1):SH_PVCCFA_EHV_FIVRA_CPU0
  PJ53     2      2  Q_SHORT     I19
  PR345    1      A  Q_RES       I57

SH_PVCCFA_EHV_FIVRA_CPU0_R   @S9S_MB_2U_LIB.S9S_MB_2U(SCH_1):SH_PVCCFA_EHV_FIVRA_CPU0_R
  PC594    1      A  Q_CAP       I56
  PR345    2      B  Q_RES       I57
  PU14    40  VSEN1  RAA229126GNPHA0  I48

SH_PVCCFA_EHV_FIVRA_CPU1   @S9S_MB_2U_LIB.S9S_MB_2U(SCH_1):SH_PVCCFA_EHV_FIVRA_CPU1
  PJ49     2      2  Q_SHORT     I174
  PR242    1      A  Q_RES       I220

SH_PVCCFA_EHV_FIVRA_CPU1_R   @S9S_MB_2U_LIB.S9S_MB_2U(SCH_1):SH_PVCCFA_EHV_FIVRA_CPU1_R
  PC422    1      A  Q_CAP       I219
  PR242    2      B  Q_RES       I220
  PU29    40  VSEN1  RAA229126GNPHA0  I211

SH_PVCCINFAON_CPU0   @S9S_MB_2U_LIB.S9S_MB_2U(SCH_1):SH_PVCCINFAON_CPU0
  PJ45     2      2  Q_SHORT     I15
  PR120    1      A  Q_RES       I58

SH_PVCCINFAON_CPU0_R   @S9S_MB_2U_LIB.S9S_MB_2U(SCH_1):SH_PVCCINFAON_CPU0_R
  PC215    1      A  Q_CAP       I47
  PR120    2      B  Q_RES       I58
  PU5     21  VSEN0  ISL69260IRAZT  I51

SH_PVCCINFAON_CPU1   @S9S_MB_2U_LIB.S9S_MB_2U(SCH_1):SH_PVCCINFAON_CPU1
  PJ50     2      2  Q_SHORT     I33
  PR273    1      A  Q_RES       I42

SH_PVCCINFAON_CPU1_R   @S9S_MB_2U_LIB.S9S_MB_2U(SCH_1):SH_PVCCINFAON_CPU1_R
  PC468    1      A  Q_CAP       I65
  PR273    2      B  Q_RES       I42
  PU22    21  VSEN0  ISL69260IRAZT  I61

SH_PVCCIN_CPU0   @S9S_MB_2U_LIB.S9S_MB_2U(SCH_1):SH_PVCCIN_CPU0
  PJ47     2      2  Q_SHORT     I30
  PR170    1      A  Q_RES       I60

SH_PVCCIN_CPU0_R   @S9S_MB_2U_LIB.S9S_MB_2U(SCH_1):SH_PVCCIN_CPU0_R
  PC331    1      A  Q_CAP       I62
  PR170    2      B  Q_RES       I60
  PU14    25  VSEN0  RAA229126GNPHA0  I48

SH_PVCCIN_CPU1   @S9S_MB_2U_LIB.S9S_MB_2U(SCH_1):SH_PVCCIN_CPU1
  PJ52     2      2  Q_SHORT     I187
  PR317    1      A  Q_RES       I238

SH_PVCCIN_CPU1_R   @S9S_MB_2U_LIB.S9S_MB_2U(SCH_1):SH_PVCCIN_CPU1_R
  PC549    1      A  Q_CAP       I240
  PR317    2      B  Q_RES       I238
  PU29    25  VSEN0  RAA229126GNPHA0  I211

SH_PVPP_HBM_CPU0_N   @S9S_MB_2U_LIB.S9S_MB_2U(SCH_1):SH_PVPP_HBM_CPU0_N
  PC1251    2      B  Q_CAP       I46
  PJ65     1      1  Q_SHORT     I54
  PR1310    2      B  Q_RES       I49
  PU79     6   RGND  MPQ8633AGLEC807Z  I13
  U73      S  SOURCE  MOSFET_N    I50

SH_PVPP_HBM_CPU0_P   @S9S_MB_2U_LIB.S9S_MB_2U(SCH_1):SH_PVPP_HBM_CPU0_P
  PC1253    2      B  Q_CAP       I52
  PJ64     1      1  Q_SHORT     I57
  PR1337    2      B  Q_RES       I53

SH_PVPP_HBM_CPU1_N   @S9S_MB_2U_LIB.S9S_MB_2U(SCH_1):SH_PVPP_HBM_CPU1_N
  PC1264    2      B  Q_CAP       I48
  PJ67     1      1  Q_SHORT     I55
  PR1314    2      B  Q_RES       I49
  PU80     6   RGND  MPQ8633AGLEC807Z  I15
  U74      S  SOURCE  MOSFET_N    I50

SH_PVPP_HBM_CPU1_P   @S9S_MB_2U_LIB.S9S_MB_2U(SCH_1):SH_PVPP_HBM_CPU1_P
  PC1266    2      B  Q_CAP       I52
  PJ66     1      1  Q_SHORT     I56
  PR1340    2      B  Q_RES       I54

SMB_CLK_PVCCD_HV_CPU0   @S9S_MB_2U_LIB.S9S_MB_2U(SCH_1):SMB_CLK_PVCCD_HV_CPU0
  PR367    2      B  Q_RES       I35
  PU35    10  PMSCL  ISL69260IRAZT  I51

SMB_CLK_PVCCD_HV_CPU1   @S9S_MB_2U_LIB.S9S_MB_2U(SCH_1):SMB_CLK_PVCCD_HV_CPU1
  PR212    2      B  Q_RES       I225
  PU18    10  PMSCL  ISL69260IRAZT  I243

SMB_CLK_PVCCINFAON_CPU0   @S9S_MB_2U_LIB.S9S_MB_2U(SCH_1):SMB_CLK_PVCCINFAON_CPU0
  PR115    2      B  Q_RES       I60
  PU5     10  PMSCL  ISL69260IRAZT  I51

SMB_CLK_PVCCINFAON_CPU1   @S9S_MB_2U_LIB.S9S_MB_2U(SCH_1):SMB_CLK_PVCCINFAON_CPU1
  PR268    2      B  Q_RES       I43
  PU22    10  PMSCL  ISL69260IRAZT  I61

SMB_CLK_PVCCIN_CPU0   @S9S_MB_2U_LIB.S9S_MB_2U(SCH_1):SMB_CLK_PVCCIN_CPU0
  PR167    2      B  Q_RES       I64
  PU14    14  PMSCL  RAA229126GNPHA0  I48

SMB_CLK_PVCCIN_CPU1   @S9S_MB_2U_LIB.S9S_MB_2U(SCH_1):SMB_CLK_PVCCIN_CPU1
  PR314    2      B  Q_RES       I241
  PU29    14  PMSCL  RAA229126GNPHA0  I211

SMB_CPU0_PIROM_3V3AUX_SCL_R   @S9S_MB_2U_LIB.S9S_MB_2U(SCH_1):SMB_CPU0_PIROM_3V3AUX_SCL_R
  R1932    2      B  Q_RES       I109
  U2     CU70  I2C_PIROM_SCL  SOCKET4677_AZIFS054P001C01   I1

SMB_CPU0_PIROM_3V3AUX_SDA_R   @S9S_MB_2U_LIB.S9S_MB_2U(SCH_1):SMB_CPU0_PIROM_3V3AUX_SDA_R
  R1933    2      B  Q_RES       I110
  U2     CM71  I2C_PIROM_SDA  SOCKET4677_AZIFS054P001C01   I1

SMB_CPU1_PIROM_3V3AUX_SCL_R   @S9S_MB_2U_LIB.S9S_MB_2U(SCH_1):SMB_CPU1_PIROM_3V3AUX_SCL_R
  R1934    2      B  Q_RES       I81
  U1     CU70  I2C_PIROM_SCL  SOCKET4677_AZIFS054P001C01  I29

SMB_CPU1_PIROM_3V3AUX_SDA_R   @S9S_MB_2U_LIB.S9S_MB_2U(SCH_1):SMB_CPU1_PIROM_3V3AUX_SDA_R
  R1935    2      B  Q_RES       I82
  U1     CM71  I2C_PIROM_SDA  SOCKET4677_AZIFS054P001C01  I29

SMB_CPU_PIROM_3V3AUX_SCL   @S9S_MB_2U_LIB.S9S_MB_2U(SCH_1):SMB_CPU_PIROM_3V3AUX_SCL
  J41    A21  PERP1  SCONN168_623403212  I115
  R606     1      A  Q_RES       I175
  R1932    1      A  Q_RES       I109
  R1934    1      A  Q_RES       I81

SMB_CPU_PIROM_3V3AUX_SDA   @S9S_MB_2U_LIB.S9S_MB_2U(SCH_1):SMB_CPU_PIROM_3V3AUX_SDA
  J41    A22  GND_A22  SCONN168_623403212  I115
  R649     1      A  Q_RES       I174
  R1933    1      A  Q_RES       I110
  R1935    1      A  Q_RES       I82

SMB_DIO_PVCCD_HV_CPU0   @S9S_MB_2U_LIB.S9S_MB_2U(SCH_1):SMB_DIO_PVCCD_HV_CPU0
  PR368    2      B  Q_RES       I36
  PU35     9  PMSDA  ISL69260IRAZT  I51

SMB_DIO_PVCCD_HV_CPU1   @S9S_MB_2U_LIB.S9S_MB_2U(SCH_1):SMB_DIO_PVCCD_HV_CPU1
  PR213    2      B  Q_RES       I226
  PU18     9  PMSDA  ISL69260IRAZT  I243

SMB_DIO_PVCCINFAON_CPU0   @S9S_MB_2U_LIB.S9S_MB_2U(SCH_1):SMB_DIO_PVCCINFAON_CPU0
  PR116    2      B  Q_RES       I59
  PU5      9  PMSDA  ISL69260IRAZT  I51

SMB_DIO_PVCCINFAON_CPU1   @S9S_MB_2U_LIB.S9S_MB_2U(SCH_1):SMB_DIO_PVCCINFAON_CPU1
  PR269    2      B  Q_RES       I41
  PU22     9  PMSDA  ISL69260IRAZT  I61

SMB_DIO_PVCCIN_CPU0   @S9S_MB_2U_LIB.S9S_MB_2U(SCH_1):SMB_DIO_PVCCIN_CPU0
  PR168    2      B  Q_RES       I61
  PU14    13  PMSDA  RAA229126GNPHA0  I48

SMB_DIO_PVCCIN_CPU1   @S9S_MB_2U_LIB.S9S_MB_2U(SCH_1):SMB_DIO_PVCCIN_CPU1
  PR315    2      B  Q_RES       I239
  PU29    13  PMSDA  RAA229126GNPHA0  I211

SMB_E1S_0_3V3AUX_SCL   @S9S_MB_2U_LIB.S9S_MB_2U(SCH_1):SMB_E1S_0_3V3AUX_SCL
  J90     A7  SMBCLK  CONN56_ME2005602311011  I105
  R1057    1      A  Q_RES       I186
  R1065    2      B  Q_RES       I146

SMB_E1S_0_3V3AUX_SDA   @S9S_MB_2U_LIB.S9S_MB_2U(SCH_1):SMB_E1S_0_3V3AUX_SDA
  J90     A8  SMBDAT  CONN56_ME2005602311011  I105
  R1058    1      A  Q_RES       I187
  R1066    2      B  Q_RES       I145

SMB_E1S_1_3V3AUX_SCL   @S9S_MB_2U_LIB.S9S_MB_2U(SCH_1):SMB_E1S_1_3V3AUX_SCL
  J91     A7  SMBCLK  CONN56_ME2005602311011  I123
  R1059    1      A  Q_RES       I188
  R1067    2      B  Q_RES       I148

SMB_E1S_1_3V3AUX_SDA   @S9S_MB_2U_LIB.S9S_MB_2U(SCH_1):SMB_E1S_1_3V3AUX_SDA
  J91     A8  SMBDAT  CONN56_ME2005602311011  I123
  R1060    1      A  Q_RES       I189
  R1068    2      B  Q_RES       I147

SMB_E1S_2_3V3AUX_SCL   @S9S_MB_2U_LIB.S9S_MB_2U(SCH_1):SMB_E1S_2_3V3AUX_SCL
  J92     A7  SMBCLK  CONN56_ME2005602311011  I105
  R1061    2      B  Q_RES       I131
  R1069    2      B  Q_RES       I149

SMB_E1S_2_3V3AUX_SDA   @S9S_MB_2U_LIB.S9S_MB_2U(SCH_1):SMB_E1S_2_3V3AUX_SDA
  J92     A8  SMBDAT  CONN56_ME2005602311011  I105
  R1062    2      B  Q_RES       I130
  R1070    2      B  Q_RES       I150

SMB_E1S_3_3V3AUX_SCL   @S9S_MB_2U_LIB.S9S_MB_2U(SCH_1):SMB_E1S_3_3V3AUX_SCL
  J93     A7  SMBCLK  CONN56_ME2005602311011  I123
  R1063    2      B  Q_RES       I133
  R1071    2      B  Q_RES       I154

SMB_E1S_3_3V3AUX_SDA   @S9S_MB_2U_LIB.S9S_MB_2U(SCH_1):SMB_E1S_3_3V3AUX_SDA
  J93     A8  SMBDAT  CONN56_ME2005602311011  I123
  R1064    2      B  Q_RES       I132
  R1072    2      B  Q_RES       I151

SMB_EDSFF1A_3V3AUX_SCL_R   @S9S_MB_2U_LIB.S9S_MB_2U(SCH_1):SMB_EDSFF1A_3V3AUX_SCL_R
  J62     A7  SMBCLK  SCONN84_123318136  I33
  R787     2      B  Q_RES       I85
  R791     2      B  Q_RES       I33

SMB_EDSFF1A_3V3AUX_SCL_R1   @S9S_MB_2U_LIB.S9S_MB_2U(SCH_1):SMB_EDSFF1A_3V3AUX_SCL_R1
  R787     1      A  Q_RES       I85
  U24      5    SC0  PCA9548APW  I60

SMB_EDSFF1A_3V3AUX_SDA_R   @S9S_MB_2U_LIB.S9S_MB_2U(SCH_1):SMB_EDSFF1A_3V3AUX_SDA_R
  J62     A8  SMBDAT  SCONN84_123318136  I33
  R788     2      B  Q_RES       I84
  R792     2      B  Q_RES       I32

SMB_EDSFF1A_3V3AUX_SDA_R1   @S9S_MB_2U_LIB.S9S_MB_2U(SCH_1):SMB_EDSFF1A_3V3AUX_SDA_R1
  R788     1      A  Q_RES       I84
  U24      4    SD0  PCA9548APW  I60

SMB_EDSFF1B_3V3AUX_SCL_R   @S9S_MB_2U_LIB.S9S_MB_2U(SCH_1):SMB_EDSFF1B_3V3AUX_SCL_R
  J87     A7  SMBCLK  SCONN84_123318136  I43
  R2051    2      B  Q_RES       I124
  R2059    2      B  Q_RES       I89

SMB_EDSFF1B_3V3AUX_SCL_R1   @S9S_MB_2U_LIB.S9S_MB_2U(SCH_1):SMB_EDSFF1B_3V3AUX_SCL_R1
  R2059    1      A  Q_RES       I89
  U24      7    SC1  PCA9548APW  I60

SMB_EDSFF1B_3V3AUX_SDA_R   @S9S_MB_2U_LIB.S9S_MB_2U(SCH_1):SMB_EDSFF1B_3V3AUX_SDA_R
  J87     A8  SMBDAT  SCONN84_123318136  I43
  R2052    2      B  Q_RES       I125
  R2060    2      B  Q_RES       I88

SMB_EDSFF1B_3V3AUX_SDA_R1   @S9S_MB_2U_LIB.S9S_MB_2U(SCH_1):SMB_EDSFF1B_3V3AUX_SDA_R1
  R2060    1      A  Q_RES       I88
  U24      6    SD1  PCA9548APW  I60

SMB_EDSFF2A_3V3AUX_SCL_R   @S9S_MB_2U_LIB.S9S_MB_2U(SCH_1):SMB_EDSFF2A_3V3AUX_SCL_R
  J33     A7  SMBCLK  SCONN84_123318136  I53
  R789     2      B  Q_RES       I87
  R793     2      B  Q_RES       I116

SMB_EDSFF2A_3V3AUX_SCL_R1   @S9S_MB_2U_LIB.S9S_MB_2U(SCH_1):SMB_EDSFF2A_3V3AUX_SCL_R1
  R789     1      A  Q_RES       I87
  U24      9    SC2  PCA9548APW  I60

SMB_EDSFF2A_3V3AUX_SDA_R   @S9S_MB_2U_LIB.S9S_MB_2U(SCH_1):SMB_EDSFF2A_3V3AUX_SDA_R
  J33     A8  SMBDAT  SCONN84_123318136  I53
  R790     2      B  Q_RES       I86
  R794     2      B  Q_RES       I117

SMB_EDSFF2A_3V3AUX_SDA_R1   @S9S_MB_2U_LIB.S9S_MB_2U(SCH_1):SMB_EDSFF2A_3V3AUX_SDA_R1
  R790     1      A  Q_RES       I86
  U24      8    SD2  PCA9548APW  I60

SMB_EDSFF2B_3V3AUX_SCL_R   @S9S_MB_2U_LIB.S9S_MB_2U(SCH_1):SMB_EDSFF2B_3V3AUX_SCL_R
  J34     A7  SMBCLK  SCONN84_123318136  I43
  R2053    2      B  Q_RES       I140
  R2061    2      B  Q_RES       I91

SMB_EDSFF2B_3V3AUX_SCL_R1   @S9S_MB_2U_LIB.S9S_MB_2U(SCH_1):SMB_EDSFF2B_3V3AUX_SCL_R1
  R2061    1      A  Q_RES       I91
  U24     11    SC3  PCA9548APW  I60

SMB_EDSFF2B_3V3AUX_SDA_R   @S9S_MB_2U_LIB.S9S_MB_2U(SCH_1):SMB_EDSFF2B_3V3AUX_SDA_R
  J34     A8  SMBDAT  SCONN84_123318136  I43
  R2054    2      B  Q_RES       I141
  R2062    2      B  Q_RES       I90

SMB_EDSFF2B_3V3AUX_SDA_R1   @S9S_MB_2U_LIB.S9S_MB_2U(SCH_1):SMB_EDSFF2B_3V3AUX_SDA_R1
  R2062    1      A  Q_RES       I90
  U24     10    SD3  PCA9548APW  I60

SMB_EDSFF3_3V3AUX_SCL_R   @S9S_MB_2U_LIB.S9S_MB_2U(SCH_1):SMB_EDSFF3_3V3AUX_SCL_R
  J35    A11  SIGNAL_A11  SCONN140_G64V3431BHR  I64
  R795     2      B  Q_RES       I134
  R801     2      B  Q_RES       I63

SMB_EDSFF3_3V3AUX_SCL_R1   @S9S_MB_2U_LIB.S9S_MB_2U(SCH_1):SMB_EDSFF3_3V3AUX_SCL_R1
  R801     1      A  Q_RES       I63
  U24     14    SC4  PCA9548APW  I60

SMB_EDSFF3_3V3AUX_SDA_R   @S9S_MB_2U_LIB.S9S_MB_2U(SCH_1):SMB_EDSFF3_3V3AUX_SDA_R
  J35    A12  SIGNAL_A12  SCONN140_G64V3431BHR  I64
  R796     2      B  Q_RES       I135
  R802     2      B  Q_RES       I64

SMB_EDSFF3_3V3AUX_SDA_R1   @S9S_MB_2U_LIB.S9S_MB_2U(SCH_1):SMB_EDSFF3_3V3AUX_SDA_R1
  R802     1      A  Q_RES       I64
  U24     13    SD4  PCA9548APW  I60

SMB_EDSFF4A_3V3AUX_SCL_R   @S9S_MB_2U_LIB.S9S_MB_2U(SCH_1):SMB_EDSFF4A_3V3AUX_SCL_R
  J88     A7  SMBCLK  SCONN84_123318136  I16
  R797     2      B  Q_RES       I136
  R799     2      B  Q_RES       I68

SMB_EDSFF4A_3V3AUX_SCL_R1   @S9S_MB_2U_LIB.S9S_MB_2U(SCH_1):SMB_EDSFF4A_3V3AUX_SCL_R1
  R799     1      A  Q_RES       I68
  U24     16    SC5  PCA9548APW  I60

SMB_EDSFF4A_3V3AUX_SDA_R   @S9S_MB_2U_LIB.S9S_MB_2U(SCH_1):SMB_EDSFF4A_3V3AUX_SDA_R
  J88     A8  SMBDAT  SCONN84_123318136  I16
  R798     2      B  Q_RES       I137
  R800     2      B  Q_RES       I65

SMB_EDSFF4A_3V3AUX_SDA_R1   @S9S_MB_2U_LIB.S9S_MB_2U(SCH_1):SMB_EDSFF4A_3V3AUX_SDA_R1
  R800     1      A  Q_RES       I65
  U24     15    SD5  PCA9548APW  I60

SMB_EDSFF4B_3V3AUX_SCL_R   @S9S_MB_2U_LIB.S9S_MB_2U(SCH_1):SMB_EDSFF4B_3V3AUX_SCL_R
  R2055    2      B  Q_RES       I143
  R2063    2      B  Q_RES       I96

SMB_EDSFF4B_3V3AUX_SCL_R1   @S9S_MB_2U_LIB.S9S_MB_2U(SCH_1):SMB_EDSFF4B_3V3AUX_SCL_R1
  R2063    1      A  Q_RES       I96
  U24     18    SC6  PCA9548APW  I60

SMB_EDSFF4B_3V3AUX_SDA_R   @S9S_MB_2U_LIB.S9S_MB_2U(SCH_1):SMB_EDSFF4B_3V3AUX_SDA_R
  R2056    2      B  Q_RES       I142
  R2064    2      B  Q_RES       I95

SMB_EDSFF4B_3V3AUX_SDA_R1   @S9S_MB_2U_LIB.S9S_MB_2U(SCH_1):SMB_EDSFF4B_3V3AUX_SDA_R1
  R2064    1      A  Q_RES       I95
  U24     17    SD6  PCA9548APW  I60

SMB_EDSFF_3V3AUX_SCL_R8   @S9S_MB_2U_LIB.S9S_MB_2U(SCH_1):SMB_EDSFF_3V3AUX_SCL_R8
  R2065    1      A  Q_RES       I109
  U24     20    SC7  PCA9548APW  I60

SMB_EDSFF_3V3AUX_SDA_R8   @S9S_MB_2U_LIB.S9S_MB_2U(SCH_1):SMB_EDSFF_3V3AUX_SDA_R8
  R2066    1      A  Q_RES       I108
  U24     19    SD7  PCA9548APW  I60

SMB_FAN_3V3AUX_SCL   @S9S_MB_2U_LIB.S9S_MB_2U(SCH_1):SMB_FAN_3V3AUX_SCL
  J41    A29  GND_A29  SCONN168_623403212  I115
  R592     1      A  Q_RES       I173
  R723     2      B  Q_RES       I154

SMB_FAN_3V3AUX_SCL_R1   @S9S_MB_2U_LIB.S9S_MB_2U(SCH_1):SMB_FAN_3V3AUX_SCL_R1
  J44     14     14  CONN24_52SH90245BRD  I125
  R723     1      A  Q_RES       I154

SMB_FAN_3V3AUX_SDA   @S9S_MB_2U_LIB.S9S_MB_2U(SCH_1):SMB_FAN_3V3AUX_SDA
  J41    A30  PERN4  SCONN168_623403212  I115
  R601     1      A  Q_RES       I172
  R724     2      B  Q_RES       I166

SMB_FAN_3V3AUX_SDA_R1   @S9S_MB_2U_LIB.S9S_MB_2U(SCH_1):SMB_FAN_3V3AUX_SDA_R1
  J44     18     18  CONN24_52SH90245BRD  I125
  R724     1      A  Q_RES       I166

SMB_FRU_3V3AUX_SCL_R   @S9S_MB_2U_LIB.S9S_MB_2U(SCH_1):SMB_FRU_3V3AUX_SCL_R
  R475     2      B  Q_RES       I39
  U64      6    SCL  M24128BWDW6TP  I35

SMB_FRU_3V3AUX_SDA_R   @S9S_MB_2U_LIB.S9S_MB_2U(SCH_1):SMB_FRU_3V3AUX_SDA_R
  R709     2      B  Q_RES       I37
  U64      5    SDA  M24128BWDW6TP  I35

SMB_HOST_3V3AUX_SCL   @S9S_MB_2U_LIB.S9S_MB_2U(SCH_1):SMB_HOST_3V3AUX_SCL
  J41     A3  GND_A3  SCONN168_623403212  I115
  J42     48     48  SCONN60_QSH03001LDAKTR  I44
  R577     1      A  Q_RES       I36
  R579     1      A  Q_RES       I38
  R1319    1      A  Q_RES        I2

SMB_HOST_3V3AUX_SCL_R   @S9S_MB_2U_LIB.S9S_MB_2U(SCH_1):SMB_HOST_3V3AUX_SCL_R
  R107     1      A  Q_RES       I43
  R577     2      B  Q_RES       I36
  R1525    1      A  Q_RES       I40

SMB_HOST_3V3AUX_SDA   @S9S_MB_2U_LIB.S9S_MB_2U(SCH_1):SMB_HOST_3V3AUX_SDA
  J41     A4  GND_A4  SCONN168_623403212  I115
  J42     50     50  SCONN60_QSH03001LDAKTR  I44
  R578     1      A  Q_RES       I37
  R580     1      A  Q_RES       I39
  R1321    1      A  Q_RES        I3

SMB_HOST_3V3AUX_SDA_R   @S9S_MB_2U_LIB.S9S_MB_2U(SCH_1):SMB_HOST_3V3AUX_SDA_R
  R108     1      A  Q_RES       I42
  R578     2      B  Q_RES       I37
  R1526    1      A  Q_RES       I41

SMB_HOST_BMC_3V3AUX_SCL   @S9S_MB_2U_LIB.S9S_MB_2U(SCH_1):SMB_HOST_BMC_3V3AUX_SCL
  R579     2      B  Q_RES       I38
  R633     2      B  Q_RES       I215
  U4     AF2  GPP_D_0_HS_SMBCLK_DMA_SMBCLK  EMMITSBURG_REV0P9  I93

SMB_HOST_BMC_3V3AUX_SDA   @S9S_MB_2U_LIB.S9S_MB_2U(SCH_1):SMB_HOST_BMC_3V3AUX_SDA
  R580     2      B  Q_RES       I39
  R632     2      B  Q_RES       I214
  U4     AE1  GPP_D_1_HS_SMBDATA_DMA_SMBDATA  EMMITSBURG_REV0P9  I93

SMB_HOST_CLK_3V3AUX_SCL   @S9S_MB_2U_LIB.S9S_MB_2U(SCH_1):SMB_HOST_CLK_3V3AUX_SCL
  R1525    2      B  Q_RES       I40
  U13    A10   SCLK  9SQ440NQQI8  I180

SMB_HOST_CLK_3V3AUX_SDA   @S9S_MB_2U_LIB.S9S_MB_2U(SCH_1):SMB_HOST_CLK_3V3AUX_SDA
  R1526    2      B  Q_RES       I41
  U13     B8  SMBDATTA  9SQ440NQQI8  I180

SMB_HOST_DB2000_3V3AUX_SCL   @S9S_MB_2U_LIB.S9S_MB_2U(SCH_1):SMB_HOST_DB2000_3V3AUX_SCL
  R107     2      B  Q_RES       I43
  U38     L5  SMBCLK  9QXL2001BNHGI8  I119

SMB_HOST_DB2000_3V3AUX_SDA   @S9S_MB_2U_LIB.S9S_MB_2U(SCH_1):SMB_HOST_DB2000_3V3AUX_SDA
  R108     2      B  Q_RES       I42
  U38     L4  SMBDAT  9QXL2001BNHGI8  I119

SMB_M2_P0_1V8AUX_SCL   @S9S_MB_2U_LIB.S9S_MB_2U(SCH_1):SMB_M2_P0_1V8AUX_SCL
  J59     40   NC12  SCONN75K_APCI0155P004A  I178
  R1703    2      B  Q_RES       I45
  U98      3   SCL1  PCA9306DCTR  I27

SMB_M2_P0_1V8AUX_SDA   @S9S_MB_2U_LIB.S9S_MB_2U(SCH_1):SMB_M2_P0_1V8AUX_SDA
  J59     42   NC13  SCONN75K_APCI0155P004A  I178
  R1702    2      B  Q_RES       I43
  U98      4   SDA1  PCA9306DCTR  I27

SMB_OCP_SFF_3V3AUX_R_SCL   @S9S_MB_2U_LIB.S9S_MB_2U(SCH_1):SMB_OCP_SFF_3V3AUX_R_SCL
  J37     A7  SMCLK  SCONN168_623403212  I86
  R424     1      A  Q_RES       I173

SMB_OCP_SFF_3V3AUX_R_SDA   @S9S_MB_2U_LIB.S9S_MB_2U(SCH_1):SMB_OCP_SFF_3V3AUX_R_SDA
  J37     A8  SMDAT  SCONN168_623403212  I86
  R425     1      A  Q_RES       I174

SMB_OCP_SFF_3V3AUX_SCL   @S9S_MB_2U_LIB.S9S_MB_2U(SCH_1):SMB_OCP_SFF_3V3AUX_SCL
  R424     2      B  Q_RES       I173
  R657     2      B  Q_RES       I131
  R1053    1      A  Q_RES       I108
  R2200    2      B  Q_RES       I122

SMB_OCP_SFF_3V3AUX_SDA   @S9S_MB_2U_LIB.S9S_MB_2U(SCH_1):SMB_OCP_SFF_3V3AUX_SDA
  R425     2      B  Q_RES       I174
  R658     2      B  Q_RES       I132
  R1054    1      A  Q_RES       I109
  R2201    2      B  Q_RES       I121

SMB_PCIE0_3V3AUX_SCL   @S9S_MB_2U_LIB.S9S_MB_2U(SCH_1):SMB_PCIE0_3V3AUX_SCL
  J41    A23  PERN2  SCONN168_623403212  I115
  R589     2      B  Q_RES       I153
  R2204    2      B  Q_RES       I183

SMB_PCIE0_3V3AUX_SCL_R   @S9S_MB_2U_LIB.S9S_MB_2U(SCH_1):SMB_PCIE0_3V3AUX_SCL_R
  R589     1      A  Q_RES       I153
  U36     14    SCL  PCA9546APWR  I179

SMB_PCIE0_3V3AUX_SCL_R0   @S9S_MB_2U_LIB.S9S_MB_2U(SCH_1):SMB_PCIE0_3V3AUX_SCL_R0
  R2188    2      B  Q_RES       I174
  U36      5    SC0  PCA9546APWR  I179

SMB_PCIE0_3V3AUX_SCL_R1   @S9S_MB_2U_LIB.S9S_MB_2U(SCH_1):SMB_PCIE0_3V3AUX_SCL_R1
  R660     2      B  Q_RES       I176
  U36      7    SC1  PCA9546APWR  I179

SMB_PCIE0_3V3AUX_SCL_R2   @S9S_MB_2U_LIB.S9S_MB_2U(SCH_1):SMB_PCIE0_3V3AUX_SCL_R2
  R1051    1      A  Q_RES       I178
  U36     10    SC2  PCA9546APWR  I179

SMB_PCIE0_3V3AUX_SCL_R3   @S9S_MB_2U_LIB.S9S_MB_2U(SCH_1):SMB_PCIE0_3V3AUX_SCL_R3
  R2189    1      A  Q_RES       I171
  U36     12    SC3  PCA9546APWR  I179

SMB_PCIE0_3V3AUX_SDA   @S9S_MB_2U_LIB.S9S_MB_2U(SCH_1):SMB_PCIE0_3V3AUX_SDA
  J41    A24  PERP2  SCONN168_623403212  I115
  R588     2      B  Q_RES       I154
  R2205    2      B  Q_RES       I182

SMB_PCIE0_3V3AUX_SDA_R   @S9S_MB_2U_LIB.S9S_MB_2U(SCH_1):SMB_PCIE0_3V3AUX_SDA_R
  R588     1      A  Q_RES       I154
  U36     15    SDA  PCA9546APWR  I179

SMB_PCIE0_3V3AUX_SDA_R0   @S9S_MB_2U_LIB.S9S_MB_2U(SCH_1):SMB_PCIE0_3V3AUX_SDA_R0
  R2187    2      B  Q_RES       I173
  U36      4    SD0  PCA9546APWR  I179

SMB_PCIE0_3V3AUX_SDA_R1   @S9S_MB_2U_LIB.S9S_MB_2U(SCH_1):SMB_PCIE0_3V3AUX_SDA_R1
  R659     2      B  Q_RES       I175
  U36      6    SD1  PCA9546APWR  I179

SMB_PCIE0_3V3AUX_SDA_R2   @S9S_MB_2U_LIB.S9S_MB_2U(SCH_1):SMB_PCIE0_3V3AUX_SDA_R2
  R1052    1      A  Q_RES       I177
  U36      9    SD2  PCA9546APWR  I179

SMB_PCIE0_3V3AUX_SDA_R3   @S9S_MB_2U_LIB.S9S_MB_2U(SCH_1):SMB_PCIE0_3V3AUX_SDA_R3
  R2190    1      A  Q_RES       I172
  U36     11    SD3  PCA9546APWR  I179

SMB_PCIE1_3V3AUX_SCL   @S9S_MB_2U_LIB.S9S_MB_2U(SCH_1):SMB_PCIE1_3V3AUX_SCL
  J41    A27  PERP3  SCONN168_623403212  I115
  R648     2      B  Q_RES       I184
  R914     2      B  Q_RES       I162

SMB_PCIE1_3V3AUX_SCL_R   @S9S_MB_2U_LIB.S9S_MB_2U(SCH_1):SMB_PCIE1_3V3AUX_SCL_R
  R648     1      A  Q_RES       I184
  U10     14    SCL  PCA9546APWR  I194

SMB_PCIE1_3V3AUX_SCL_R0   @S9S_MB_2U_LIB.S9S_MB_2U(SCH_1):SMB_PCIE1_3V3AUX_SCL_R0
  R1057    2      B  Q_RES       I186
  U10      5    SC0  PCA9546APWR  I194

SMB_PCIE1_3V3AUX_SCL_R1   @S9S_MB_2U_LIB.S9S_MB_2U(SCH_1):SMB_PCIE1_3V3AUX_SCL_R1
  R1059    2      B  Q_RES       I188
  U10      7    SC1  PCA9546APWR  I194

SMB_PCIE1_3V3AUX_SCL_R2   @S9S_MB_2U_LIB.S9S_MB_2U(SCH_1):SMB_PCIE1_3V3AUX_SCL_R2
  R1061    1      A  Q_RES       I131
  U10     10    SC2  PCA9546APWR  I194

SMB_PCIE1_3V3AUX_SCL_R3   @S9S_MB_2U_LIB.S9S_MB_2U(SCH_1):SMB_PCIE1_3V3AUX_SCL_R3
  R1063    1      A  Q_RES       I133
  U10     12    SC3  PCA9546APWR  I194

SMB_PCIE1_3V3AUX_SDA   @S9S_MB_2U_LIB.S9S_MB_2U(SCH_1):SMB_PCIE1_3V3AUX_SDA
  J41    A28  GND_A28  SCONN168_623403212  I115
  R647     2      B  Q_RES       I185
  R1314    2      B  Q_RES       I161

SMB_PCIE1_3V3AUX_SDA_R   @S9S_MB_2U_LIB.S9S_MB_2U(SCH_1):SMB_PCIE1_3V3AUX_SDA_R
  R647     1      A  Q_RES       I185
  U10     15    SDA  PCA9546APWR  I194

SMB_PCIE1_3V3AUX_SDA_R0   @S9S_MB_2U_LIB.S9S_MB_2U(SCH_1):SMB_PCIE1_3V3AUX_SDA_R0
  R1058    2      B  Q_RES       I187
  U10      4    SD0  PCA9546APWR  I194

SMB_PCIE1_3V3AUX_SDA_R1   @S9S_MB_2U_LIB.S9S_MB_2U(SCH_1):SMB_PCIE1_3V3AUX_SDA_R1
  R1060    2      B  Q_RES       I189
  U10      6    SD1  PCA9546APWR  I194

SMB_PCIE1_3V3AUX_SDA_R2   @S9S_MB_2U_LIB.S9S_MB_2U(SCH_1):SMB_PCIE1_3V3AUX_SDA_R2
  R1062    1      A  Q_RES       I130
  U10      9    SD2  PCA9546APWR  I194

SMB_PCIE1_3V3AUX_SDA_R3   @S9S_MB_2U_LIB.S9S_MB_2U(SCH_1):SMB_PCIE1_3V3AUX_SDA_R3
  R1064    1      A  Q_RES       I132
  U10     11    SD3  PCA9546APWR  I194

SMB_PCIE2_3V3AUX_SCL   @S9S_MB_2U_LIB.S9S_MB_2U(SCH_1):SMB_PCIE2_3V3AUX_SCL
  J41    A31  PERP4  SCONN168_623403212  I115
  R2206    2      B  Q_RES       I154
  U24     22    SCL  PCA9548APW  I60

SMB_PCIE2_3V3AUX_SDA   @S9S_MB_2U_LIB.S9S_MB_2U(SCH_1):SMB_PCIE2_3V3AUX_SDA
  J41    A32  GND_A32  SCONN168_623403212  I115
  R2207    2      B  Q_RES       I155
  U24     23    SDA  PCA9548APW  I60

SMB_PCIE3_3V3AUX_SCL   @S9S_MB_2U_LIB.S9S_MB_2U(SCH_1):SMB_PCIE3_3V3AUX_SCL
  J41    A38  GND_A38  SCONN168_623403212  I115
  R2198    2      B  Q_RES       I123
  U141    14    SCL  PCA9546APWR  I91

SMB_PCIE3_3V3AUX_SDA   @S9S_MB_2U_LIB.S9S_MB_2U(SCH_1):SMB_PCIE3_3V3AUX_SDA
  J41    A39  PERN7  SCONN168_623403212  I115
  R2199    2      B  Q_RES       I124
  U141    15    SDA  PCA9546APWR  I91

SMB_PCIE_3V3AUX_B_SCL   @S9S_MB_2U_LIB.S9S_MB_2U(SCH_1):SMB_PCIE_3V3AUX_B_SCL
  R1560    1      A  Q_RES       I395
  U122   B16  DIFFIO_RX_T2N  10M04SAU324I7G  I155

SMB_PCIE_3V3AUX_B_SDA   @S9S_MB_2U_LIB.S9S_MB_2U(SCH_1):SMB_PCIE_3V3AUX_B_SDA
  R1559    1      A  Q_RES       I394
  U122   B17  DIFFIO_RX_T2P  10M04SAU324I7G  I155

SMB_PCIE_3V3AUX_SCL   @S9S_MB_2U_LIB.S9S_MB_2U(SCH_1):SMB_PCIE_3V3AUX_SCL
  R1550    2      B  Q_RES       I392
  R1560    2      B  Q_RES       I395

SMB_PCIE_3V3AUX_SCL_R3   @S9S_MB_2U_LIB.S9S_MB_2U(SCH_1):SMB_PCIE_3V3AUX_SCL_R3
  R1055    2      B  Q_RES       I106
  U141     7    SC1  PCA9546APWR  I91

SMB_PCIE_3V3AUX_SCL_R4   @S9S_MB_2U_LIB.S9S_MB_2U(SCH_1):SMB_PCIE_3V3AUX_SCL_R4
  R1053    2      B  Q_RES       I108
  U141     5    SC0  PCA9546APWR  I91

SMB_PCIE_3V3AUX_SDA   @S9S_MB_2U_LIB.S9S_MB_2U(SCH_1):SMB_PCIE_3V3AUX_SDA
  R1549    2      B  Q_RES       I393
  R1559    2      B  Q_RES       I394

SMB_PCIE_3V3AUX_SDA_R3   @S9S_MB_2U_LIB.S9S_MB_2U(SCH_1):SMB_PCIE_3V3AUX_SDA_R3
  R1056    2      B  Q_RES       I107
  U141     6    SD1  PCA9546APWR  I91

SMB_PCIE_3V3AUX_SDA_R4   @S9S_MB_2U_LIB.S9S_MB_2U(SCH_1):SMB_PCIE_3V3AUX_SDA_R4
  R1054    2      B  Q_RES       I109
  U141     4    SD0  PCA9546APWR  I91

SMB_PCIE_M2_EN   @S9S_MB_2U_LIB.S9S_MB_2U(SCH_1):SMB_PCIE_M2_EN
  R1700    2      B  Q_RES       I48
  R1701    1      A  Q_RES       I49
  U98      8     EN  PCA9306DCTR  I27

SMB_PEHPCPU0_EDSFF1ALVC3_R_SDA   @S9S_MB_2U_LIB.S9S_MB_2U(SCH_1):SMB_PEHPCPU0_EDSFF1ALVC3_R_SDA
  J62     B9  DUALPORTEN_N  SCONN84_123318136  I33
  R1966    2      B  Q_RES       I62

SMB_PEHPCPU0_EDSFF1A_LVC3_R_SCL   @S9S_MB_2U_LIB.S9S_MB_2U(SCH_1):SMB_PEHPCPU0_EDSFF1A_LVC3_R_SCL
  J62    A10  LED_ACTIVITYA10  SCONN84_123318136  I33
  R1971    1      A  Q_RES        I6

SMB_PEHPCPU0_EDSFF1B_LVC3_R_SCL   @S9S_MB_2U_LIB.S9S_MB_2U(SCH_1):SMB_PEHPCPU0_EDSFF1B_LVC3_R_SCL
  J87    A10  LED_ACTIVITYA10  SCONN84_123318136  I43
  R1981    1      A  Q_RES        I2

SMB_PEHPCPU0_EDSFF1B_LVC3_R_SDA   @S9S_MB_2U_LIB.S9S_MB_2U(SCH_1):SMB_PEHPCPU0_EDSFF1B_LVC3_R_SDA
  J87     B9  DUALPORTEN_N  SCONN84_123318136  I43
  R1976    2      B  Q_RES       I75

SMB_PEHPCPU0_GTL_R_SCL   @S9S_MB_2U_LIB.S9S_MB_2U(SCH_1):SMB_PEHPCPU0_GTL_R_SCL
  R910     2      B  Q_RES       I24
  R960     2      B  Q_RES       I25
  U28      2   SCLA  PCA9617ADP  I39

SMB_PEHPCPU0_GTL_R_SDA   @S9S_MB_2U_LIB.S9S_MB_2U(SCH_1):SMB_PEHPCPU0_GTL_R_SDA
  R909     2      B  Q_RES       I26
  R911     2      B  Q_RES       I22
  U28      3   SDAA  PCA9617ADP  I39

SMB_PEHPCPU0_GTL_SCL   @S9S_MB_2U_LIB.S9S_MB_2U(SCH_1):SMB_PEHPCPU0_GTL_SCL
  R960     1      A  Q_RES       I25
  U2     CA25  CXPSMBUSSCL  SOCKET4677_AZIFS054P001C01   I1

SMB_PEHPCPU0_GTL_SDA   @S9S_MB_2U_LIB.S9S_MB_2U(SCH_1):SMB_PEHPCPU0_GTL_SDA
  R909     1      A  Q_RES       I26
  U2     BY26  CXPSMBUSSDA  SOCKET4677_AZIFS054P001C01   I1

SMB_PEHPCPU0_LVC3_R1_SCL   @S9S_MB_2U_LIB.S9S_MB_2U(SCH_1):SMB_PEHPCPU0_LVC3_R1_SCL
  R2101    2      B  Q_RES       I37
  U130    22    SCL  PCA9555PW    I1

SMB_PEHPCPU0_LVC3_R1_SDA   @S9S_MB_2U_LIB.S9S_MB_2U(SCH_1):SMB_PEHPCPU0_LVC3_R1_SDA
  R2102    2      B  Q_RES       I38
  U130    23    SDA  PCA9555PW    I1

SMB_PEHPCPU0_LVC3_R2_SCL   @S9S_MB_2U_LIB.S9S_MB_2U(SCH_1):SMB_PEHPCPU0_LVC3_R2_SCL
  R2103    2      B  Q_RES       I79
  U131    22    SCL  PCA9555PW   I51

SMB_PEHPCPU0_LVC3_R2_SDA   @S9S_MB_2U_LIB.S9S_MB_2U(SCH_1):SMB_PEHPCPU0_LVC3_R2_SDA
  R2104    2      B  Q_RES       I76
  U131    23    SDA  PCA9555PW   I51

SMB_PEHPCPU0_LVC3_R_SCL   @S9S_MB_2U_LIB.S9S_MB_2U(SCH_1):SMB_PEHPCPU0_LVC3_R_SCL
  R1130    2      B  Q_RES       I130
  U51     22    SCL  PCA9555PW   I125

SMB_PEHPCPU0_LVC3_R_SDA   @S9S_MB_2U_LIB.S9S_MB_2U(SCH_1):SMB_PEHPCPU0_LVC3_R_SDA
  R1131    2      B  Q_RES       I131
  U51     23    SDA  PCA9555PW   I125

SMB_PEHPCPU0_LVC3_SCL   @S9S_MB_2U_LIB.S9S_MB_2U(SCH_1):SMB_PEHPCPU0_LVC3_SCL
  R965     2      B  Q_RES       I15
  R1130    1      A  Q_RES       I130
  R1971    2      B  Q_RES        I6
  R1981    2      B  Q_RES        I2
  R2101    1      A  Q_RES       I37
  R2103    1      A  Q_RES       I79
  U28      7   SCLB  PCA9617ADP  I39

SMB_PEHPCPU0_LVC3_SDA   @S9S_MB_2U_LIB.S9S_MB_2U(SCH_1):SMB_PEHPCPU0_LVC3_SDA
  R967     2      B  Q_RES       I14
  R1131    1      A  Q_RES       I131
  R1966    1      A  Q_RES       I62
  R1976    1      A  Q_RES       I75
  R2102    1      A  Q_RES       I38
  R2104    1      A  Q_RES       I76
  U28      6   SDAB  PCA9617ADP  I39

SMB_PEHPCPU1_EDSFF4A_LVC3_R_SCL   @S9S_MB_2U_LIB.S9S_MB_2U(SCH_1):SMB_PEHPCPU1_EDSFF4A_LVC3_R_SCL
  J88    A10  LED_ACTIVITYA10  SCONN84_123318136  I16
  R1991    1      A  Q_RES       I87

SMB_PEHPCPU1_EDSFF4A_LVC3_R_SDA   @S9S_MB_2U_LIB.S9S_MB_2U(SCH_1):SMB_PEHPCPU1_EDSFF4A_LVC3_R_SDA
  J88     B9  DUALPORTEN_N  SCONN84_123318136  I16
  R1986    2      B  Q_RES       I30

SMB_PEHPCPU1_GTL_R_SCL   @S9S_MB_2U_LIB.S9S_MB_2U(SCH_1):SMB_PEHPCPU1_GTL_R_SCL
  R961     2      B  Q_RES       I49
  R963     2      B  Q_RES       I48
  U29      2   SCLA  PCA9617ADP  I43

SMB_PEHPCPU1_GTL_R_SDA   @S9S_MB_2U_LIB.S9S_MB_2U(SCH_1):SMB_PEHPCPU1_GTL_R_SDA
  R962     2      B  Q_RES       I50
  R964     2      B  Q_RES       I46
  U29      3   SDAA  PCA9617ADP  I43

SMB_PEHPCPU1_GTL_SCL   @S9S_MB_2U_LIB.S9S_MB_2U(SCH_1):SMB_PEHPCPU1_GTL_SCL
  R961     1      A  Q_RES       I49
  U1     CA25  CXPSMBUSSCL  SOCKET4677_AZIFS054P001C01  I29

SMB_PEHPCPU1_GTL_SDA   @S9S_MB_2U_LIB.S9S_MB_2U(SCH_1):SMB_PEHPCPU1_GTL_SDA
  R962     1      A  Q_RES       I50
  U1     BY26  CXPSMBUSSDA  SOCKET4677_AZIFS054P001C01  I29

SMB_PEHPCPU1_LVC3_SCL   @S9S_MB_2U_LIB.S9S_MB_2U(SCH_1):SMB_PEHPCPU1_LVC3_SCL
  R966     2      B  Q_RES       I29
  R1991    2      B  Q_RES       I87
  U29      7   SCLB  PCA9617ADP  I43

SMB_PEHPCPU1_LVC3_SDA   @S9S_MB_2U_LIB.S9S_MB_2U(SCH_1):SMB_PEHPCPU1_LVC3_SDA
  R968     2      B  Q_RES       I27
  R1986    1      A  Q_RES       I30
  U29      6   SDAB  PCA9617ADP  I43

SMB_PLD_3V3AUX_SCL   @S9S_MB_2U_LIB.S9S_MB_2U(SCH_1):SMB_PLD_3V3AUX_SCL
  J41     A1  GND_A1  SCONN168_623403212  I115
  R1761    1      A  Q_RES       I160

SMB_PLD_3V3AUX_SCL_R   @S9S_MB_2U_LIB.S9S_MB_2U(SCH_1):SMB_PLD_3V3AUX_SCL_R
  R1551    2      B  Q_RES       I234
  R1761    2      B  Q_RES       I160
  U122    J2  DIFFIO_RX_L13N  10M04SAU324I7G  I93

SMB_PLD_3V3AUX_SDA   @S9S_MB_2U_LIB.S9S_MB_2U(SCH_1):SMB_PLD_3V3AUX_SDA
  J41     A2  GND_A2  SCONN168_623403212  I115
  R1762    1      A  Q_RES       I161

SMB_PLD_3V3AUX_SDA_R   @S9S_MB_2U_LIB.S9S_MB_2U(SCH_1):SMB_PLD_3V3AUX_SDA_R
  R1467    2      B  Q_RES       I232
  R1762    2      B  Q_RES       I161
  U122    J1  DIFFIO_RX_L13P  10M04SAU324I7G  I93

SMB_PMBUS_PSU1_SCL   @S9S_MB_2U_LIB.S9S_MB_2U(SCH_1):SMB_PMBUS_PSU1_SCL
  R1537    2      B  Q_RES       I71
  R1940    2      B  Q_RES       I161

SMB_PMBUS_PSU1_SCL_R2   @S9S_MB_2U_LIB.S9S_MB_2U(SCH_1):SMB_PMBUS_PSU1_SCL_R2
  J44      6      6  CONN24_52SH90245BRD  I125
  R1940    1      A  Q_RES       I161

SMB_PMBUS_PSU1_SDA   @S9S_MB_2U_LIB.S9S_MB_2U(SCH_1):SMB_PMBUS_PSU1_SDA
  R1538    2      B  Q_RES       I72
  R1941    2      B  Q_RES       I163

SMB_PMBUS_PSU1_SDA_R2   @S9S_MB_2U_LIB.S9S_MB_2U(SCH_1):SMB_PMBUS_PSU1_SDA_R2
  J44     10     10  CONN24_52SH90245BRD  I125
  R1941    1      A  Q_RES       I163

SMB_RISER1_3V3AUX_SCL   @S9S_MB_2U_LIB.S9S_MB_2U(SCH_1):SMB_RISER1_3V3AUX_SCL
  J55     B7  GND_B7  SCONN140_G64V3431BHR  I150
  R1091    2      B  Q_RES       I30
  R2188    1      A  Q_RES       I174

SMB_RISER1_3V3AUX_SDA   @S9S_MB_2U_LIB.S9S_MB_2U(SCH_1):SMB_RISER1_3V3AUX_SDA
  J55     B8  SIGNAL_B8  SCONN140_G64V3431BHR  I150
  R1092    2      B  Q_RES       I29
  R2187    1      A  Q_RES       I173

SMB_RISER2_0_3V3AUX_SCL   @S9S_MB_2U_LIB.S9S_MB_2U(SCH_1):SMB_RISER2_0_3V3AUX_SCL
  J89    A20    A20  SCONN280_ME1028040102011  I239
  R651     2      B  Q_RES       I170
  R660     1      A  Q_RES       I176

SMB_RISER2_0_3V3AUX_SDA   @S9S_MB_2U_LIB.S9S_MB_2U(SCH_1):SMB_RISER2_0_3V3AUX_SDA
  J89    A21    A21  SCONN280_ME1028040102011  I239
  R652     2      B  Q_RES       I169
  R659     1      A  Q_RES       I175

SMB_RISER2_1_3V3AUX_SCL   @S9S_MB_2U_LIB.S9S_MB_2U(SCH_1):SMB_RISER2_1_3V3AUX_SCL
  J89    B24    B24  SCONN280_ME1028040102011  I239
  R653     2      B  Q_RES       I163
  R1051    2      B  Q_RES       I178

SMB_RISER2_1_3V3AUX_SDA   @S9S_MB_2U_LIB.S9S_MB_2U(SCH_1):SMB_RISER2_1_3V3AUX_SDA
  J89    B25    B25  SCONN280_ME1028040102011  I239
  R654     2      B  Q_RES       I164
  R1052    2      B  Q_RES       I177

SMB_RISER3_3V3AUX_SCL   @S9S_MB_2U_LIB.S9S_MB_2U(SCH_1):SMB_RISER3_3V3AUX_SCL
  J57     B7  GND_B7  SCONN140_G64V3431BHR  I242
  R655     2      B  Q_RES       I129
  R1055    1      A  Q_RES       I106
  R2202    2      B  Q_RES       I120

SMB_RISER3_3V3AUX_SDA   @S9S_MB_2U_LIB.S9S_MB_2U(SCH_1):SMB_RISER3_3V3AUX_SDA
  J57     B8  SIGNAL_B8  SCONN140_G64V3431BHR  I242
  R656     2      B  Q_RES       I130
  R1056    1      A  Q_RES       I107
  R2203    2      B  Q_RES       I119

SMB_S3M_CPU0_3V3AUX_SCL   @S9S_MB_2U_LIB.S9S_MB_2U(SCH_1):SMB_S3M_CPU0_3V3AUX_SCL
  R448     1      A  Q_RES       I13
  R977     2      B  Q_RES        I8
  R1759    1      A  Q_RES       I12
  R2208    2      B  Q_RES       I194
  U30      7   SCLB  PCA9617ADP  I28

SMB_S3M_CPU0_3V3AUX_SDA   @S9S_MB_2U_LIB.S9S_MB_2U(SCH_1):SMB_S3M_CPU0_3V3AUX_SDA
  R979     2      B  Q_RES        I6
  R1648    1      A  Q_RES        I3
  R1760    1      A  Q_RES       I11
  R2209    2      B  Q_RES       I197
  U30      6   SDAB  PCA9617ADP  I28

SMB_S3M_CPU0_LVC1_SCL   @S9S_MB_2U_LIB.S9S_MB_2U(SCH_1):SMB_S3M_CPU0_LVC1_SCL
  R973     2      B  Q_RES       I27
  R1759    2      B  Q_RES       I12
  U122    R8  DIFFIO_TX_RX_B10N  10M04SAU324I7G  I155

SMB_S3M_CPU0_LVC1_SDA   @S9S_MB_2U_LIB.S9S_MB_2U(SCH_1):SMB_S3M_CPU0_LVC1_SDA
  R974     2      B  Q_RES       I30
  R1760    2      B  Q_RES       I11
  U122    R9  DIFFIO_TX_RX_B10P  10M04SAU324I7G  I155

SMB_S3M_CPU0_R_SCL   @S9S_MB_2U_LIB.S9S_MB_2U(SCH_1):SMB_S3M_CPU0_R_SCL
  R969     2      B  Q_RES       I43
  R973     1      A  Q_RES       I27
  R993     2      B  Q_RES       I44
  U30      2   SCLA  PCA9617ADP  I28

SMB_S3M_CPU0_R_SDA   @S9S_MB_2U_LIB.S9S_MB_2U(SCH_1):SMB_S3M_CPU0_R_SDA
  R971     2      B  Q_RES       I42
  R974     1      A  Q_RES       I30
  R994     2      B  Q_RES       I45
  U30      3   SDAA  PCA9617ADP  I28

SMB_S3M_CPU0_SCL   @S9S_MB_2U_LIB.S9S_MB_2U(SCH_1):SMB_S3M_CPU0_SCL
  R993     1      A  Q_RES       I44
  U2     CE64  SMB_CLK  SOCKET4677_AZIFS054P001C01   I1

SMB_S3M_CPU0_SDA   @S9S_MB_2U_LIB.S9S_MB_2U(SCH_1):SMB_S3M_CPU0_SDA
  R994     1      A  Q_RES       I45
  U2     CD63  SMB_DATA  SOCKET4677_AZIFS054P001C01   I1

SMB_S3M_CPU1_3V3AUX_SCL   @S9S_MB_2U_LIB.S9S_MB_2U(SCH_1):SMB_S3M_CPU1_3V3AUX_SCL
  R448     2      B  Q_RES       I13
  R978     2      B  Q_RES       I16
  R1829    1      A  Q_RES       I20
  R2210    2      B  Q_RES       I193
  U31      7   SCLB  PCA9617ADP  I37

SMB_S3M_CPU1_3V3AUX_SDA   @S9S_MB_2U_LIB.S9S_MB_2U(SCH_1):SMB_S3M_CPU1_3V3AUX_SDA
  R980     2      B  Q_RES       I14
  R1648    2      B  Q_RES        I3
  R1830    1      A  Q_RES       I19
  R2211    2      B  Q_RES       I196
  U31      6   SDAB  PCA9617ADP  I37

SMB_S3M_CPU1_LVC1_SCL   @S9S_MB_2U_LIB.S9S_MB_2U(SCH_1):SMB_S3M_CPU1_LVC1_SCL
  R975     2      B  Q_RES       I39
  R1829    2      B  Q_RES       I20
  U122    N7  DIFFIO_TX_RX_B9N  10M04SAU324I7G  I155

SMB_S3M_CPU1_LVC1_SDA   @S9S_MB_2U_LIB.S9S_MB_2U(SCH_1):SMB_S3M_CPU1_LVC1_SDA
  R976     2      B  Q_RES       I40
  R1830    2      B  Q_RES       I19
  U122    N8  DIFFIO_TX_RX_B9P  10M04SAU324I7G  I155

SMB_S3M_CPU1_R_SCL   @S9S_MB_2U_LIB.S9S_MB_2U(SCH_1):SMB_S3M_CPU1_R_SCL
  R970     2      B  Q_RES       I50
  R975     1      A  Q_RES       I39
  R995     2      B  Q_RES       I51
  U31      2   SCLA  PCA9617ADP  I37

SMB_S3M_CPU1_R_SDA   @S9S_MB_2U_LIB.S9S_MB_2U(SCH_1):SMB_S3M_CPU1_R_SDA
  R972     2      B  Q_RES       I49
  R976     1      A  Q_RES       I40
  R996     2      B  Q_RES       I52
  U31      3   SDAA  PCA9617ADP  I37

SMB_S3M_CPU1_SCL   @S9S_MB_2U_LIB.S9S_MB_2U(SCH_1):SMB_S3M_CPU1_SCL
  R995     1      A  Q_RES       I51
  U1     CE64  SMB_CLK  SOCKET4677_AZIFS054P001C01   I5

SMB_S3M_CPU1_SDA   @S9S_MB_2U_LIB.S9S_MB_2U(SCH_1):SMB_S3M_CPU1_SDA
  R996     1      A  Q_RES       I52
  U1     CD63  SMB_DATA  SOCKET4677_AZIFS054P001C01   I5

SMB_S3M_CPU_3V3AUX_SCL   @S9S_MB_2U_LIB.S9S_MB_2U(SCH_1):SMB_S3M_CPU_3V3AUX_SCL
  J41    A40  PERP7  SCONN168_623403212  I115
  R2208    1      A  Q_RES       I194
  R2210    1      A  Q_RES       I193
  R2212    1      A  Q_RES       I202

SMB_S3M_CPU_3V3AUX_SDA   @S9S_MB_2U_LIB.S9S_MB_2U(SCH_1):SMB_S3M_CPU_3V3AUX_SDA
  J41    A41  GND_A41  SCONN168_623403212  I115
  R2209    1      A  Q_RES       I197
  R2211    1      A  Q_RES       I196
  R2213    1      A  Q_RES       I203

SMB_SENSOR_3V3AUX_SCL   @S9S_MB_2U_LIB.S9S_MB_2U(SCH_1):SMB_SENSOR_3V3AUX_SCL
  J41     A9  SMRST#  SCONN168_623403212  I115
  R460     1      A  Q_RES       I14
  R475     1      A  Q_RES       I39
  R726     1      A  Q_RES       I91
  R1331    2      B  Q_RES       I95
  R1336    1      A  Q_RES       I177

SMB_SENSOR_3V3AUX_SDA   @S9S_MB_2U_LIB.S9S_MB_2U(SCH_1):SMB_SENSOR_3V3AUX_SDA
  J41    A10  PRSNTA#  SCONN168_623403212  I115
  R459     1      A  Q_RES       I15
  R709     1      A  Q_RES       I37
  R725     1      A  Q_RES       I92
  R1332    2      B  Q_RES       I93
  R1460    1      A  Q_RES       I176

SMB_SENSOR_M2_P0_3V3AUX_SCL   @S9S_MB_2U_LIB.S9S_MB_2U(SCH_1):SMB_SENSOR_M2_P0_3V3AUX_SCL
  R1089    2      B  Q_RES       I31
  R2189    2      B  Q_RES       I171
  U98      6   SCL2  PCA9306DCTR  I27

SMB_SENSOR_M2_P0_3V3AUX_SDA   @S9S_MB_2U_LIB.S9S_MB_2U(SCH_1):SMB_SENSOR_M2_P0_3V3AUX_SDA
  R1090    2      B  Q_RES       I32
  R2190    2      B  Q_RES       I172
  U98      5   SDA2  PCA9306DCTR  I27

SMB_SEN_3V3AUX_SCL   @S9S_MB_2U_LIB.S9S_MB_2U(SCH_1):SMB_SEN_3V3AUX_SCL
  R1793    2      B  Q_RES       I19
  U105    10    SCL  ADS1015IDGSR   I1
  U121     5    SCL  MAX11607EUAT  I48

SMB_SEN_3V3AUX_SDA   @S9S_MB_2U_LIB.S9S_MB_2U(SCH_1):SMB_SEN_3V3AUX_SDA
  R1792    2      B  Q_RES       I20
  U105     9    SDA  ADS1015IDGSR   I1
  U121     6    SDA  MAX11607EUAT  I48

SMB_SML0B_3V3AUX_SCL   @S9S_MB_2U_LIB.S9S_MB_2U(SCH_1):SMB_SML0B_3V3AUX_SCL
  R1545    1      A  Q_RES       I137
  U4     BB3  GPPC_C_4_ME_SML0BCLK  EMMITSBURG_REV0P9  I93

SMB_SML0B_3V3AUX_SDA   @S9S_MB_2U_LIB.S9S_MB_2U(SCH_1):SMB_SML0B_3V3AUX_SDA
  R1546    1      A  Q_RES       I138
  U4     AU4  GPPC_C_3_ME_SML0BDATA  EMMITSBURG_REV0P9  I93

SMB_SML0_3V3AUX_PCH_SCL   @S9S_MB_2U_LIB.S9S_MB_2U(SCH_1):SMB_SML0_3V3AUX_PCH_SCL
  R581     2      B  Q_RES       I44
  U4     BC4  GPPC_C_0_ME_SML0CLK  EMMITSBURG_REV0P9  I93

SMB_SML0_3V3AUX_PCH_SDA   @S9S_MB_2U_LIB.S9S_MB_2U(SCH_1):SMB_SML0_3V3AUX_PCH_SDA
  R582     2      B  Q_RES       I45
  U4     BA4  GPPC_C_1_ME_SML0DATA  EMMITSBURG_REV0P9  I93

SMB_SML0_3V3AUX_SCL   @S9S_MB_2U_LIB.S9S_MB_2U(SCH_1):SMB_SML0_3V3AUX_SCL
  J41    A25  GND_A25  SCONN168_623403212  I115
  R581     1      A  Q_RES       I44
  R1384    1      A  Q_RES        I4

SMB_SML0_3V3AUX_SDA   @S9S_MB_2U_LIB.S9S_MB_2U(SCH_1):SMB_SML0_3V3AUX_SDA
  J41    A26  PERN3  SCONN168_623403212  I115
  R582     1      A  Q_RES       I45
  R1385    1      A  Q_RES        I5

SMB_SML1_PMBUS_3V3AUX_PCH_SCL   @S9S_MB_2U_LIB.S9S_MB_2U(SCH_1):SMB_SML1_PMBUS_3V3AUX_PCH_SCL
  J41     A7  SMCLK  SCONN168_623403212  I115
  R585     1      A  Q_RES       I109
  R1386    1      A  Q_RES        I6
  R1537    1      A  Q_RES       I71
  U4     AP1  GPPC_C_6_ME_SML1CLK  EMMITSBURG_REV0P9  I93

SMB_SML1_PMBUS_3V3AUX_PCH_SDA   @S9S_MB_2U_LIB.S9S_MB_2U(SCH_1):SMB_SML1_PMBUS_3V3AUX_PCH_SDA
  J41     A8  SMDAT  SCONN168_623403212  I115
  R586     1      A  Q_RES       I106
  R1387    1      A  Q_RES        I7
  R1538    1      A  Q_RES       I72
  U4     AW4  GPPC_C_7_ME_SML1DATA  EMMITSBURG_REV0P9  I93

SMB_SML1_PMBUS_3V3AUX_PLD_SCL   @S9S_MB_2U_LIB.S9S_MB_2U(SCH_1):SMB_SML1_PMBUS_3V3AUX_PLD_SCL
  R585     2      B  Q_RES       I109
  U122   F11  DIFFIO_RX_T8P  10M04SAU324I7G  I155

SMB_SML1_PMBUS_3V3AUX_PLD_SDA   @S9S_MB_2U_LIB.S9S_MB_2U(SCH_1):SMB_SML1_PMBUS_3V3AUX_PLD_SDA
  R586     2      B  Q_RES       I106
  U122   F12  DIFFIO_RX_T8N  10M04SAU324I7G  I155

SMB_TMP75_1_3V3AUX_SCL_R   @S9S_MB_2U_LIB.S9S_MB_2U(SCH_1):SMB_TMP75_1_3V3AUX_SCL_R
  R460     2      B  Q_RES       I14
  U63      2    SCL  TMP75AIDR    I1

SMB_TMP75_1_3V3AUX_SDA_R   @S9S_MB_2U_LIB.S9S_MB_2U(SCH_1):SMB_TMP75_1_3V3AUX_SDA_R
  R459     2      B  Q_RES       I15
  U63      1    SDA  TMP75AIDR    I1

SMB_TMP75_2_3V3AUX_SCL_R   @S9S_MB_2U_LIB.S9S_MB_2U(SCH_1):SMB_TMP75_2_3V3AUX_SCL_R
  R726     2      B  Q_RES       I91
  U65      2    SCL  TMP75AIDR   I84

SMB_TMP75_2_3V3AUX_SDA_R   @S9S_MB_2U_LIB.S9S_MB_2U(SCH_1):SMB_TMP75_2_3V3AUX_SDA_R
  R725     2      B  Q_RES       I92
  U65      1    SDA  TMP75AIDR   I84

SMB_VR_3V3AUX_SCL   @S9S_MB_2U_LIB.S9S_MB_2U(SCH_1):SMB_VR_3V3AUX_SCL
  J41     A5  GND_A5  SCONN168_623403212  I115
  R1661    1      A  Q_RES       I89
  R1731    1      A  Q_RES       I125

SMB_VR_3V3AUX_SCL_R   @S9S_MB_2U_LIB.S9S_MB_2U(SCH_1):SMB_VR_3V3AUX_SCL_R
  JP1      3      3  CONN3_210HP1030BR1  I123
  PR115    1      A  Q_RES       I60
  PR167    1      A  Q_RES       I64
  PR212    1      A  Q_RES       I225
  PR268    1      A  Q_RES       I43
  PR314    1      A  Q_RES       I241
  PR367    1      A  Q_RES       I35
  R1661    2      B  Q_RES       I89
  R1713    1      A  Q_RES       I130

SMB_VR_3V3AUX_SDA   @S9S_MB_2U_LIB.S9S_MB_2U(SCH_1):SMB_VR_3V3AUX_SDA
  J41     A6  GND_A6  SCONN168_623403212  I115
  R1662    1      A  Q_RES       I90
  R1732    1      A  Q_RES       I124

SMB_VR_3V3AUX_SDA_R   @S9S_MB_2U_LIB.S9S_MB_2U(SCH_1):SMB_VR_3V3AUX_SDA_R
  JP1      2      2  CONN3_210HP1030BR1  I123
  PR116    1      A  Q_RES       I59
  PR168    1      A  Q_RES       I61
  PR213    1      A  Q_RES       I226
  PR269    1      A  Q_RES       I41
  PR315    1      A  Q_RES       I239
  PR368    1      A  Q_RES       I36
  R1662    2      B  Q_RES       I90
  R1712    1      A  Q_RES       I129

SPI_PCH_CLK     @S9S_MB_2U_LIB.S9S_MB_2U(SCH_1):SPI_PCH_CLK
  R499     1      A  Q_RES       I106
  U4     BB15  SPI0_CLK  EMMITSBURG_REV0P9  I27

SPI_PCH_CS0_R_N   @S9S_MB_2U_LIB.S9S_MB_2U(SCH_1):SPI_PCH_CS0_R_N
  R501     1      A  Q_RES       I100
  U4     AW13  SPI0_FLASH_0_CS_N  EMMITSBURG_REV0P9  I27

SPI_PCH_CS1_R_N   @S9S_MB_2U_LIB.S9S_MB_2U(SCH_1):SPI_PCH_CS1_R_N
  R500     1      A  Q_RES       I101
  U4     BA10  SPI0_FLASH_1_CS_N  EMMITSBURG_REV0P9  I27

SPI_PCH_IO0     @S9S_MB_2U_LIB.S9S_MB_2U(SCH_1):SPI_PCH_IO0
  R915     1      A  Q_RES       I103
  U4     BA13  SPI0_MOSI_IO_0  EMMITSBURG_REV0P9  I27

SPI_PCH_IO1     @S9S_MB_2U_LIB.S9S_MB_2U(SCH_1):SPI_PCH_IO1
  R916     1      A  Q_RES       I105
  U4     AW16  SPI0_MISO_IO_1  EMMITSBURG_REV0P9  I27

SPI_PCH_IO2     @S9S_MB_2U_LIB.S9S_MB_2U(SCH_1):SPI_PCH_IO2
  R918     1      A  Q_RES       I104
  U4     AV15  SPI0_IO_2  EMMITSBURG_REV0P9  I27

SPI_PCH_IO3     @S9S_MB_2U_LIB.S9S_MB_2U(SCH_1):SPI_PCH_IO3
  R917     1      A  Q_RES       I107
  U4     BA16  SPI0_IO_3  EMMITSBURG_REV0P9  I27

SPI_PCH_PFR_CS1_N   @S9S_MB_2U_LIB.S9S_MB_2U(SCH_1):SPI_PCH_PFR_CS1_N
  J41    B42  PRSNTB0#  SCONN168_623403212  I115
  R500     2      B  Q_RES       I101

SPI_PCH_TPM_CS_N   @S9S_MB_2U_LIB.S9S_MB_2U(SCH_1):SPI_PCH_TPM_CS_N
  R1395    1      A  Q_RES       I102
  U4     BB11  SPI0_TPM_CS_N  EMMITSBURG_REV0P9  I27

SPI_SYS_CLK     @S9S_MB_2U_LIB.S9S_MB_2U(SCH_1):SPI_SYS_CLK
  J41    B11  +3.3V_EDGE  SCONN168_623403212  I115
  R499     2      B  Q_RES       I106

SPI_SYS_CS0_N   @S9S_MB_2U_LIB.S9S_MB_2U(SCH_1):SPI_SYS_CS0_N
  J41    B12  AUX_PWR_EN  SCONN168_623403212  I115
  R501     2      B  Q_RES       I100

SPI_SYS_HOLD_IO3   @S9S_MB_2U_LIB.S9S_MB_2U(SCH_1):SPI_SYS_HOLD_IO3
  J41    B16  GND_B16  SCONN168_623403212  I115
  R917     2      B  Q_RES       I107

SPI_SYS_MISO    @S9S_MB_2U_LIB.S9S_MB_2U(SCH_1):SPI_SYS_MISO
  J41    B14  REFCLKN0  SCONN168_623403212  I115
  R916     2      B  Q_RES       I105

SPI_SYS_MOSI    @S9S_MB_2U_LIB.S9S_MB_2U(SCH_1):SPI_SYS_MOSI
  J41    B13  GND_B13  SCONN168_623403212  I115
  R915     2      B  Q_RES       I103

SPI_SYS_WP_IO2   @S9S_MB_2U_LIB.S9S_MB_2U(SCH_1):SPI_SYS_WP_IO2
  J41    B15  REFCLKP0  SCONN168_623403212  I115
  R918     2      B  Q_RES       I104

SPI_TPM_CS_N    @S9S_MB_2U_LIB.S9S_MB_2U(SCH_1):SPI_TPM_CS_N
  J41    OCP_B12  REFCLKP2  SCONN168_623403212  I115
  R1395    2      B  Q_RES       I102

SVID_ALERT0_CPU0_N   @S9S_MB_2U_LIB.S9S_MB_2U(SCH_1):SVID_ALERT0_CPU0_N
  R14      1      A  Q_RES       I61
  U2     BK26  SVIDALERT0_N  SOCKET4677_AZIFS054P001C01   I1

SVID_ALERT0_CPU0_R_N   @S9S_MB_2U_LIB.S9S_MB_2U(SCH_1):SVID_ALERT0_CPU0_R_N
  PR114    1      A  Q_RES       I61
  PR165    1      A  Q_RES       I63
  PR530    1      A  Q_RES       I100
  R14      2      B  Q_RES       I61
  R548     1      A  Q_RES       I94

SVID_ALERT0_CPU1_N   @S9S_MB_2U_LIB.S9S_MB_2U(SCH_1):SVID_ALERT0_CPU1_N
  R57      1      A  Q_RES       I56
  U1     BK26  SVIDALERT0_N  SOCKET4677_AZIFS054P001C01  I29

SVID_ALERT0_CPU1_R_N   @S9S_MB_2U_LIB.S9S_MB_2U(SCH_1):SVID_ALERT0_CPU1_R_N
  PR267    1      A  Q_RES       I44
  PR312    1      A  Q_RES       I190
  PR577    1      A  Q_RES       I268
  R57      2      B  Q_RES       I56
  R558     1      A  Q_RES       I73

SVID_ALERT1_CPU0_N   @S9S_MB_2U_LIB.S9S_MB_2U(SCH_1):SVID_ALERT1_CPU0_N
  R17      1      A  Q_RES       I64
  U2     BJ25  SVIDALERT1_N  SOCKET4677_AZIFS054P001C01   I1

SVID_ALERT1_CPU0_R_N   @S9S_MB_2U_LIB.S9S_MB_2U(SCH_1):SVID_ALERT1_CPU0_R_N
  PR366    1      A  Q_RES       I38
  R17      2      B  Q_RES       I64
  R556     1      A  Q_RES       I100

SVID_ALERT1_CPU1_N   @S9S_MB_2U_LIB.S9S_MB_2U(SCH_1):SVID_ALERT1_CPU1_N
  R60      1      A  Q_RES       I53
  U1     BJ25  SVIDALERT1_N  SOCKET4677_AZIFS054P001C01  I29

SVID_ALERT1_CPU1_R_N   @S9S_MB_2U_LIB.S9S_MB_2U(SCH_1):SVID_ALERT1_CPU1_R_N
  PR211    1      A  Q_RES       I227
  R60      2      B  Q_RES       I53
  R560     1      A  Q_RES       I70

SVID_ALERT_PVCCD_HV_CPU0_R   @S9S_MB_2U_LIB.S9S_MB_2U(SCH_1):SVID_ALERT_PVCCD_HV_CPU0_R
  PR366    2      B  Q_RES       I38
  PU35    19  NSVALERT  ISL69260IRAZT  I51

SVID_ALERT_PVCCD_HV_CPU1_R   @S9S_MB_2U_LIB.S9S_MB_2U(SCH_1):SVID_ALERT_PVCCD_HV_CPU1_R
  PR211    2      B  Q_RES       I227
  PU18    19  NSVALERT  ISL69260IRAZT  I243

SVID_ALERT_PVCCINFAON_CPU0_R   @S9S_MB_2U_LIB.S9S_MB_2U(SCH_1):SVID_ALERT_PVCCINFAON_CPU0_R
  PR114    2      B  Q_RES       I61
  PU5     19  NSVALERT  ISL69260IRAZT  I51

SVID_ALERT_PVCCINFAON_CPU1_R   @S9S_MB_2U_LIB.S9S_MB_2U(SCH_1):SVID_ALERT_PVCCINFAON_CPU1_R
  PR267    2      B  Q_RES       I44
  PU22    19  NSVALERT  ISL69260IRAZT  I61

SVID_ALERT_PVCCIN_CPU0_R   @S9S_MB_2U_LIB.S9S_MB_2U(SCH_1):SVID_ALERT_PVCCIN_CPU0_R
  PR165    2      B  Q_RES       I63
  PU14    23  NSVALERT  RAA229126GNPHA0  I48

SVID_ALERT_PVCCIN_CPU1_R   @S9S_MB_2U_LIB.S9S_MB_2U(SCH_1):SVID_ALERT_PVCCIN_CPU1_R
  PR312    2      B  Q_RES       I190
  PU29    23  NSVALERT  RAA229126GNPHA0  I211

SVID_CLK0_CPU0   @S9S_MB_2U_LIB.S9S_MB_2U(SCH_1):SVID_CLK0_CPU0
  R13      1      A  Q_RES       I60
  U2     BH26  SVIDCLK0  SOCKET4677_AZIFS054P001C01   I1

SVID_CLK0_CPU0_R   @S9S_MB_2U_LIB.S9S_MB_2U(SCH_1):SVID_CLK0_CPU0_R
  PR112    1      A  Q_RES       I63
  PR163    1      A  Q_RES       I66
  PR529    1      A  Q_RES       I101
  R13      2      B  Q_RES       I60
  R2322    2      B  Q_RES       I22

SVID_CLK0_CPU1   @S9S_MB_2U_LIB.S9S_MB_2U(SCH_1):SVID_CLK0_CPU1
  R56      1      A  Q_RES       I55
  U1     BH26  SVIDCLK0  SOCKET4677_AZIFS054P001C01  I29

SVID_CLK0_CPU1_R   @S9S_MB_2U_LIB.S9S_MB_2U(SCH_1):SVID_CLK0_CPU1_R
  PR265    1      A  Q_RES       I45
  PR310    1      A  Q_RES       I192
  PR576    1      A  Q_RES       I269
  R56      2      B  Q_RES       I55
  R2345    2      B  Q_RES       I39

SVID_CLK1_CPU0   @S9S_MB_2U_LIB.S9S_MB_2U(SCH_1):SVID_CLK1_CPU0
  R16      1      A  Q_RES       I63
  U2     BF26  SVIDCLK1  SOCKET4677_AZIFS054P001C01   I1

SVID_CLK1_CPU0_R   @S9S_MB_2U_LIB.S9S_MB_2U(SCH_1):SVID_CLK1_CPU0_R
  PR364    1      A  Q_RES       I39
  R16      2      B  Q_RES       I63
  R1717    2      B  Q_RES       I26

SVID_CLK1_CPU1   @S9S_MB_2U_LIB.S9S_MB_2U(SCH_1):SVID_CLK1_CPU1
  R59      1      A  Q_RES       I52
  U1     BF26  SVIDCLK1  SOCKET4677_AZIFS054P001C01  I29

SVID_CLK1_CPU1_R   @S9S_MB_2U_LIB.S9S_MB_2U(SCH_1):SVID_CLK1_CPU1_R
  PR209    1      A  Q_RES       I229
  PR1718    2      B  Q_RES       I216
  R59      2      B  Q_RES       I52

SVID_CLK_PVCCD_HV_CPU0_R   @S9S_MB_2U_LIB.S9S_MB_2U(SCH_1):SVID_CLK_PVCCD_HV_CPU0_R
  PR364    2      B  Q_RES       I39
  PU35    17  SVCLK  ISL69260IRAZT  I51

SVID_CLK_PVCCD_HV_CPU1_R   @S9S_MB_2U_LIB.S9S_MB_2U(SCH_1):SVID_CLK_PVCCD_HV_CPU1_R
  PR209    2      B  Q_RES       I229
  PU18    17  SVCLK  ISL69260IRAZT  I243

SVID_CLK_PVCCINFAON_CPU0_R   @S9S_MB_2U_LIB.S9S_MB_2U(SCH_1):SVID_CLK_PVCCINFAON_CPU0_R
  PR112    2      B  Q_RES       I63
  PU5     17  SVCLK  ISL69260IRAZT  I51

SVID_CLK_PVCCINFAON_CPU1_R   @S9S_MB_2U_LIB.S9S_MB_2U(SCH_1):SVID_CLK_PVCCINFAON_CPU1_R
  PR265    2      B  Q_RES       I45
  PU22    17  SVCLK  ISL69260IRAZT  I61

SVID_CLK_PVCCIN_CPU0_R   @S9S_MB_2U_LIB.S9S_MB_2U(SCH_1):SVID_CLK_PVCCIN_CPU0_R
  PR163    2      B  Q_RES       I66
  PU14    21  SVCLK  RAA229126GNPHA0  I48

SVID_CLK_PVCCIN_CPU1_R   @S9S_MB_2U_LIB.S9S_MB_2U(SCH_1):SVID_CLK_PVCCIN_CPU1_R
  PR310    2      B  Q_RES       I192
  PU29    21  SVCLK  RAA229126GNPHA0  I211

SVID_DIO0_CPU0   @S9S_MB_2U_LIB.S9S_MB_2U(SCH_1):SVID_DIO0_CPU0
  R12      1      A  Q_RES       I59
  U2     BD26  SVIDDATA0  SOCKET4677_AZIFS054P001C01   I1

SVID_DIO0_CPU0_R   @S9S_MB_2U_LIB.S9S_MB_2U(SCH_1):SVID_DIO0_CPU0_R
  PR113    1      A  Q_RES       I62
  PR164    1      A  Q_RES       I65
  PR528    1      A  Q_RES       I102
  R12      2      B  Q_RES       I59
  R328     1      A  Q_RES       I93
  R561     2      B  Q_RES       I21

SVID_DIO0_CPU1   @S9S_MB_2U_LIB.S9S_MB_2U(SCH_1):SVID_DIO0_CPU1
  R55      1      A  Q_RES       I54
  U1     BD26  SVIDDATA0  SOCKET4677_AZIFS054P001C01  I29

SVID_DIO0_CPU1_R   @S9S_MB_2U_LIB.S9S_MB_2U(SCH_1):SVID_DIO0_CPU1_R
  PR266    1      A  Q_RES       I46
  PR311    1      A  Q_RES       I191
  PR575    1      A  Q_RES       I272
  R55      2      B  Q_RES       I54
  R557     1      A  Q_RES       I74
  R2354    2      B  Q_RES       I38

SVID_DIO1_CPU0   @S9S_MB_2U_LIB.S9S_MB_2U(SCH_1):SVID_DIO1_CPU0
  R15      1      A  Q_RES       I62
  U2     BL25  SVIDDATA1  SOCKET4677_AZIFS054P001C01   I1

SVID_DIO1_CPU0_R   @S9S_MB_2U_LIB.S9S_MB_2U(SCH_1):SVID_DIO1_CPU0_R
  PR365    1      A  Q_RES       I37
  R15      2      B  Q_RES       I62
  R555     1      A  Q_RES       I98
  R1735    2      B  Q_RES       I25

SVID_DIO1_CPU1   @S9S_MB_2U_LIB.S9S_MB_2U(SCH_1):SVID_DIO1_CPU1
  R58      1      A  Q_RES       I51
  U1     BL25  SVIDDATA1  SOCKET4677_AZIFS054P001C01  I29

SVID_DIO1_CPU1_R   @S9S_MB_2U_LIB.S9S_MB_2U(SCH_1):SVID_DIO1_CPU1_R
  PR210    1      A  Q_RES       I228
  PR1747    2      B  Q_RES       I217
  R58      2      B  Q_RES       I51
  R559     1      A  Q_RES       I69

SVID_DIO_PVCCD_HV_CPU0_R   @S9S_MB_2U_LIB.S9S_MB_2U(SCH_1):SVID_DIO_PVCCD_HV_CPU0_R
  PR365    2      B  Q_RES       I37
  PU35    18  SVDATA  ISL69260IRAZT  I51

SVID_DIO_PVCCD_HV_CPU1_R   @S9S_MB_2U_LIB.S9S_MB_2U(SCH_1):SVID_DIO_PVCCD_HV_CPU1_R
  PR210    2      B  Q_RES       I228
  PU18    18  SVDATA  ISL69260IRAZT  I243

SVID_DIO_PVCCINFAON_CPU0_R   @S9S_MB_2U_LIB.S9S_MB_2U(SCH_1):SVID_DIO_PVCCINFAON_CPU0_R
  PR113    2      B  Q_RES       I62
  PU5     18  SVDATA  ISL69260IRAZT  I51

SVID_DIO_PVCCINFAON_CPU1_R   @S9S_MB_2U_LIB.S9S_MB_2U(SCH_1):SVID_DIO_PVCCINFAON_CPU1_R
  PR266    2      B  Q_RES       I46
  PU22    18  SVDATA  ISL69260IRAZT  I61

SVID_DIO_PVCCIN_CPU0_R   @S9S_MB_2U_LIB.S9S_MB_2U(SCH_1):SVID_DIO_PVCCIN_CPU0_R
  PR164    2      B  Q_RES       I65
  PU14    22  SVDATA  RAA229126GNPHA0  I48

SVID_DIO_PVCCIN_CPU1_R   @S9S_MB_2U_LIB.S9S_MB_2U(SCH_1):SVID_DIO_PVCCIN_CPU1_R
  PR311    2      B  Q_RES       I191
  PU29    22  SVDATA  RAA229126GNPHA0  I211

SW_P12V_AUX_P1V05_PCH_AUX_FLT   @S9S_MB_2U_LIB.S9S_MB_2U(SCH_1):SW_P12V_AUX_P1V05_PCH_AUX_FLT
  PC1215    1      A  Q_CAPP       I5
  PC1216    1      A  Q_CAP       I24
  PC1217    1      A  Q_CAP       I28
  PC1218    1      A  Q_CAP       I32
  PC1219    1      A  Q_CAP       I33
  PL110    2      2  Q_INDUCTOR   I2
  PU73    10   VIN1  MPQ8633BGLEC838Z  I34
  PU73    21   VIN2  MPQ8633BGLEC838Z  I34

SW_P12V_PVCCFA_EHV_FIVRA_CPU0_L   @S9S_MB_2U_LIB.S9S_MB_2U(SCH_1):SW_P12V_PVCCFA_EHV_FIVRA_CPU0_L
  PC1174_P0_4    1      A  Q_CAP       I31
  PC1176_P0_4    1      A  Q_CAP       I32
  PC1180_P0_4    1      A  Q_CAP       I34
  PC1182_P0_4    1      A  Q_CAP       I35
  PC603_P0_2    1      A  Q_CAP       I38
  PC605_P0_2    1      A  Q_CAP       I39
  PC609_P0_2    1      A  Q_CAP       I41
  PC611_P0_2    1      A  Q_CAP       I42
  PC622    1      A  Q_CAPP      I77
  PC721_P0_2    1      A  Q_CAP       I86
  PC723_P0_4    1      A  Q_CAP       I79
  PL44     2      2  Q_INDUCTOR  I74
  PU70_P0_2  25_29   VIN1  ISL99390FRZTR5935  I30
  PU70_P0_2   30   VIN2  ISL99390FRZTR5935  I30
  PU72_P0_4  25_29   VIN1  ISL99390FRZTR5935  I24
  PU72_P0_4   30   VIN2  ISL99390FRZTR5935  I24

SW_P12V_PVCCFA_EHV_FIVRA_CPU0_R   @S9S_MB_2U_LIB.S9S_MB_2U(SCH_1):SW_P12V_PVCCFA_EHV_FIVRA_CPU0_R
  PC1173_P0_3    1      A  Q_CAP       I43
  PC1175_P0_3    1      A  Q_CAP       I44
  PC1179_P0_3    1      A  Q_CAP       I46
  PC1181_P0_3    1      A  Q_CAP       I50
  PC1189    1      A  Q_CAPP      I73
  PC602_P0_1    1      A  Q_CAP       I49
  PC604_P0_1    1      A  Q_CAP       I50
  PC608_P0_1    1      A  Q_CAP       I52
  PC610_P0_1    1      A  Q_CAP       I56
  PC720_P0_1    1      A  Q_CAP       I85
  PC722_P0_3    1      A  Q_CAP       I78
  PL101    2      2  Q_INDUCTOR  I69
  PU69_P0_1  25_29   VIN1  ISL99390FRZTR5935  I35
  PU69_P0_1   30   VIN2  ISL99390FRZTR5935  I35
  PU71_P0_3  25_29   VIN1  ISL99390FRZTR5935  I40
  PU71_P0_3   30   VIN2  ISL99390FRZTR5935  I40

SW_P12V_PVCCFA_EHV_FIVRA_CPU1_L   @S9S_MB_2U_LIB.S9S_MB_2U(SCH_1):SW_P12V_PVCCFA_EHV_FIVRA_CPU1_L
  PC1194_P1_4    1      A  Q_CAP       I33
  PC1196_P1_4    1      A  Q_CAP       I35
  PC1200_P1_4    1      A  Q_CAP       I36
  PC1202_P1_4    1      A  Q_CAP       I37
  PC398_P1_2    1      A  Q_CAP       I223
  PC400_P1_2    1      A  Q_CAP       I243
  PC404_P1_2    1      A  Q_CAP       I244
  PC406_P1_2    1      A  Q_CAP       I245
  PC417    1      A  Q_CAPP      I275
  PC725_P1_2    1      A  Q_CAP       I286
  PC727_P1_4    1      A  Q_CAP       I84
  PL43     2      2  Q_INDUCTOR  I266
  PU76_P1_2  25_29   VIN1  ISL99390FRZTR5935  I221
  PU76_P1_2   30   VIN2  ISL99390FRZTR5935  I221
  PU78_P1_4  25_29   VIN1  ISL99390FRZTR5935  I24
  PU78_P1_4   30   VIN2  ISL99390FRZTR5935  I24

SW_P12V_PVCCFA_EHV_FIVRA_CPU1_R   @S9S_MB_2U_LIB.S9S_MB_2U(SCH_1):SW_P12V_PVCCFA_EHV_FIVRA_CPU1_R
  PC1193_P1_3    1      A  Q_CAP       I44
  PC1195_P1_3    1      A  Q_CAP       I45
  PC1199_P1_3    1      A  Q_CAP       I46
  PC1201_P1_3    1      A  Q_CAP       I51
  PC1210    1      A  Q_CAPP      I73
  PC397_P1_1    1      A  Q_CAP       I238
  PC399_P1_1    1      A  Q_CAP       I257
  PC403_P1_1    1      A  Q_CAP       I258
  PC405_P1_1    1      A  Q_CAP       I259
  PC724_P1_1    1      A  Q_CAP       I285
  PC726_P1_3    1      A  Q_CAP       I83
  PL14     2      2  Q_INDUCTOR  I69
  PU75_P1_1  25_29   VIN1  ISL99390FRZTR5935  I278
  PU75_P1_1   30   VIN2  ISL99390FRZTR5935  I278
  PU77_P1_3  25_29   VIN1  ISL99390FRZTR5935  I27
  PU77_P1_3   30   VIN2  ISL99390FRZTR5935  I27

SW_P12V_PVCCINFAON_CPU0_FLT   @S9S_MB_2U_LIB.S9S_MB_2U(SCH_1):SW_P12V_PVCCINFAON_CPU0_FLT
  PC176    1      A  Q_CAP       I18
  PC177    1      A  Q_CAP       I31
  PC179    1      A  Q_CAP       I35
  PC180    1      A  Q_CAP       I32
  PC1272    1      A  Q_CAP       I164
  PC1273    1      A  Q_CAP       I165
  PC1274    1      A  Q_CAP       I166
  PC189_P0_1    1      A  Q_CAP       I178
  PC190_P0_2    1      A  Q_CAP       I167
  PC191_P0_1    1      A  Q_CAP       I179
  PC192_P0_2    1      A  Q_CAP       I168
  PC195_P0_1    1      A  Q_CAP       I204
  PC196_P0_2    1      A  Q_CAP       I186
  PC197_P0_1    1      A  Q_CAP       I206
  PC198_P0_2    1      A  Q_CAP       I187
  PC207    1      A  Q_CAPP      I213
  PC208    1      A  Q_CAPP      I214
  PC634    1      A  Q_CAP       I340
  PC635    1      A  Q_CAP       I357
  PC637    1      A  Q_CAP       I358
  PC638    1      A  Q_CAP       I359
  PL6      2      2  Q_INDUCTOR  I211
  PU36   16_18-28    VIN  RAA2213404GNPHB0  I333
  PU42   16_18-28    VIN  RAA2213404GNPHB0  I11
  PU43_P0_1  16_18-28    VIN  RAA2213404GNPHB0  I166
  PU44_P0_2  16_18-28    VIN  RAA2213404GNPHB0  I164
  PU81     3    VIN  MPQ8626GDZ  I190

SW_P12V_PVCCINFAON_CPU1_FLT   @S9S_MB_2U_LIB.S9S_MB_2U(SCH_1):SW_P12V_PVCCINFAON_CPU1_FLT
  PC374    1      A  Q_CAP       I18
  PC375    1      A  Q_CAP       I20
  PC377    1      A  Q_CAP       I29
  PC378    1      A  Q_CAP       I30
  PC429    1      A  Q_CAP       I20
  PC430    1      A  Q_CAP       I21
  PC432    1      A  Q_CAP       I22
  PC433    1      A  Q_CAP       I27
  PC1280    1      A  Q_CAP       I169
  PC1281    1      A  Q_CAP       I170
  PC1282    1      A  Q_CAP       I175
  PC442_P1_1    1      A  Q_CAP       I50
  PC443_P1_2    1      A  Q_CAP       I34
  PC444_P1_1    1      A  Q_CAP       I51
  PC445_P1_2    1      A  Q_CAP       I36
  PC448_P1_1    1      A  Q_CAP       I56
  PC449_P1_2    1      A  Q_CAP       I38
  PC450_P1_1    1      A  Q_CAP       I57
  PC451_P1_2    1      A  Q_CAP       I39
  PC460    1      A  Q_CAPP      I74
  PC461    1      A  Q_CAPP      I75
  PL23     2      2  Q_INDUCTOR  I65
  PU17   16_18-28    VIN  RAA2213404GNPHB0  I38
  PU49   16_18-28    VIN  RAA2213404GNPHB0  I14
  PU50_P1_1  16_18-28    VIN  RAA2213404GNPHB0  I17
  PU51_P1_2  16_18-28    VIN  RAA2213404GNPHB0  I12
  PU82     3    VIN  MPQ8626GDZ  I198

SW_P12V_PVCCIN_CPU0_FLT   @S9S_MB_2U_LIB.S9S_MB_2U(SCH_1):SW_P12V_PVCCIN_CPU0_FLT
  PC230_P0_8    1      A  Q_CAP       I36
  PC231_P0_7    1      A  Q_CAP       I50
  PC232_P0_8    1      A  Q_CAP       I37
  PC233_P0_7    1      A  Q_CAP       I51
  PC236_P0_8    1      A  Q_CAP       I38
  PC237_P0_7    1      A  Q_CAP       I52
  PC238_P0_8    1      A  Q_CAP       I39
  PC239_P0_7    1      A  Q_CAP       I57
  PC240_P0_8    1      A  Q_CAP       I40
  PC241_P0_7    1      A  Q_CAP       I58
  PC252_P0_6    1      A  Q_CAP       I15
  PC253_P0_5    1      A  Q_CAP       I38
  PC254_P0_6    1      A  Q_CAP       I18
  PC255_P0_5    1      A  Q_CAP       I39
  PC258_P0_6    1      A  Q_CAP       I19
  PC259_P0_5    1      A  Q_CAP       I40
  PC260_P0_6    1      A  Q_CAP       I41
  PC261_P0_5    1      A  Q_CAP       I59
  PC262_P0_6    1      A  Q_CAP       I45
  PC263_P0_5    1      A  Q_CAP       I60
  PC274_P0_4    1      A  Q_CAP       I36
  PC275_P0_3    1      A  Q_CAP       I48
  PC276_P0_4    1      A  Q_CAP       I37
  PC277_P0_3    1      A  Q_CAP       I50
  PC280_P0_4    1      A  Q_CAP       I38
  PC281_P0_3    1      A  Q_CAP       I51
  PC282_P0_4    1      A  Q_CAP       I40
  PC283_P0_3    1      A  Q_CAP       I55
  PC284_P0_4    1      A  Q_CAP       I42
  PC285_P0_3    1      A  Q_CAP       I56
  PC296_P0_2    1      A  Q_CAP       I22
  PC297_P0_1    1      A  Q_CAP       I40
  PC298_P0_2    1      A  Q_CAP       I23
  PC299_P0_1    1      A  Q_CAP       I41
  PC302_P0_2    1      A  Q_CAP       I24
  PC303_P0_1    1      A  Q_CAP       I65
  PC304_P0_2    1      A  Q_CAP       I46
  PC305_P0_1    1      A  Q_CAP       I66
  PC306_P0_2    1      A  Q_CAP       I47
  PC307_P0_1    1      A  Q_CAP       I67
  PC315    1      A  Q_CAPP      I74
  PC318    1      A  Q_CAPP      I76
  PC321    1      A  Q_CAPP      I77
  PC324    1      A  Q_CAPP      I84
  PC831    1      A  Q_CAP       I44
  PC1247    1      A  Q_CAP       I10
  PC1248    1      A  Q_CAP       I17
  PC1249    1      A  Q_CAP       I18
  PL15     2      2  Q_INDUCTOR  I75
  PU10_P0_4  25_29   VIN1  ISL99390FRZTR5935  I14
  PU10_P0_4   30   VIN2  ISL99390FRZTR5935  I14
  PU11_P0_3  25_29   VIN1  ISL99390FRZTR5935  I30
  PU11_P0_3   30   VIN2  ISL99390FRZTR5935  I30
  PU12_P0_2  25_29   VIN1  ISL99390FRZTR5935  I87
  PU12_P0_2   30   VIN2  ISL99390FRZTR5935  I87
  PU13_P0_1  25_29   VIN1  ISL99390FRZTR5935  I21
  PU13_P0_1   30   VIN2  ISL99390FRZTR5935  I21
  PU6_P0_8  25_29   VIN1  ISL99390FRZTR5935  I64
  PU6_P0_8   30   VIN2  ISL99390FRZTR5935  I64
  PU79    10   VIN1  MPQ8633AGLEC807Z  I13
  PU79    21   VIN2  MPQ8633AGLEC807Z  I13
  PU7_P0_7  25_29   VIN1  ISL99390FRZTR5935  I20
  PU7_P0_7   30   VIN2  ISL99390FRZTR5935  I20
  PU8_P0_6  25_29   VIN1  ISL99390FRZTR5935  I62
  PU8_P0_6   30   VIN2  ISL99390FRZTR5935  I62
  PU9_P0_5  25_29   VIN1  ISL99390FRZTR5935  I31
  PU9_P0_5   30   VIN2  ISL99390FRZTR5935  I31

SW_P12V_PVCCIN_CPU1_FLT   @S9S_MB_2U_LIB.S9S_MB_2U(SCH_1):SW_P12V_PVCCIN_CPU1_FLT
  PC1259    1      A  Q_CAP        I4
  PC1260    1      A  Q_CAP       I19
  PC1261    1      A  Q_CAP       I20
  PC1262    1      A  Q_CAP       I21
  PC483_P1_8    1      A  Q_CAP       I38
  PC484_P1_7    1      A  Q_CAP       I46
  PC485_P1_8    1      A  Q_CAP       I40
  PC486_P1_7    1      A  Q_CAP       I48
  PC489_P1_8    1      A  Q_CAP       I42
  PC490_P1_7    1      A  Q_CAP       I52
  PC491_P1_8    1      A  Q_CAP       I43
  PC492_P1_7    1      A  Q_CAP       I53
  PC493_P1_8    1      A  Q_CAP       I44
  PC494_P1_7    1      A  Q_CAP       I54
  PC505_P1_6    1      A  Q_CAP       I37
  PC506_P1_5    1      A  Q_CAP       I48
  PC507_P1_6    1      A  Q_CAP       I38
  PC508_P1_5    1      A  Q_CAP       I49
  PC511_P1_6    1      A  Q_CAP       I39
  PC512_P1_5    1      A  Q_CAP       I50
  PC513_P1_6    1      A  Q_CAP       I44
  PC514_P1_5    1      A  Q_CAP       I54
  PC515_P1_6    1      A  Q_CAP       I45
  PC516_P1_5    1      A  Q_CAP       I56
  PC527_P1_4    1      A  Q_CAP       I32
  PC528_P1_3    1      A  Q_CAP       I46
  PC529_P1_4    1      A  Q_CAP       I35
  PC530_P1_3    1      A  Q_CAP       I48
  PC533_P1_4    1      A  Q_CAP       I36
  PC534_P1_3    1      A  Q_CAP       I49
  PC535_P1_4    1      A  Q_CAP       I42
  PC536_P1_3    1      A  Q_CAP       I53
  PC537_P1_4    1      A  Q_CAP       I43
  PC538_P1_3    1      A  Q_CAP       I54
  PC560_P1_2    1      A  Q_CAP       I21
  PC561_P1_1    1      A  Q_CAP       I38
  PC562_P1_2    1      A  Q_CAP       I39
  PC563_P1_1    1      A  Q_CAP       I40
  PC566_P1_2    1      A  Q_CAP       I44
  PC567_P1_1    1      A  Q_CAP       I61
  PC568_P1_2    1      A  Q_CAP       I45
  PC569_P1_1    1      A  Q_CAP       I62
  PC570_P1_2    1      A  Q_CAP       I46
  PC571_P1_1    1      A  Q_CAP       I66
  PC579    1      A  Q_CAPP      I73
  PC582    1      A  Q_CAPP      I74
  PC585    1      A  Q_CAPP      I83
  PC588    1      A  Q_CAPP      I84
  PL32     2      2  Q_INDUCTOR  I71
  PU23_P1_8  25_29   VIN1  ISL99390FRZTR5935   I9
  PU23_P1_8   30   VIN2  ISL99390FRZTR5935   I9
  PU24_P1_7  25_29   VIN1  ISL99390FRZTR5935  I37
  PU24_P1_7   30   VIN2  ISL99390FRZTR5935  I37
  PU25_P1_6  25_29   VIN1  ISL99390FRZTR5935  I23
  PU25_P1_6   30   VIN2  ISL99390FRZTR5935  I23
  PU26_P1_5  25_29   VIN1  ISL99390FRZTR5935  I32
  PU26_P1_5   30   VIN2  ISL99390FRZTR5935  I32
  PU27_P1_4  25_29   VIN1  ISL99390FRZTR5935   I9
  PU27_P1_4   30   VIN2  ISL99390FRZTR5935   I9
  PU28_P1_3  25_29   VIN1  ISL99390FRZTR5935  I18
  PU28_P1_3   30   VIN2  ISL99390FRZTR5935  I18
  PU30_P1_2  25_29   VIN1  ISL99390FRZTR5935  I18
  PU30_P1_2   30   VIN2  ISL99390FRZTR5935  I18
  PU31_P1_1  25_29   VIN1  ISL99390FRZTR5935  I20
  PU31_P1_1   30   VIN2  ISL99390FRZTR5935  I20
  PU80    10   VIN1  MPQ8633AGLEC807Z  I15
  PU80    21   VIN2  MPQ8633AGLEC807Z  I15

SW_P1V05_PCH_AUX_BST   @S9S_MB_2U_LIB.S9S_MB_2U(SCH_1):SW_P1V05_PCH_AUX_BST
  PC1222    1      A  Q_CAP       I37
  PU73     1    BST  MPQ8633BGLEC838Z  I34

SW_P1V05_PCH_AUX_SW   @S9S_MB_2U_LIB.S9S_MB_2U(SCH_1):SW_P1V05_PCH_AUX_SW
  PC1222    2      B  Q_CAP       I37
  PL150    1      1  Q_INDUCTOR  I43
  PU73    20     SW  MPQ8633BGLEC838Z  I34

SW_P1V8_PCH_AUX_BST   @S9S_MB_2U_LIB.S9S_MB_2U(SCH_1):SW_P1V8_PCH_AUX_BST
  PC1235    1      A  Q_CAP       I32
  PU74     9    BST  NB695GDZ    I20

SW_P1V8_PCH_AUX_FLT   @S9S_MB_2U_LIB.S9S_MB_2U(SCH_1):SW_P1V8_PCH_AUX_FLT
  PC1232    1      A  Q_CAP       I28
  PC1233    1      A  Q_CAP       I30
  PC1234    1      A  Q_CAP       I31
  PL16     2      2  Q_INDUCTOR  I26
  PU74     1    VIN  NB695GDZ    I20

SW_P1V8_PCH_AUX_SW   @S9S_MB_2U_LIB.S9S_MB_2U(SCH_1):SW_P1V8_PCH_AUX_SW
  PC1235    2      B  Q_CAP       I32
  PL170    1      1  Q_INDUCTOR  I22
  PU74     8     SW  NB695GDZ    I20

SW_P3V3_AUX_BOOT   @S9S_MB_2U_LIB.S9S_MB_2U(SCH_1):SW_P3V3_AUX_BOOT
  PR835    1      A  Q_RES       I29
  PU9     26   BOOT  NCP3284MNTXG  I23

SW_P3V3_AUX_BOOTR   @S9S_MB_2U_LIB.S9S_MB_2U(SCH_1):SW_P3V3_AUX_BOOTR
  PC568    1      A  Q_CAP       I28
  PU9     25  PHASE  NCP3284MNTXG  I23

SW_P3V3_AUX_BOOT_R   @S9S_MB_2U_LIB.S9S_MB_2U(SCH_1):SW_P3V3_AUX_BOOT_R
  PC568    2      B  Q_CAP       I28
  PR835    2      B  Q_RES       I29

SW_P3V3_AUX_FLT   @S9S_MB_2U_LIB.S9S_MB_2U(SCH_1):SW_P3V3_AUX_FLT
  PC71     1      A  Q_CAP       I22
  PC566    1      A  Q_CAPP       I4
  PC567    1      A  Q_CAP        I5
  PC570    1      A  Q_CAP       I18
  PC571    1      A  Q_CAP       I19
  PC576    1      A  Q_CAP       I20
  PC577    1      A  Q_CAP       I21
  PL45     2      2  Q_INDUCTOR   I3
  PU9    20_24   PVIN  NCP3284MNTXG  I23

SW_P3V3_AUX_SW   @S9S_MB_2U_LIB.S9S_MB_2U(SCH_1):SW_P3V3_AUX_SW
  PL66     1      1  Q_INDUCTOR  I37
  PU9    11_18     SW  NCP3284MNTXG  I23

SW_P5V_AUX_BST   @S9S_MB_2U_LIB.S9S_MB_2U(SCH_1):SW_P5V_AUX_BST
  PC1847    1      A  Q_CAP       I26
  PU181    1    BST  MPQ8633BGLEC838Z  I19

SW_P5V_AUX_FLT   @S9S_MB_2U_LIB.S9S_MB_2U(SCH_1):SW_P5V_AUX_FLT
  PC1846    1      A  Q_CAP       I18
  PC1849    1      A  Q_CAP       I12
  PC1850    1      A  Q_CAP       I14
  PC1898    1      A  Q_CAP       I17
  PL64     2      2  Q_INDUCTOR   I5
  PU181   10   VIN1  MPQ8633BGLEC838Z  I19
  PU181   21   VIN2  MPQ8633BGLEC838Z  I19

SW_P5V_AUX_SW   @S9S_MB_2U_LIB.S9S_MB_2U(SCH_1):SW_P5V_AUX_SW
  PC1847    2      B  Q_CAP       I26
  PL65     1      1  Q_INDUCTOR  I29
  PU181   20     SW  MPQ8633BGLEC838Z  I19

SW_PVCCD_HV_CPU0_BOOT1   @S9S_MB_2U_LIB.S9S_MB_2U(SCH_1):SW_PVCCD_HV_CPU0_BOOT1
  PR1784    1      A  Q_RES       I341
  PU36    20   BOOT  RAA2213404GNPHB0  I333

SW_PVCCD_HV_CPU0_BOOT1_R   @S9S_MB_2U_LIB.S9S_MB_2U(SCH_1):SW_PVCCD_HV_CPU0_BOOT1_R
  PC636    1      A  Q_CAP       I344
  PR1784    2      B  Q_RES       I341

SW_PVCCD_HV_CPU0_BOOTR1   @S9S_MB_2U_LIB.S9S_MB_2U(SCH_1):SW_PVCCD_HV_CPU0_BOOTR1
  PC636    2      B  Q_CAP       I344
  PU36    19  PHASE  RAA2213404GNPHB0  I333

SW_PVCCD_HV_CPU0_SW1   @S9S_MB_2U_LIB.S9S_MB_2U(SCH_1):SW_PVCCD_HV_CPU0_SW1
  PL35     1      1  Q_INDUCTOR  I345
  PU36   8_12     SW  RAA2213404GNPHB0  I333

SW_PVCCD_HV_CPU1_BOOT1   @S9S_MB_2U_LIB.S9S_MB_2U(SCH_1):SW_PVCCD_HV_CPU1_BOOT1
  PR1804    1      A  Q_RES       I19
  PU17    20   BOOT  RAA2213404GNPHB0  I38

SW_PVCCD_HV_CPU1_BOOT1_R   @S9S_MB_2U_LIB.S9S_MB_2U(SCH_1):SW_PVCCD_HV_CPU1_BOOT1_R
  PC376    1      A  Q_CAP       I25
  PR1804    2      B  Q_RES       I19

SW_PVCCD_HV_CPU1_BOOTR1   @S9S_MB_2U_LIB.S9S_MB_2U(SCH_1):SW_PVCCD_HV_CPU1_BOOTR1
  PC376    2      B  Q_CAP       I25
  PU17    19  PHASE  RAA2213404GNPHB0  I38

SW_PVCCD_HV_CPU1_SW1   @S9S_MB_2U_LIB.S9S_MB_2U(SCH_1):SW_PVCCD_HV_CPU1_SW1
  PL17     1      1  Q_INDUCTOR  I26
  PU17   8_12     SW  RAA2213404GNPHB0  I38

SW_PVCCFA_EHV_CPU0_BOOT1   @S9S_MB_2U_LIB.S9S_MB_2U(SCH_1):SW_PVCCFA_EHV_CPU0_BOOT1
  PR1778    1      A  Q_RES       I30
  PU42    20   BOOT  RAA2213404GNPHB0  I11

SW_PVCCFA_EHV_CPU0_BOOT1_R   @S9S_MB_2U_LIB.S9S_MB_2U(SCH_1):SW_PVCCFA_EHV_CPU0_BOOT1_R
  PC178    1      A  Q_CAP       I21
  PR1778    2      B  Q_RES       I30

SW_PVCCFA_EHV_CPU0_BOOTR1   @S9S_MB_2U_LIB.S9S_MB_2U(SCH_1):SW_PVCCFA_EHV_CPU0_BOOTR1
  PC178    2      B  Q_CAP       I21
  PU42    19  PHASE  RAA2213404GNPHB0  I11

SW_PVCCFA_EHV_CPU0_SW1   @S9S_MB_2U_LIB.S9S_MB_2U(SCH_1):SW_PVCCFA_EHV_CPU0_SW1
  PL3      1      1  Q_INDUCTOR  I23
  PU42   8_12     SW  RAA2213404GNPHB0  I11

SW_PVCCFA_EHV_CPU1_BOOT1   @S9S_MB_2U_LIB.S9S_MB_2U(SCH_1):SW_PVCCFA_EHV_CPU1_BOOT1
  PR1798    1      A  Q_RES       I18
  PU49    20   BOOT  RAA2213404GNPHB0  I14

SW_PVCCFA_EHV_CPU1_BOOT1_R   @S9S_MB_2U_LIB.S9S_MB_2U(SCH_1):SW_PVCCFA_EHV_CPU1_BOOT1_R
  PC431    1      A  Q_CAP       I24
  PR1798    2      B  Q_RES       I18

SW_PVCCFA_EHV_CPU1_BOOTR1   @S9S_MB_2U_LIB.S9S_MB_2U(SCH_1):SW_PVCCFA_EHV_CPU1_BOOTR1
  PC431    2      B  Q_CAP       I24
  PU49    19  PHASE  RAA2213404GNPHB0  I14

SW_PVCCFA_EHV_CPU1_SW1   @S9S_MB_2U_LIB.S9S_MB_2U(SCH_1):SW_PVCCFA_EHV_CPU1_SW1
  PL20     1      1  Q_INDUCTOR  I23
  PU49   8_12     SW  RAA2213404GNPHB0  I14

SW_PVCCFA_EHV_FIVRA_CPU0_BOOT1   @S9S_MB_2U_LIB.S9S_MB_2U(SCH_1):SW_PVCCFA_EHV_FIVRA_CPU0_BOOT1
  PR1780    1      A  Q_RES       I51
  PU69_P0_1   33   BOOT  ISL99390FRZTR5935  I35

SW_PVCCFA_EHV_FIVRA_CPU0_BOOT1_   @S9S_MB_2U_LIB.S9S_MB_2U(SCH_1):SW_PVCCFA_EHV_FIVRA_CPU0_BOOT1_R
  PC606    1      A  Q_CAP       I54
  PR1780    2      B  Q_RES       I51

SW_PVCCFA_EHV_FIVRA_CPU0_BOOT2   @S9S_MB_2U_LIB.S9S_MB_2U(SCH_1):SW_PVCCFA_EHV_FIVRA_CPU0_BOOT2
  PR1781    1      A  Q_RES       I40
  PU70_P0_2   33   BOOT  ISL99390FRZTR5935  I30

SW_PVCCFA_EHV_FIVRA_CPU0_BOOT2_   @S9S_MB_2U_LIB.S9S_MB_2U(SCH_1):SW_PVCCFA_EHV_FIVRA_CPU0_BOOT2_R
  PC607    1      A  Q_CAP       I43
  PR1781    2      B  Q_RES       I40

SW_PVCCFA_EHV_FIVRA_CPU0_BOOT3   @S9S_MB_2U_LIB.S9S_MB_2U(SCH_1):SW_PVCCFA_EHV_FIVRA_CPU0_BOOT3
  PR1782    1      A  Q_RES       I45
  PU71_P0_3   33   BOOT  ISL99390FRZTR5935  I40

SW_PVCCFA_EHV_FIVRA_CPU0_BOOT3_   @S9S_MB_2U_LIB.S9S_MB_2U(SCH_1):SW_PVCCFA_EHV_FIVRA_CPU0_BOOT3_R
  PC1177    1      A  Q_CAP       I48
  PR1782    2      B  Q_RES       I45

SW_PVCCFA_EHV_FIVRA_CPU0_BOOT4   @S9S_MB_2U_LIB.S9S_MB_2U(SCH_1):SW_PVCCFA_EHV_FIVRA_CPU0_BOOT4
  PR1783    1      A  Q_RES       I33
  PU72_P0_4   33   BOOT  ISL99390FRZTR5935  I24

SW_PVCCFA_EHV_FIVRA_CPU0_BOOT4_   @S9S_MB_2U_LIB.S9S_MB_2U(SCH_1):SW_PVCCFA_EHV_FIVRA_CPU0_BOOT4_R
  PC1178    1      A  Q_CAP       I36
  PR1783    2      B  Q_RES       I33

SW_PVCCFA_EHV_FIVRA_CPU0_BOOTR1   @S9S_MB_2U_LIB.S9S_MB_2U(SCH_1):SW_PVCCFA_EHV_FIVRA_CPU0_BOOTR1
  PC606    2      B  Q_CAP       I54
  PU69_P0_1   32  PHASE  ISL99390FRZTR5935  I35

SW_PVCCFA_EHV_FIVRA_CPU0_BOOTR2   @S9S_MB_2U_LIB.S9S_MB_2U(SCH_1):SW_PVCCFA_EHV_FIVRA_CPU0_BOOTR2
  PC607    2      B  Q_CAP       I43
  PU70_P0_2   32  PHASE  ISL99390FRZTR5935  I30

SW_PVCCFA_EHV_FIVRA_CPU0_BOOTR3   @S9S_MB_2U_LIB.S9S_MB_2U(SCH_1):SW_PVCCFA_EHV_FIVRA_CPU0_BOOTR3
  PC1177    2      B  Q_CAP       I48
  PU71_P0_3   32  PHASE  ISL99390FRZTR5935  I40

SW_PVCCFA_EHV_FIVRA_CPU0_BOOTR4   @S9S_MB_2U_LIB.S9S_MB_2U(SCH_1):SW_PVCCFA_EHV_FIVRA_CPU0_BOOTR4
  PC1178    2      B  Q_CAP       I36
  PU72_P0_4   32  PHASE  ISL99390FRZTR5935  I24

SW_PVCCFA_EHV_FIVRA_CPU0_SW1   @S9S_MB_2U_LIB.S9S_MB_2U(SCH_1):SW_PVCCFA_EHV_FIVRA_CPU0_SW1
  PL33     1      1  Q_INDUCTOR  I81
  PU69_P0_1  10_19     SW  ISL99390FRZTR5935  I35

SW_PVCCFA_EHV_FIVRA_CPU0_SW2   @S9S_MB_2U_LIB.S9S_MB_2U(SCH_1):SW_PVCCFA_EHV_FIVRA_CPU0_SW2
  PL34     1      1  Q_INDUCTOR  I82
  PU70_P0_2  10_19     SW  ISL99390FRZTR5935  I30

SW_PVCCFA_EHV_FIVRA_CPU0_SW3   @S9S_MB_2U_LIB.S9S_MB_2U(SCH_1):SW_PVCCFA_EHV_FIVRA_CPU0_SW3
  PL2      1      1  Q_INDUCTOR  I75
  PU71_P0_3  10_19     SW  ISL99390FRZTR5935  I40

SW_PVCCFA_EHV_FIVRA_CPU0_SW4   @S9S_MB_2U_LIB.S9S_MB_2U(SCH_1):SW_PVCCFA_EHV_FIVRA_CPU0_SW4
  PL210    1      1  Q_INDUCTOR  I30
  PU72_P0_4  10_19     SW  ISL99390FRZTR5935  I24

SW_PVCCFA_EHV_FIVRA_CPU1_BOOT1   @S9S_MB_2U_LIB.S9S_MB_2U(SCH_1):SW_PVCCFA_EHV_FIVRA_CPU1_BOOT1
  PR1800    1      A  Q_RES       I256
  PU75_P1_1   33   BOOT  ISL99390FRZTR5935  I278

SW_PVCCFA_EHV_FIVRA_CPU1_BOOT1_   @S9S_MB_2U_LIB.S9S_MB_2U(SCH_1):SW_PVCCFA_EHV_FIVRA_CPU1_BOOT1_R
  PC401    1      A  Q_CAP       I261
  PR1800    2      B  Q_RES       I256

SW_PVCCFA_EHV_FIVRA_CPU1_BOOT2   @S9S_MB_2U_LIB.S9S_MB_2U(SCH_1):SW_PVCCFA_EHV_FIVRA_CPU1_BOOT2
  PR1801    1      A  Q_RES       I242
  PU76_P1_2   33   BOOT  ISL99390FRZTR5935  I221

SW_PVCCFA_EHV_FIVRA_CPU1_BOOT2_   @S9S_MB_2U_LIB.S9S_MB_2U(SCH_1):SW_PVCCFA_EHV_FIVRA_CPU1_BOOT2_R
  PC402    1      A  Q_CAP       I241
  PR1801    2      B  Q_RES       I242

SW_PVCCFA_EHV_FIVRA_CPU1_BOOT3   @S9S_MB_2U_LIB.S9S_MB_2U(SCH_1):SW_PVCCFA_EHV_FIVRA_CPU1_BOOT3
  PR1802    1      A  Q_RES       I43
  PU77_P1_3   33   BOOT  ISL99390FRZTR5935  I27

SW_PVCCFA_EHV_FIVRA_CPU1_BOOT3_   @S9S_MB_2U_LIB.S9S_MB_2U(SCH_1):SW_PVCCFA_EHV_FIVRA_CPU1_BOOT3_R
  PC1197    1      A  Q_CAP       I48
  PR1802    2      B  Q_RES       I43

SW_PVCCFA_EHV_FIVRA_CPU1_BOOT4   @S9S_MB_2U_LIB.S9S_MB_2U(SCH_1):SW_PVCCFA_EHV_FIVRA_CPU1_BOOT4
  PR1803    1      A  Q_RES       I34
  PU78_P1_4   33   BOOT  ISL99390FRZTR5935  I24

SW_PVCCFA_EHV_FIVRA_CPU1_BOOT4_   @S9S_MB_2U_LIB.S9S_MB_2U(SCH_1):SW_PVCCFA_EHV_FIVRA_CPU1_BOOT4_R
  PC1198    1      A  Q_CAP       I31
  PR1803    2      B  Q_RES       I34

SW_PVCCFA_EHV_FIVRA_CPU1_BOOTR1   @S9S_MB_2U_LIB.S9S_MB_2U(SCH_1):SW_PVCCFA_EHV_FIVRA_CPU1_BOOTR1
  PC401    2      B  Q_CAP       I261
  PU75_P1_1   32  PHASE  ISL99390FRZTR5935  I278

SW_PVCCFA_EHV_FIVRA_CPU1_BOOTR2   @S9S_MB_2U_LIB.S9S_MB_2U(SCH_1):SW_PVCCFA_EHV_FIVRA_CPU1_BOOTR2
  PC402    2      B  Q_CAP       I241
  PU76_P1_2   32  PHASE  ISL99390FRZTR5935  I221

SW_PVCCFA_EHV_FIVRA_CPU1_BOOTR3   @S9S_MB_2U_LIB.S9S_MB_2U(SCH_1):SW_PVCCFA_EHV_FIVRA_CPU1_BOOTR3
  PC1197    2      B  Q_CAP       I48
  PU77_P1_3   32  PHASE  ISL99390FRZTR5935  I27

SW_PVCCFA_EHV_FIVRA_CPU1_BOOTR4   @S9S_MB_2U_LIB.S9S_MB_2U(SCH_1):SW_PVCCFA_EHV_FIVRA_CPU1_BOOTR4
  PC1198    2      B  Q_CAP       I31
  PU78_P1_4   32  PHASE  ISL99390FRZTR5935  I24

SW_PVCCFA_EHV_FIVRA_CPU1_SW1   @S9S_MB_2U_LIB.S9S_MB_2U(SCH_1):SW_PVCCFA_EHV_FIVRA_CPU1_SW1
  PL18     1      1  Q_INDUCTOR  I279
  PU75_P1_1  10_19     SW  ISL99390FRZTR5935  I278

SW_PVCCFA_EHV_FIVRA_CPU1_SW2   @S9S_MB_2U_LIB.S9S_MB_2U(SCH_1):SW_PVCCFA_EHV_FIVRA_CPU1_SW2
  PL19     1      1  Q_INDUCTOR  I280
  PU76_P1_2  10_19     SW  ISL99390FRZTR5935  I221

SW_PVCCFA_EHV_FIVRA_CPU1_SW3   @S9S_MB_2U_LIB.S9S_MB_2U(SCH_1):SW_PVCCFA_EHV_FIVRA_CPU1_SW3
  PL12     1      1  Q_INDUCTOR  I76
  PU77_P1_3  10_19     SW  ISL99390FRZTR5935  I27

SW_PVCCFA_EHV_FIVRA_CPU1_SW4   @S9S_MB_2U_LIB.S9S_MB_2U(SCH_1):SW_PVCCFA_EHV_FIVRA_CPU1_SW4
  PL113    1      1  Q_INDUCTOR  I77
  PU78_P1_4  10_19     SW  ISL99390FRZTR5935  I24

SW_PVCCINFAON_CPU0_BOOT1   @S9S_MB_2U_LIB.S9S_MB_2U(SCH_1):SW_PVCCINFAON_CPU0_BOOT1
  PR1774    1      A  Q_RES       I203
  PU43_P0_1   20   BOOT  RAA2213404GNPHB0  I166

SW_PVCCINFAON_CPU0_BOOT1_R   @S9S_MB_2U_LIB.S9S_MB_2U(SCH_1):SW_PVCCINFAON_CPU0_BOOT1_R
  PC193    1      A  Q_CAP       I205
  PR1774    2      B  Q_RES       I203

SW_PVCCINFAON_CPU0_BOOT2   @S9S_MB_2U_LIB.S9S_MB_2U(SCH_1):SW_PVCCINFAON_CPU0_BOOT2
  PR1775    1      A  Q_RES       I181
  PU44_P0_2   20   BOOT  RAA2213404GNPHB0  I164

SW_PVCCINFAON_CPU0_BOOT2_R   @S9S_MB_2U_LIB.S9S_MB_2U(SCH_1):SW_PVCCINFAON_CPU0_BOOT2_R
  PC194    1      A  Q_CAP       I183
  PR1775    2      B  Q_RES       I181

SW_PVCCINFAON_CPU0_BOOTR1   @S9S_MB_2U_LIB.S9S_MB_2U(SCH_1):SW_PVCCINFAON_CPU0_BOOTR1
  PC193    2      B  Q_CAP       I205
  PU43_P0_1   19  PHASE  RAA2213404GNPHB0  I166

SW_PVCCINFAON_CPU0_BOOTR2   @S9S_MB_2U_LIB.S9S_MB_2U(SCH_1):SW_PVCCINFAON_CPU0_BOOTR2
  PC194    2      B  Q_CAP       I183
  PU44_P0_2   19  PHASE  RAA2213404GNPHB0  I164

SW_PVCCINFAON_CPU0_SW1   @S9S_MB_2U_LIB.S9S_MB_2U(SCH_1):SW_PVCCINFAON_CPU0_SW1
  PL4      1      1  Q_INDUCTOR  I207
  PU43_P0_1  8_12     SW  RAA2213404GNPHB0  I166

SW_PVCCINFAON_CPU0_SW2   @S9S_MB_2U_LIB.S9S_MB_2U(SCH_1):SW_PVCCINFAON_CPU0_SW2
  PL5      1      1  Q_INDUCTOR  I184
  PU44_P0_2  8_12     SW  RAA2213404GNPHB0  I164

SW_PVCCINFAON_CPU1_BOOT1   @S9S_MB_2U_LIB.S9S_MB_2U(SCH_1):SW_PVCCINFAON_CPU1_BOOT1
  PR1794    1      A  Q_RES       I52
  PU50_P1_1   20   BOOT  RAA2213404GNPHB0  I17

SW_PVCCINFAON_CPU1_BOOT1_R   @S9S_MB_2U_LIB.S9S_MB_2U(SCH_1):SW_PVCCINFAON_CPU1_BOOT1_R
  PC446    1      A  Q_CAP       I54
  PR1794    2      B  Q_RES       I52

SW_PVCCINFAON_CPU1_BOOT2   @S9S_MB_2U_LIB.S9S_MB_2U(SCH_1):SW_PVCCINFAON_CPU1_BOOT2
  PR1795    1      A  Q_RES       I35
  PU51_P1_2   20   BOOT  RAA2213404GNPHB0  I12

SW_PVCCINFAON_CPU1_BOOT2_R   @S9S_MB_2U_LIB.S9S_MB_2U(SCH_1):SW_PVCCINFAON_CPU1_BOOT2_R
  PC447    1      A  Q_CAP       I40
  PR1795    2      B  Q_RES       I35

SW_PVCCINFAON_CPU1_BOOTR1   @S9S_MB_2U_LIB.S9S_MB_2U(SCH_1):SW_PVCCINFAON_CPU1_BOOTR1
  PC446    2      B  Q_CAP       I54
  PU50_P1_1   19  PHASE  RAA2213404GNPHB0  I17

SW_PVCCINFAON_CPU1_BOOTR2   @S9S_MB_2U_LIB.S9S_MB_2U(SCH_1):SW_PVCCINFAON_CPU1_BOOTR2
  PC447    2      B  Q_CAP       I40
  PU51_P1_2   19  PHASE  RAA2213404GNPHB0  I12

SW_PVCCINFAON_CPU1_SW1   @S9S_MB_2U_LIB.S9S_MB_2U(SCH_1):SW_PVCCINFAON_CPU1_SW1
  PL21     1      1  Q_INDUCTOR  I55
  PU50_P1_1  8_12     SW  RAA2213404GNPHB0  I17

SW_PVCCINFAON_CPU1_SW2   @S9S_MB_2U_LIB.S9S_MB_2U(SCH_1):SW_PVCCINFAON_CPU1_SW2
  PL22     1      1  Q_INDUCTOR  I33
  PU51_P1_2  8_12     SW  RAA2213404GNPHB0  I12

SW_PVCCIN_CPU0_BOOT1   @S9S_MB_2U_LIB.S9S_MB_2U(SCH_1):SW_PVCCIN_CPU0_BOOT1
  PR1787    1      A  Q_RES       I39
  PU13_P0_1   33   BOOT  ISL99390FRZTR5935  I21

SW_PVCCIN_CPU0_BOOT1_R   @S9S_MB_2U_LIB.S9S_MB_2U(SCH_1):SW_PVCCIN_CPU0_BOOT1_R
  PC301    1      A  Q_CAP       I62
  PR1787    2      B  Q_RES       I39

SW_PVCCIN_CPU0_BOOT2   @S9S_MB_2U_LIB.S9S_MB_2U(SCH_1):SW_PVCCIN_CPU0_BOOT2
  PR1786    1      A  Q_RES       I20
  PU12_P0_2   33   BOOT  ISL99390FRZTR5935  I87

SW_PVCCIN_CPU0_BOOT2_R   @S9S_MB_2U_LIB.S9S_MB_2U(SCH_1):SW_PVCCIN_CPU0_BOOT2_R
  PC300    1      A  Q_CAP       I44
  PR1786    2      B  Q_RES       I20

SW_PVCCIN_CPU0_BOOT3   @S9S_MB_2U_LIB.S9S_MB_2U(SCH_1):SW_PVCCIN_CPU0_BOOT3
  PR1769    1      A  Q_RES       I49
  PU11_P0_3   33   BOOT  ISL99390FRZTR5935  I30

SW_PVCCIN_CPU0_BOOT3_R   @S9S_MB_2U_LIB.S9S_MB_2U(SCH_1):SW_PVCCIN_CPU0_BOOT3_R
  PC279    1      A  Q_CAP       I53
  PR1769    2      B  Q_RES       I49

SW_PVCCIN_CPU0_BOOT4   @S9S_MB_2U_LIB.S9S_MB_2U(SCH_1):SW_PVCCIN_CPU0_BOOT4
  PR1768    1      A  Q_RES       I35
  PU10_P0_4   33   BOOT  ISL99390FRZTR5935  I14

SW_PVCCIN_CPU0_BOOT4_R   @S9S_MB_2U_LIB.S9S_MB_2U(SCH_1):SW_PVCCIN_CPU0_BOOT4_R
  PC278    1      A  Q_CAP       I39
  PR1768    2      B  Q_RES       I35

SW_PVCCIN_CPU0_BOOT5   @S9S_MB_2U_LIB.S9S_MB_2U(SCH_1):SW_PVCCIN_CPU0_BOOT5
  PR1771    1      A  Q_RES       I37
  PU9_P0_5   33   BOOT  ISL99390FRZTR5935  I31

SW_PVCCIN_CPU0_BOOT5_R   @S9S_MB_2U_LIB.S9S_MB_2U(SCH_1):SW_PVCCIN_CPU0_BOOT5_R
  PC257    1      A  Q_CAP       I42
  PR1771    2      B  Q_RES       I37

SW_PVCCIN_CPU0_BOOT6   @S9S_MB_2U_LIB.S9S_MB_2U(SCH_1):SW_PVCCIN_CPU0_BOOT6
  PR1770    1      A  Q_RES       I17
  PU8_P0_6   33   BOOT  ISL99390FRZTR5935  I62

SW_PVCCIN_CPU0_BOOT6_R   @S9S_MB_2U_LIB.S9S_MB_2U(SCH_1):SW_PVCCIN_CPU0_BOOT6_R
  PC256    1      A  Q_CAP       I16
  PR1770    2      B  Q_RES       I17

SW_PVCCIN_CPU0_BOOT7   @S9S_MB_2U_LIB.S9S_MB_2U(SCH_1):SW_PVCCIN_CPU0_BOOT7
  PR1773    1      A  Q_RES       I49
  PU7_P0_7   33   BOOT  ISL99390FRZTR5935  I20

SW_PVCCIN_CPU0_BOOT7_R   @S9S_MB_2U_LIB.S9S_MB_2U(SCH_1):SW_PVCCIN_CPU0_BOOT7_R
  PC235    1      A  Q_CAP       I55
  PR1773    2      B  Q_RES       I49

SW_PVCCIN_CPU0_BOOT8   @S9S_MB_2U_LIB.S9S_MB_2U(SCH_1):SW_PVCCIN_CPU0_BOOT8
  PR1772    1      A  Q_RES       I35
  PU6_P0_8   33   BOOT  ISL99390FRZTR5935  I64

SW_PVCCIN_CPU0_BOOT8_R   @S9S_MB_2U_LIB.S9S_MB_2U(SCH_1):SW_PVCCIN_CPU0_BOOT8_R
  PC234    1      A  Q_CAP       I33
  PR1772    2      B  Q_RES       I35

SW_PVCCIN_CPU0_BOOTR1   @S9S_MB_2U_LIB.S9S_MB_2U(SCH_1):SW_PVCCIN_CPU0_BOOTR1
  PC301    2      B  Q_CAP       I62
  PU13_P0_1   32  PHASE  ISL99390FRZTR5935  I21

SW_PVCCIN_CPU0_BOOTR2   @S9S_MB_2U_LIB.S9S_MB_2U(SCH_1):SW_PVCCIN_CPU0_BOOTR2
  PC300    2      B  Q_CAP       I44
  PU12_P0_2   32  PHASE  ISL99390FRZTR5935  I87

SW_PVCCIN_CPU0_BOOTR3   @S9S_MB_2U_LIB.S9S_MB_2U(SCH_1):SW_PVCCIN_CPU0_BOOTR3
  PC279    2      B  Q_CAP       I53
  PU11_P0_3   32  PHASE  ISL99390FRZTR5935  I30

SW_PVCCIN_CPU0_BOOTR4   @S9S_MB_2U_LIB.S9S_MB_2U(SCH_1):SW_PVCCIN_CPU0_BOOTR4
  PC278    2      B  Q_CAP       I39
  PU10_P0_4   32  PHASE  ISL99390FRZTR5935  I14

SW_PVCCIN_CPU0_BOOTR5   @S9S_MB_2U_LIB.S9S_MB_2U(SCH_1):SW_PVCCIN_CPU0_BOOTR5
  PC257    2      B  Q_CAP       I42
  PU9_P0_5   32  PHASE  ISL99390FRZTR5935  I31

SW_PVCCIN_CPU0_BOOTR6   @S9S_MB_2U_LIB.S9S_MB_2U(SCH_1):SW_PVCCIN_CPU0_BOOTR6
  PC256    2      B  Q_CAP       I16
  PU8_P0_6   32  PHASE  ISL99390FRZTR5935  I62

SW_PVCCIN_CPU0_BOOTR7   @S9S_MB_2U_LIB.S9S_MB_2U(SCH_1):SW_PVCCIN_CPU0_BOOTR7
  PC235    2      B  Q_CAP       I55
  PU7_P0_7   32  PHASE  ISL99390FRZTR5935  I20

SW_PVCCIN_CPU0_BOOTR8   @S9S_MB_2U_LIB.S9S_MB_2U(SCH_1):SW_PVCCIN_CPU0_BOOTR8
  PC234    2      B  Q_CAP       I33
  PU6_P0_8   32  PHASE  ISL99390FRZTR5935  I64

SW_PVCCIN_CPU0_SW1   @S9S_MB_2U_LIB.S9S_MB_2U(SCH_1):SW_PVCCIN_CPU0_SW1
  PL114    1      1  Q_INDUCTOR4P_14  I104
  PU13_P0_1  10_19     SW  ISL99390FRZTR5935  I21

SW_PVCCIN_CPU0_SW2   @S9S_MB_2U_LIB.S9S_MB_2U(SCH_1):SW_PVCCIN_CPU0_SW2
  PL13     1      1  Q_INDUCTOR4P_14  I122
  PU12_P0_2  10_19     SW  ISL99390FRZTR5935  I87

SW_PVCCIN_CPU0_SW3   @S9S_MB_2U_LIB.S9S_MB_2U(SCH_1):SW_PVCCIN_CPU0_SW3
  PL112    1      1  Q_INDUCTOR4P_14  I74
  PU11_P0_3  10_19     SW  ISL99390FRZTR5935  I30

SW_PVCCIN_CPU0_SW4   @S9S_MB_2U_LIB.S9S_MB_2U(SCH_1):SW_PVCCIN_CPU0_SW4
  PL11     1      1  Q_INDUCTOR4P_14  I90
  PU10_P0_4  10_19     SW  ISL99390FRZTR5935  I14

SW_PVCCIN_CPU0_SW5   @S9S_MB_2U_LIB.S9S_MB_2U(SCH_1):SW_PVCCIN_CPU0_SW5
  PL10     1      1  Q_INDUCTOR4P_14  I74
  PU9_P0_5  10_19     SW  ISL99390FRZTR5935  I31

SW_PVCCIN_CPU0_SW6   @S9S_MB_2U_LIB.S9S_MB_2U(SCH_1):SW_PVCCIN_CPU0_SW6
  PL9      1      1  Q_INDUCTOR4P_14  I90
  PU8_P0_6  10_19     SW  ISL99390FRZTR5935  I62

SW_PVCCIN_CPU0_SW7   @S9S_MB_2U_LIB.S9S_MB_2U(SCH_1):SW_PVCCIN_CPU0_SW7
  PL8      1      1  Q_INDUCTOR4P_14  I81
  PU7_P0_7  10_19     SW  ISL99390FRZTR5935  I20

SW_PVCCIN_CPU0_SW8   @S9S_MB_2U_LIB.S9S_MB_2U(SCH_1):SW_PVCCIN_CPU0_SW8
  PL7      1      1  Q_INDUCTOR4P_14  I117
  PU6_P0_8  10_19     SW  ISL99390FRZTR5935  I64

SW_PVCCIN_CPU1_BOOT1   @S9S_MB_2U_LIB.S9S_MB_2U(SCH_1):SW_PVCCIN_CPU1_BOOT1
  PR1767    1      A  Q_RES       I37
  PU31_P1_1   33   BOOT  ISL99390FRZTR5935  I20

SW_PVCCIN_CPU1_BOOT1_R   @S9S_MB_2U_LIB.S9S_MB_2U(SCH_1):SW_PVCCIN_CPU1_BOOT1_R
  PC565    1      A  Q_CAP       I60
  PR1767    2      B  Q_RES       I37

SW_PVCCIN_CPU1_BOOT2   @S9S_MB_2U_LIB.S9S_MB_2U(SCH_1):SW_PVCCIN_CPU1_BOOT2
  PR1766    1      A  Q_RES       I22
  PU30_P1_2   33   BOOT  ISL99390FRZTR5935  I18

SW_PVCCIN_CPU1_BOOT2_R   @S9S_MB_2U_LIB.S9S_MB_2U(SCH_1):SW_PVCCIN_CPU1_BOOT2_R
  PC564    1      A  Q_CAP       I42
  PR1766    2      B  Q_RES       I22

SW_PVCCIN_CPU1_BOOT3   @S9S_MB_2U_LIB.S9S_MB_2U(SCH_1):SW_PVCCIN_CPU1_BOOT3
  PR1789    1      A  Q_RES       I47
  PU28_P1_3   33   BOOT  ISL99390FRZTR5935  I18

SW_PVCCIN_CPU1_BOOT3_R   @S9S_MB_2U_LIB.S9S_MB_2U(SCH_1):SW_PVCCIN_CPU1_BOOT3_R
  PC532    1      A  Q_CAP       I52
  PR1789    2      B  Q_RES       I47

SW_PVCCIN_CPU1_BOOT4   @S9S_MB_2U_LIB.S9S_MB_2U(SCH_1):SW_PVCCIN_CPU1_BOOT4
  PR1788    1      A  Q_RES       I34
  PU27_P1_4   33   BOOT  ISL99390FRZTR5935   I9

SW_PVCCIN_CPU1_BOOT4_R   @S9S_MB_2U_LIB.S9S_MB_2U(SCH_1):SW_PVCCIN_CPU1_BOOT4_R
  PC531    1      A  Q_CAP       I41
  PR1788    2      B  Q_RES       I34

SW_PVCCIN_CPU1_BOOT5   @S9S_MB_2U_LIB.S9S_MB_2U(SCH_1):SW_PVCCIN_CPU1_BOOT5
  PR1791    1      A  Q_RES       I47
  PU26_P1_5   33   BOOT  ISL99390FRZTR5935  I32

SW_PVCCIN_CPU1_BOOT5_R   @S9S_MB_2U_LIB.S9S_MB_2U(SCH_1):SW_PVCCIN_CPU1_BOOT5_R
  PC510    1      A  Q_CAP       I53
  PR1791    2      B  Q_RES       I47

SW_PVCCIN_CPU1_BOOT6   @S9S_MB_2U_LIB.S9S_MB_2U(SCH_1):SW_PVCCIN_CPU1_BOOT6
  PR1790    1      A  Q_RES       I36
  PU25_P1_6   33   BOOT  ISL99390FRZTR5935  I23

SW_PVCCIN_CPU1_BOOT6_R   @S9S_MB_2U_LIB.S9S_MB_2U(SCH_1):SW_PVCCIN_CPU1_BOOT6_R
  PC509    1      A  Q_CAP       I41
  PR1790    2      B  Q_RES       I36

SW_PVCCIN_CPU1_BOOT7   @S9S_MB_2U_LIB.S9S_MB_2U(SCH_1):SW_PVCCIN_CPU1_BOOT7
  PR1793    1      A  Q_RES       I47
  PU24_P1_7   33   BOOT  ISL99390FRZTR5935  I37

SW_PVCCIN_CPU1_BOOT7_R   @S9S_MB_2U_LIB.S9S_MB_2U(SCH_1):SW_PVCCIN_CPU1_BOOT7_R
  PC488    1      A  Q_CAP       I49
  PR1793    2      B  Q_RES       I47

SW_PVCCIN_CPU1_BOOT8   @S9S_MB_2U_LIB.S9S_MB_2U(SCH_1):SW_PVCCIN_CPU1_BOOT8
  PR1792    1      A  Q_RES       I39
  PU23_P1_8   33   BOOT  ISL99390FRZTR5935   I9

SW_PVCCIN_CPU1_BOOT8_R   @S9S_MB_2U_LIB.S9S_MB_2U(SCH_1):SW_PVCCIN_CPU1_BOOT8_R
  PC487    1      A  Q_CAP       I41
  PR1792    2      B  Q_RES       I39

SW_PVCCIN_CPU1_BOOTR1   @S9S_MB_2U_LIB.S9S_MB_2U(SCH_1):SW_PVCCIN_CPU1_BOOTR1
  PC565    2      B  Q_CAP       I60
  PU31_P1_1   32  PHASE  ISL99390FRZTR5935  I20

SW_PVCCIN_CPU1_BOOTR2   @S9S_MB_2U_LIB.S9S_MB_2U(SCH_1):SW_PVCCIN_CPU1_BOOTR2
  PC564    2      B  Q_CAP       I42
  PU30_P1_2   32  PHASE  ISL99390FRZTR5935  I18

SW_PVCCIN_CPU1_BOOTR3   @S9S_MB_2U_LIB.S9S_MB_2U(SCH_1):SW_PVCCIN_CPU1_BOOTR3
  PC532    2      B  Q_CAP       I52
  PU28_P1_3   32  PHASE  ISL99390FRZTR5935  I18

SW_PVCCIN_CPU1_BOOTR4   @S9S_MB_2U_LIB.S9S_MB_2U(SCH_1):SW_PVCCIN_CPU1_BOOTR4
  PC531    2      B  Q_CAP       I41
  PU27_P1_4   32  PHASE  ISL99390FRZTR5935   I9

SW_PVCCIN_CPU1_BOOTR5   @S9S_MB_2U_LIB.S9S_MB_2U(SCH_1):SW_PVCCIN_CPU1_BOOTR5
  PC510    2      B  Q_CAP       I53
  PU26_P1_5   32  PHASE  ISL99390FRZTR5935  I32

SW_PVCCIN_CPU1_BOOTR6   @S9S_MB_2U_LIB.S9S_MB_2U(SCH_1):SW_PVCCIN_CPU1_BOOTR6
  PC509    2      B  Q_CAP       I41
  PU25_P1_6   32  PHASE  ISL99390FRZTR5935  I23

SW_PVCCIN_CPU1_BOOTR7   @S9S_MB_2U_LIB.S9S_MB_2U(SCH_1):SW_PVCCIN_CPU1_BOOTR7
  PC488    2      B  Q_CAP       I49
  PU24_P1_7   32  PHASE  ISL99390FRZTR5935  I37

SW_PVCCIN_CPU1_BOOTR8   @S9S_MB_2U_LIB.S9S_MB_2U(SCH_1):SW_PVCCIN_CPU1_BOOTR8
  PC487    2      B  Q_CAP       I41
  PU23_P1_8   32  PHASE  ISL99390FRZTR5935   I9

SW_PVCCIN_CPU1_SW1   @S9S_MB_2U_LIB.S9S_MB_2U(SCH_1):SW_PVCCIN_CPU1_SW1
  PL31     1      1  Q_INDUCTOR4P_14  I89
  PU31_P1_1  10_19     SW  ISL99390FRZTR5935  I20

SW_PVCCIN_CPU1_SW2   @S9S_MB_2U_LIB.S9S_MB_2U(SCH_1):SW_PVCCIN_CPU1_SW2
  PL30     1      1  Q_INDUCTOR4P_14  I103
  PU30_P1_2  10_19     SW  ISL99390FRZTR5935  I18

SW_PVCCIN_CPU1_SW3   @S9S_MB_2U_LIB.S9S_MB_2U(SCH_1):SW_PVCCIN_CPU1_SW3
  PL29     1      1  Q_INDUCTOR4P_14  I74
  PU28_P1_3  10_19     SW  ISL99390FRZTR5935  I18

SW_PVCCIN_CPU1_SW4   @S9S_MB_2U_LIB.S9S_MB_2U(SCH_1):SW_PVCCIN_CPU1_SW4
  PL28     1      1  Q_INDUCTOR4P_14  I90
  PU27_P1_4  10_19     SW  ISL99390FRZTR5935   I9

SW_PVCCIN_CPU1_SW5   @S9S_MB_2U_LIB.S9S_MB_2U(SCH_1):SW_PVCCIN_CPU1_SW5
  PL27     1      1  Q_INDUCTOR4P_14  I73
  PU26_P1_5  10_19     SW  ISL99390FRZTR5935  I32

SW_PVCCIN_CPU1_SW6   @S9S_MB_2U_LIB.S9S_MB_2U(SCH_1):SW_PVCCIN_CPU1_SW6
  PL26     1      1  Q_INDUCTOR4P_14  I90
  PU25_P1_6  10_19     SW  ISL99390FRZTR5935  I23

SW_PVCCIN_CPU1_SW7   @S9S_MB_2U_LIB.S9S_MB_2U(SCH_1):SW_PVCCIN_CPU1_SW7
  PL25     1      1  Q_INDUCTOR4P_14  I76
  PU24_P1_7  10_19     SW  ISL99390FRZTR5935  I37

SW_PVCCIN_CPU1_SW8   @S9S_MB_2U_LIB.S9S_MB_2U(SCH_1):SW_PVCCIN_CPU1_SW8
  PL24     1      1  Q_INDUCTOR4P_14  I95
  PU23_P1_8  10_19     SW  ISL99390FRZTR5935   I9

SW_PVNN_MAIN_CPU0_BST   @S9S_MB_2U_LIB.S9S_MB_2U(SCH_1):SW_PVNN_MAIN_CPU0_BST
  PC1275    1      A  Q_CAP       I176
  PU81    10    BST  MPQ8626GDZ  I190

SW_PVNN_MAIN_CPU0_SW   @S9S_MB_2U_LIB.S9S_MB_2U(SCH_1):SW_PVNN_MAIN_CPU0_SW
  PC1275    2      B  Q_CAP       I176
  PL120    1      1  Q_INDUCTOR  I180
  PU81     2    SW1  MPQ8626GDZ  I190
  PU81    11    SW2  MPQ8626GDZ  I190

SW_PVNN_MAIN_CPU1_BST   @S9S_MB_2U_LIB.S9S_MB_2U(SCH_1):SW_PVNN_MAIN_CPU1_BST
  PC1283    1      A  Q_CAP       I181
  PU82    10    BST  MPQ8626GDZ  I198

SW_PVNN_MAIN_CPU1_SW   @S9S_MB_2U_LIB.S9S_MB_2U(SCH_1):SW_PVNN_MAIN_CPU1_SW
  PC1283    2      B  Q_CAP       I181
  PL121    1      1  Q_INDUCTOR  I182
  PU82     2    SW1  MPQ8626GDZ  I198
  PU82    11    SW2  MPQ8626GDZ  I198

SW_PVPP_HBM_CPU0_BST   @S9S_MB_2U_LIB.S9S_MB_2U(SCH_1):SW_PVPP_HBM_CPU0_BST
  PC1252    1      A  Q_CAP       I23
  PU79     1    BST  MPQ8633AGLEC807Z  I13

SW_PVPP_HBM_CPU0_SW   @S9S_MB_2U_LIB.S9S_MB_2U(SCH_1):SW_PVPP_HBM_CPU0_SW
  PC1252    2      B  Q_CAP       I23
  PL118    1      1  Q_INDUCTOR  I24
  PU79    20     SW  MPQ8633AGLEC807Z  I13

SW_PVPP_HBM_CPU1_BST   @S9S_MB_2U_LIB.S9S_MB_2U(SCH_1):SW_PVPP_HBM_CPU1_BST
  PC1265    1      A  Q_CAP       I22
  PU80     1    BST  MPQ8633AGLEC807Z  I15

SW_PVPP_HBM_CPU1_SW   @S9S_MB_2U_LIB.S9S_MB_2U(SCH_1):SW_PVPP_HBM_CPU1_SW
  PC1265    2      B  Q_CAP       I22
  PL119    1      1  Q_INDUCTOR  I41
  PU80    20     SW  MPQ8633AGLEC807Z  I15

TDR_DIFF_100_BOT_DN   @S9S_MB_2U_LIB.S9S_MB_2U(SCH_1):TDR_DIFF_100_BOT_DN
  X18      4     S2  TP_TDR_4P_FTS  I55
  X24      1     S1  TP_TDR_4P_FTS  I57

TDR_DIFF_100_BOT_DP   @S9S_MB_2U_LIB.S9S_MB_2U(SCH_1):TDR_DIFF_100_BOT_DP
  X18      1     S1  TP_TDR_4P_FTS  I55
  X24      4     S2  TP_TDR_4P_FTS  I57

TDR_DIFF_100_IN1_DN   @S9S_MB_2U_LIB.S9S_MB_2U(SCH_1):TDR_DIFF_100_IN1_DN
  X14      4     S2  TP_TDR_4P_FTS  I67
  X20      1     S1  TP_TDR_4P_FTS  I74

TDR_DIFF_100_IN1_DP   @S9S_MB_2U_LIB.S9S_MB_2U(SCH_1):TDR_DIFF_100_IN1_DP
  X14      1     S1  TP_TDR_4P_FTS  I67
  X20      4     S2  TP_TDR_4P_FTS  I74

TDR_DIFF_100_IN2_DN   @S9S_MB_2U_LIB.S9S_MB_2U(SCH_1):TDR_DIFF_100_IN2_DN
  X15      4     S2  TP_TDR_4P_FTS  I66
  X21      1     S1  TP_TDR_4P_FTS  I72

TDR_DIFF_100_IN2_DP   @S9S_MB_2U_LIB.S9S_MB_2U(SCH_1):TDR_DIFF_100_IN2_DP
  X15      1     S1  TP_TDR_4P_FTS  I66
  X21      4     S2  TP_TDR_4P_FTS  I72

TDR_DIFF_100_IN3_DN   @S9S_MB_2U_LIB.S9S_MB_2U(SCH_1):TDR_DIFF_100_IN3_DN
  X16      4     S2  TP_TDR_4P_FTS  I62
  X22      1     S1  TP_TDR_4P_FTS  I69

TDR_DIFF_100_IN3_DP   @S9S_MB_2U_LIB.S9S_MB_2U(SCH_1):TDR_DIFF_100_IN3_DP
  X16      1     S1  TP_TDR_4P_FTS  I62
  X22      4     S2  TP_TDR_4P_FTS  I69

TDR_DIFF_100_IN4_DN   @S9S_MB_2U_LIB.S9S_MB_2U(SCH_1):TDR_DIFF_100_IN4_DN
  X17      4     S2  TP_TDR_4P_FTS  I61
  X23      1     S1  TP_TDR_4P_FTS  I78

TDR_DIFF_100_IN4_DP   @S9S_MB_2U_LIB.S9S_MB_2U(SCH_1):TDR_DIFF_100_IN4_DP
  X17      1     S1  TP_TDR_4P_FTS  I61
  X23      4     S2  TP_TDR_4P_FTS  I78

TDR_DIFF_100_TOP_DN   @S9S_MB_2U_LIB.S9S_MB_2U(SCH_1):TDR_DIFF_100_TOP_DN
  X13      4     S2  TP_TDR_4P_FTS  I68
  X19      1     S1  TP_TDR_4P_FTS  I73

TDR_DIFF_100_TOP_DP   @S9S_MB_2U_LIB.S9S_MB_2U(SCH_1):TDR_DIFF_100_TOP_DP
  X13      1     S1  TP_TDR_4P_FTS  I68
  X19      4     S2  TP_TDR_4P_FTS  I73

TDR_DIFF_85_BOT_DN   @S9S_MB_2U_LIB.S9S_MB_2U(SCH_1):TDR_DIFF_85_BOT_DN
  X6       4     S2  TP_TDR_4P_FTS  I53
  X12      1     S1  TP_TDR_4P_FTS  I52

TDR_DIFF_85_BOT_DP   @S9S_MB_2U_LIB.S9S_MB_2U(SCH_1):TDR_DIFF_85_BOT_DP
  X6       1     S1  TP_TDR_4P_FTS  I53
  X12      4     S2  TP_TDR_4P_FTS  I52

TDR_DIFF_85_IN1_DN   @S9S_MB_2U_LIB.S9S_MB_2U(SCH_1):TDR_DIFF_85_IN1_DN
  X2       4     S2  TP_TDR_4P_FTS  I18
  X8       1     S1  TP_TDR_4P_FTS  I19

TDR_DIFF_85_IN1_DP   @S9S_MB_2U_LIB.S9S_MB_2U(SCH_1):TDR_DIFF_85_IN1_DP
  X2       1     S1  TP_TDR_4P_FTS  I18
  X8       4     S2  TP_TDR_4P_FTS  I19

TDR_DIFF_85_IN2_DN   @S9S_MB_2U_LIB.S9S_MB_2U(SCH_1):TDR_DIFF_85_IN2_DN
  X3       4     S2  TP_TDR_4P_FTS  I39
  X9       1     S1  TP_TDR_4P_FTS  I41

TDR_DIFF_85_IN2_DP   @S9S_MB_2U_LIB.S9S_MB_2U(SCH_1):TDR_DIFF_85_IN2_DP
  X3       1     S1  TP_TDR_4P_FTS  I39
  X9       4     S2  TP_TDR_4P_FTS  I41

TDR_DIFF_85_IN3_DN   @S9S_MB_2U_LIB.S9S_MB_2U(SCH_1):TDR_DIFF_85_IN3_DN
  X4       4     S2  TP_TDR_4P_FTS  I47
  X10      1     S1  TP_TDR_4P_FTS  I44

TDR_DIFF_85_IN3_DP   @S9S_MB_2U_LIB.S9S_MB_2U(SCH_1):TDR_DIFF_85_IN3_DP
  X4       1     S1  TP_TDR_4P_FTS  I47
  X10      4     S2  TP_TDR_4P_FTS  I44

TDR_DIFF_85_IN4_DN   @S9S_MB_2U_LIB.S9S_MB_2U(SCH_1):TDR_DIFF_85_IN4_DN
  X5       4     S2  TP_TDR_4P_FTS  I48
  X11      1     S1  TP_TDR_4P_FTS  I45

TDR_DIFF_85_IN4_DP   @S9S_MB_2U_LIB.S9S_MB_2U(SCH_1):TDR_DIFF_85_IN4_DP
  X5       1     S1  TP_TDR_4P_FTS  I48
  X11      4     S2  TP_TDR_4P_FTS  I45

TDR_DIFF_85_TOP_DN   @S9S_MB_2U_LIB.S9S_MB_2U(SCH_1):TDR_DIFF_85_TOP_DN
  X1       4     S2  TP_TDR_4P_FTS  I13
  X7       1     S1  TP_TDR_4P_FTS  I15

TDR_DIFF_85_TOP_DP   @S9S_MB_2U_LIB.S9S_MB_2U(SCH_1):TDR_DIFF_85_TOP_DP
  X1       1     S1  TP_TDR_4P_FTS  I13
  X7       4     S2  TP_TDR_4P_FTS  I15

TDR_SE_40_OHM_BOT   @S9S_MB_2U_LIB.S9S_MB_2U(SCH_1):TDR_SE_40_OHM_BOT
  DB6      2    IO1  TDR_3P_TH2   I7
  DB6      3    IO2  TDR_3P_TH2   I7

TDR_SE_40_OHM_IN1   @S9S_MB_2U_LIB.S9S_MB_2U(SCH_1):TDR_SE_40_OHM_IN1
  DB2      2    IO1  TDR_3P_TH2   I3
  DB2      3    IO2  TDR_3P_TH2   I3

TDR_SE_40_OHM_IN2   @S9S_MB_2U_LIB.S9S_MB_2U(SCH_1):TDR_SE_40_OHM_IN2
  DB3      2    IO1  TDR_3P_TH2   I5
  DB3      3    IO2  TDR_3P_TH2   I5

TDR_SE_40_OHM_IN3   @S9S_MB_2U_LIB.S9S_MB_2U(SCH_1):TDR_SE_40_OHM_IN3
  DB4      2    IO1  TDR_3P_TH2   I9
  DB4      3    IO2  TDR_3P_TH2   I9

TDR_SE_40_OHM_IN4   @S9S_MB_2U_LIB.S9S_MB_2U(SCH_1):TDR_SE_40_OHM_IN4
  DB5      2    IO1  TDR_3P_TH2  I12
  DB5      3    IO2  TDR_3P_TH2  I12

TDR_SE_40_OHM_TOP   @S9S_MB_2U_LIB.S9S_MB_2U(SCH_1):TDR_SE_40_OHM_TOP
  DB1      2    IO1  TDR_3P_TH2   I1
  DB1      3    IO2  TDR_3P_TH2   I1

TDR_SE_50_OHM_BOT   @S9S_MB_2U_LIB.S9S_MB_2U(SCH_1):TDR_SE_50_OHM_BOT
  DB12     2    IO1  TDR_3P_TH2  I85
  DB12     3    IO2  TDR_3P_TH2  I85

TDR_SE_50_OHM_IN1   @S9S_MB_2U_LIB.S9S_MB_2U(SCH_1):TDR_SE_50_OHM_IN1
  DB8      2    IO1  TDR_3P_TH2  I87
  DB8      3    IO2  TDR_3P_TH2  I87

TDR_SE_50_OHM_IN2   @S9S_MB_2U_LIB.S9S_MB_2U(SCH_1):TDR_SE_50_OHM_IN2
  DB9      2    IO1  TDR_3P_TH2  I88
  DB9      3    IO2  TDR_3P_TH2  I88

TDR_SE_50_OHM_IN3   @S9S_MB_2U_LIB.S9S_MB_2U(SCH_1):TDR_SE_50_OHM_IN3
  DB10     2    IO1  TDR_3P_TH2  I92
  DB10     3    IO2  TDR_3P_TH2  I92

TDR_SE_50_OHM_IN4   @S9S_MB_2U_LIB.S9S_MB_2U(SCH_1):TDR_SE_50_OHM_IN4
  DB11     2    IO1  TDR_3P_TH2  I93
  DB11     3    IO2  TDR_3P_TH2  I93

TDR_SE_50_OHM_TOP   @S9S_MB_2U_LIB.S9S_MB_2U(SCH_1):TDR_SE_50_OHM_TOP
  DB7      2    IO1  TDR_3P_TH2  I86
  DB7      3    IO2  TDR_3P_TH2  I86

TMP75_1_ADDR0   @S9S_MB_2U_LIB.S9S_MB_2U(SCH_1):TMP75_1_ADDR0
  R719     2      B  Q_RES       I29
  R720     1      A  Q_RES       I32
  U63      7     A0  TMP75AIDR    I1

TMP75_1_ADDR1   @S9S_MB_2U_LIB.S9S_MB_2U(SCH_1):TMP75_1_ADDR1
  R715     2      B  Q_RES       I28
  R716     1      A  Q_RES       I31
  U63      6     A1  TMP75AIDR    I1

TMP75_1_ADDR2   @S9S_MB_2U_LIB.S9S_MB_2U(SCH_1):TMP75_1_ADDR2
  R711     2      B  Q_RES       I27
  R712     1      A  Q_RES       I30
  U63      5     A2  TMP75AIDR    I1

TMP75_2_ADDR0   @S9S_MB_2U_LIB.S9S_MB_2U(SCH_1):TMP75_2_ADDR0
  R732     2      B  Q_RES       I85
  R733     1      A  Q_RES       I88
  U65      7     A0  TMP75AIDR   I84

TMP75_2_ADDR1   @S9S_MB_2U_LIB.S9S_MB_2U(SCH_1):TMP75_2_ADDR1
  R730     2      B  Q_RES       I86
  R731     1      A  Q_RES       I89
  U65      6     A1  TMP75AIDR   I84

TMP75_2_ADDR2   @S9S_MB_2U_LIB.S9S_MB_2U(SCH_1):TMP75_2_ADDR2
  R728     2      B  Q_RES       I87
  R729     1      A  Q_RES       I90
  U65      5     A2  TMP75AIDR   I84

TP_MP5981_0_IMON   @S9S_MB_2U_LIB.S9S_MB_2U(SCH_1):TP_MP5981_0_IMON
  R2141    1      A  Q_RES       I151
  U107    22   IMON  MP5981GLUZ  I113

TP_MP5981_1_IMON   @S9S_MB_2U_LIB.S9S_MB_2U(SCH_1):TP_MP5981_1_IMON
  R2142    1      A  Q_RES       I109
  U81     22   IMON  MP5981GLUZ  I66

T_GND           @S9S_MB_2U_LIB.S9S_MB_2U(SCH_1):T_GND
  DB1      1    GND  TDR_3P_TH2   I1
  DB2      1    GND  TDR_3P_TH2   I3
  DB3      1    GND  TDR_3P_TH2   I5
  DB4      1    GND  TDR_3P_TH2   I9
  DB5      1    GND  TDR_3P_TH2  I12
  DB6      1    GND  TDR_3P_TH2   I7
  DB7      1    GND  TDR_3P_TH2  I86
  DB8      1    GND  TDR_3P_TH2  I87
  DB9      1    GND  TDR_3P_TH2  I88
  DB10     1    GND  TDR_3P_TH2  I92
  DB11     1    GND  TDR_3P_TH2  I93
  DB12     1    GND  TDR_3P_TH2  I85
  X1       2     P1  TP_TDR_4P_FTS  I13
  X1       3     P2  TP_TDR_4P_FTS  I13
  X2       2     P1  TP_TDR_4P_FTS  I18
  X2       3     P2  TP_TDR_4P_FTS  I18
  X3       2     P1  TP_TDR_4P_FTS  I39
  X3       3     P2  TP_TDR_4P_FTS  I39
  X4       2     P1  TP_TDR_4P_FTS  I47
  X4       3     P2  TP_TDR_4P_FTS  I47
  X5       2     P1  TP_TDR_4P_FTS  I48
  X5       3     P2  TP_TDR_4P_FTS  I48
  X6       2     P1  TP_TDR_4P_FTS  I53
  X6       3     P2  TP_TDR_4P_FTS  I53
  X7       2     P1  TP_TDR_4P_FTS  I15
  X7       3     P2  TP_TDR_4P_FTS  I15
  X8       2     P1  TP_TDR_4P_FTS  I19
  X8       3     P2  TP_TDR_4P_FTS  I19
  X9       2     P1  TP_TDR_4P_FTS  I41
  X9       3     P2  TP_TDR_4P_FTS  I41
  X10      2     P1  TP_TDR_4P_FTS  I44
  X10      3     P2  TP_TDR_4P_FTS  I44
  X11      2     P1  TP_TDR_4P_FTS  I45
  X11      3     P2  TP_TDR_4P_FTS  I45
  X12      2     P1  TP_TDR_4P_FTS  I52
  X12      3     P2  TP_TDR_4P_FTS  I52
  X13      2     P1  TP_TDR_4P_FTS  I68
  X13      3     P2  TP_TDR_4P_FTS  I68
  X14      2     P1  TP_TDR_4P_FTS  I67
  X14      3     P2  TP_TDR_4P_FTS  I67
  X15      2     P1  TP_TDR_4P_FTS  I66
  X15      3     P2  TP_TDR_4P_FTS  I66
  X16      2     P1  TP_TDR_4P_FTS  I62
  X16      3     P2  TP_TDR_4P_FTS  I62
  X17      2     P1  TP_TDR_4P_FTS  I61
  X17      3     P2  TP_TDR_4P_FTS  I61
  X18      2     P1  TP_TDR_4P_FTS  I55
  X18      3     P2  TP_TDR_4P_FTS  I55
  X19      2     P1  TP_TDR_4P_FTS  I73
  X19      3     P2  TP_TDR_4P_FTS  I73
  X20      2     P1  TP_TDR_4P_FTS  I74
  X20      3     P2  TP_TDR_4P_FTS  I74
  X21      2     P1  TP_TDR_4P_FTS  I72
  X21      3     P2  TP_TDR_4P_FTS  I72
  X22      2     P1  TP_TDR_4P_FTS  I69
  X22      3     P2  TP_TDR_4P_FTS  I69
  X23      2     P1  TP_TDR_4P_FTS  I78
  X23      3     P2  TP_TDR_4P_FTS  I78
  X24      2     P1  TP_TDR_4P_FTS  I57
  X24      3     P2  TP_TDR_4P_FTS  I57

UNNAMED_222_QRES_I129_A   @S9S_MB_2U_LIB.S9S_MB_2U(SCH_1):UNNAMED_222_QRES_I129_A
  R655     1      A  Q_RES       I129
  R656     1      A  Q_RES       I130
  R657     1      A  Q_RES       I131
  R658     1      A  Q_RES       I132

UPI_CPU0_CPU1_P0P1_DN<0>   @S9S_MB_2U_LIB.S9S_MB_2U(SCH_1):UPI_CPU0_CPU1_P0P1_DN<0>
  U1     EH2  UPI1_RX_DN0  SOCKET4677_AZIFS054P001C01  I21
  U2      K4  UPI0_TX_DN0  SOCKET4677_AZIFS054P001C01  I70

UPI_CPU0_CPU1_P0P1_DN<1>   @S9S_MB_2U_LIB.S9S_MB_2U(SCH_1):UPI_CPU0_CPU1_P0P1_DN<1>
  U1     EE3  UPI1_RX_DN1  SOCKET4677_AZIFS054P001C01  I21
  U2      M2  UPI0_TX_DN1  SOCKET4677_AZIFS054P001C01  I70

UPI_CPU0_CPU1_P0P1_DN<2>   @S9S_MB_2U_LIB.S9S_MB_2U(SCH_1):UPI_CPU0_CPU1_P0P1_DN<2>
  U1     ED2  UPI1_RX_DN2  SOCKET4677_AZIFS054P001C01  I21
  U2      N1  UPI0_TX_DN2  SOCKET4677_AZIFS054P001C01  I70

UPI_CPU0_CPU1_P0P1_DN<3>   @S9S_MB_2U_LIB.S9S_MB_2U(SCH_1):UPI_CPU0_CPU1_P0P1_DN<3>
  U1     EA1  UPI1_RX_DN3  SOCKET4677_AZIFS054P001C01  I21
  U2      T2  UPI0_TX_DN3  SOCKET4677_AZIFS054P001C01  I70

UPI_CPU0_CPU1_P0P1_DN<4>   @S9S_MB_2U_LIB.S9S_MB_2U(SCH_1):UPI_CPU0_CPU1_P0P1_DN<4>
  U1     DY2  UPI1_RX_DN4  SOCKET4677_AZIFS054P001C01  I21
  U2      U1  UPI0_TX_DN4  SOCKET4677_AZIFS054P001C01  I70

UPI_CPU0_CPU1_P0P1_DN<5>   @S9S_MB_2U_LIB.S9S_MB_2U(SCH_1):UPI_CPU0_CPU1_P0P1_DN<5>
  U1     DU1  UPI1_RX_DN5  SOCKET4677_AZIFS054P001C01  I21
  U2      Y2  UPI0_TX_DN5  SOCKET4677_AZIFS054P001C01  I70

UPI_CPU0_CPU1_P0P1_DN<6>   @S9S_MB_2U_LIB.S9S_MB_2U(SCH_1):UPI_CPU0_CPU1_P0P1_DN<6>
  U1     DT2  UPI1_RX_DN6  SOCKET4677_AZIFS054P001C01  I21
  U2     AA1  UPI0_TX_DN6  SOCKET4677_AZIFS054P001C01  I70

UPI_CPU0_CPU1_P0P1_DN<7>   @S9S_MB_2U_LIB.S9S_MB_2U(SCH_1):UPI_CPU0_CPU1_P0P1_DN<7>
  U1     DN1  UPI1_RX_DN7  SOCKET4677_AZIFS054P001C01  I21
  U2     AD2  UPI0_TX_DN7  SOCKET4677_AZIFS054P001C01  I70

UPI_CPU0_CPU1_P0P1_DN<8>   @S9S_MB_2U_LIB.S9S_MB_2U(SCH_1):UPI_CPU0_CPU1_P0P1_DN<8>
  U1     DL3  UPI1_RX_DN8  SOCKET4677_AZIFS054P001C01  I21
  U2     AF2  UPI0_TX_DN8  SOCKET4677_AZIFS054P001C01  I70

UPI_CPU0_CPU1_P0P1_DN<9>   @S9S_MB_2U_LIB.S9S_MB_2U(SCH_1):UPI_CPU0_CPU1_P0P1_DN<9>
  U1     DJ1  UPI1_RX_DN9  SOCKET4677_AZIFS054P001C01  I21
  U2     AH2  UPI0_TX_DN9  SOCKET4677_AZIFS054P001C01  I70

UPI_CPU0_CPU1_P0P1_DN<10>   @S9S_MB_2U_LIB.S9S_MB_2U(SCH_1):UPI_CPU0_CPU1_P0P1_DN<10>
  U1     DG3  UPI1_RX_DN10  SOCKET4677_AZIFS054P001C01  I21
  U2     AK2  UPI0_TX_DN10  SOCKET4677_AZIFS054P001C01  I70

UPI_CPU0_CPU1_P0P1_DN<11>   @S9S_MB_2U_LIB.S9S_MB_2U(SCH_1):UPI_CPU0_CPU1_P0P1_DN<11>
  U1     DE1  UPI1_RX_DN11  SOCKET4677_AZIFS054P001C01  I21
  U2     AM2  UPI0_TX_DN11  SOCKET4677_AZIFS054P001C01  I70

UPI_CPU0_CPU1_P0P1_DN<12>   @S9S_MB_2U_LIB.S9S_MB_2U(SCH_1):UPI_CPU0_CPU1_P0P1_DN<12>
  U1     DD2  UPI1_RX_DN12  SOCKET4677_AZIFS054P001C01  I21
  U2     AN1  UPI0_TX_DP12  SOCKET4677_AZIFS054P001C01  I70

UPI_CPU0_CPU1_P0P1_DN<13>   @S9S_MB_2U_LIB.S9S_MB_2U(SCH_1):UPI_CPU0_CPU1_P0P1_DN<13>
  U1     DB2  UPI1_RX_DN13  SOCKET4677_AZIFS054P001C01  I21
  U2     AR3  UPI0_TX_DP13  SOCKET4677_AZIFS054P001C01  I70

UPI_CPU0_CPU1_P0P1_DN<14>   @S9S_MB_2U_LIB.S9S_MB_2U(SCH_1):UPI_CPU0_CPU1_P0P1_DN<14>
  U1     CY2  UPI1_RX_DN14  SOCKET4677_AZIFS054P001C01  I21
  U2     AU1  UPI0_TX_DN14  SOCKET4677_AZIFS054P001C01  I70

UPI_CPU0_CPU1_P0P1_DN<15>   @S9S_MB_2U_LIB.S9S_MB_2U(SCH_1):UPI_CPU0_CPU1_P0P1_DN<15>
  U1     CV2  UPI1_RX_DN15  SOCKET4677_AZIFS054P001C01  I21
  U2     AW3  UPI0_TX_DP15  SOCKET4677_AZIFS054P001C01  I70

UPI_CPU0_CPU1_P0P1_DN<16>   @S9S_MB_2U_LIB.S9S_MB_2U(SCH_1):UPI_CPU0_CPU1_P0P1_DN<16>
  U1     CR3  UPI1_RX_DN16  SOCKET4677_AZIFS054P001C01  I21
  U2     BB2  UPI0_TX_DN16  SOCKET4677_AZIFS054P001C01  I70

UPI_CPU0_CPU1_P0P1_DN<17>   @S9S_MB_2U_LIB.S9S_MB_2U(SCH_1):UPI_CPU0_CPU1_P0P1_DN<17>
  U1     CN1  UPI1_RX_DN17  SOCKET4677_AZIFS054P001C01  I21
  U2     BD2  UPI0_TX_DN17  SOCKET4677_AZIFS054P001C01  I70

UPI_CPU0_CPU1_P0P1_DN<18>   @S9S_MB_2U_LIB.S9S_MB_2U(SCH_1):UPI_CPU0_CPU1_P0P1_DN<18>
  U1     CL3  UPI1_RX_DN18  SOCKET4677_AZIFS054P001C01  I21
  U2     BF2  UPI0_TX_DN18  SOCKET4677_AZIFS054P001C01  I70

UPI_CPU0_CPU1_P0P1_DN<19>   @S9S_MB_2U_LIB.S9S_MB_2U(SCH_1):UPI_CPU0_CPU1_P0P1_DN<19>
  U1     CJ1  UPI1_RX_DN19  SOCKET4677_AZIFS054P001C01  I21
  U2     BH2  UPI0_TX_DN19  SOCKET4677_AZIFS054P001C01  I70

UPI_CPU0_CPU1_P0P1_DN<20>   @S9S_MB_2U_LIB.S9S_MB_2U(SCH_1):UPI_CPU0_CPU1_P0P1_DN<20>
  U1     CH2  UPI1_RX_DN20  SOCKET4677_AZIFS054P001C01  I21
  U2     BJ1  UPI0_TX_DP20  SOCKET4677_AZIFS054P001C01  I70

UPI_CPU0_CPU1_P0P1_DN<21>   @S9S_MB_2U_LIB.S9S_MB_2U(SCH_1):UPI_CPU0_CPU1_P0P1_DN<21>
  U1     CF2  UPI1_RX_DN21  SOCKET4677_AZIFS054P001C01  I21
  U2     BL3  UPI0_TX_DP21  SOCKET4677_AZIFS054P001C01  I70

UPI_CPU0_CPU1_P0P1_DN<22>   @S9S_MB_2U_LIB.S9S_MB_2U(SCH_1):UPI_CPU0_CPU1_P0P1_DN<22>
  U1     CD2  UPI1_RX_DN22  SOCKET4677_AZIFS054P001C01  I21
  U2     BN3  UPI0_TX_DP22  SOCKET4677_AZIFS054P001C01  I70

UPI_CPU0_CPU1_P0P1_DN<23>   @S9S_MB_2U_LIB.S9S_MB_2U(SCH_1):UPI_CPU0_CPU1_P0P1_DN<23>
  U1     CB2  UPI1_RX_DN23  SOCKET4677_AZIFS054P001C01  I21
  U2     BT2  UPI0_TX_DN23  SOCKET4677_AZIFS054P001C01  I70

UPI_CPU0_CPU1_P0P1_DP<0>   @S9S_MB_2U_LIB.S9S_MB_2U(SCH_1):UPI_CPU0_CPU1_P0P1_DP<0>
  U1     EJ3  UPI1_RX_DP0  SOCKET4677_AZIFS054P001C01  I21
  U2      J3  UPI0_TX_DP0  SOCKET4677_AZIFS054P001C01  I70

UPI_CPU0_CPU1_P0P1_DP<1>   @S9S_MB_2U_LIB.S9S_MB_2U(SCH_1):UPI_CPU0_CPU1_P0P1_DP<1>
  U1     EG3  UPI1_RX_DP1  SOCKET4677_AZIFS054P001C01  I21
  U2      L3  UPI0_TX_DP1  SOCKET4677_AZIFS054P001C01  I70

UPI_CPU0_CPU1_P0P1_DP<2>   @S9S_MB_2U_LIB.S9S_MB_2U(SCH_1):UPI_CPU0_CPU1_P0P1_DP<2>
  U1     EC3  UPI1_RX_DP2  SOCKET4677_AZIFS054P001C01  I21
  U2      P2  UPI0_TX_DP2  SOCKET4677_AZIFS054P001C01  I70

UPI_CPU0_CPU1_P0P1_DP<3>   @S9S_MB_2U_LIB.S9S_MB_2U(SCH_1):UPI_CPU0_CPU1_P0P1_DP<3>
  U1     EB2  UPI1_RX_DP3  SOCKET4677_AZIFS054P001C01  I21
  U2      R3  UPI0_TX_DP3  SOCKET4677_AZIFS054P001C01  I70

UPI_CPU0_CPU1_P0P1_DP<4>   @S9S_MB_2U_LIB.S9S_MB_2U(SCH_1):UPI_CPU0_CPU1_P0P1_DP<4>
  U1     DW3  UPI1_RX_DP4  SOCKET4677_AZIFS054P001C01  I21
  U2      V2  UPI0_TX_DP4  SOCKET4677_AZIFS054P001C01  I70

UPI_CPU0_CPU1_P0P1_DP<5>   @S9S_MB_2U_LIB.S9S_MB_2U(SCH_1):UPI_CPU0_CPU1_P0P1_DP<5>
  U1     DV2  UPI1_RX_DP5  SOCKET4677_AZIFS054P001C01  I21
  U2      W3  UPI0_TX_DP5  SOCKET4677_AZIFS054P001C01  I70

UPI_CPU0_CPU1_P0P1_DP<6>   @S9S_MB_2U_LIB.S9S_MB_2U(SCH_1):UPI_CPU0_CPU1_P0P1_DP<6>
  U1     DR3  UPI1_RX_DP6  SOCKET4677_AZIFS054P001C01  I21
  U2     AB2  UPI0_TX_DP6  SOCKET4677_AZIFS054P001C01  I70

UPI_CPU0_CPU1_P0P1_DP<7>   @S9S_MB_2U_LIB.S9S_MB_2U(SCH_1):UPI_CPU0_CPU1_P0P1_DP<7>
  U1     DP2  UPI1_RX_DP7  SOCKET4677_AZIFS054P001C01  I21
  U2     AC3  UPI0_TX_DP7  SOCKET4677_AZIFS054P001C01  I70

UPI_CPU0_CPU1_P0P1_DP<8>   @S9S_MB_2U_LIB.S9S_MB_2U(SCH_1):UPI_CPU0_CPU1_P0P1_DP<8>
  U1     DM2  UPI1_RX_DP8  SOCKET4677_AZIFS054P001C01  I21
  U2     AE1  UPI0_TX_DP8  SOCKET4677_AZIFS054P001C01  I70

UPI_CPU0_CPU1_P0P1_DP<9>   @S9S_MB_2U_LIB.S9S_MB_2U(SCH_1):UPI_CPU0_CPU1_P0P1_DP<9>
  U1     DK2  UPI1_RX_DP9  SOCKET4677_AZIFS054P001C01  I21
  U2     AG3  UPI0_TX_DP9  SOCKET4677_AZIFS054P001C01  I70

UPI_CPU0_CPU1_P0P1_DP<10>   @S9S_MB_2U_LIB.S9S_MB_2U(SCH_1):UPI_CPU0_CPU1_P0P1_DP<10>
  U1     DH2  UPI1_RX_DP10  SOCKET4677_AZIFS054P001C01  I21
  U2     AJ1  UPI0_TX_DP10  SOCKET4677_AZIFS054P001C01  I70

UPI_CPU0_CPU1_P0P1_DP<11>   @S9S_MB_2U_LIB.S9S_MB_2U(SCH_1):UPI_CPU0_CPU1_P0P1_DP<11>
  U1     DF2  UPI1_RX_DP11  SOCKET4677_AZIFS054P001C01  I21
  U2     AL3  UPI0_TX_DP11  SOCKET4677_AZIFS054P001C01  I70

UPI_CPU0_CPU1_P0P1_DP<12>   @S9S_MB_2U_LIB.S9S_MB_2U(SCH_1):UPI_CPU0_CPU1_P0P1_DP<12>
  U1     DC3  UPI1_RX_DP12  SOCKET4677_AZIFS054P001C01  I21
  U2     AP2  UPI0_TX_DN12  SOCKET4677_AZIFS054P001C01  I70

UPI_CPU0_CPU1_P0P1_DP<13>   @S9S_MB_2U_LIB.S9S_MB_2U(SCH_1):UPI_CPU0_CPU1_P0P1_DP<13>
  U1     DA1  UPI1_RX_DP13  SOCKET4677_AZIFS054P001C01  I21
  U2     AT2  UPI0_TX_DN13  SOCKET4677_AZIFS054P001C01  I70

UPI_CPU0_CPU1_P0P1_DP<14>   @S9S_MB_2U_LIB.S9S_MB_2U(SCH_1):UPI_CPU0_CPU1_P0P1_DP<14>
  U1     CW3  UPI1_RX_DP14  SOCKET4677_AZIFS054P001C01  I21
  U2     AV2  UPI0_TX_DP14  SOCKET4677_AZIFS054P001C01  I70

UPI_CPU0_CPU1_P0P1_DP<15>   @S9S_MB_2U_LIB.S9S_MB_2U(SCH_1):UPI_CPU0_CPU1_P0P1_DP<15>
  U1     CU1  UPI1_RX_DP15  SOCKET4677_AZIFS054P001C01  I21
  U2     AY2  UPI0_TX_DN15  SOCKET4677_AZIFS054P001C01  I70

UPI_CPU0_CPU1_P0P1_DP<16>   @S9S_MB_2U_LIB.S9S_MB_2U(SCH_1):UPI_CPU0_CPU1_P0P1_DP<16>
  U1     CT2  UPI1_RX_DP16  SOCKET4677_AZIFS054P001C01  I21
  U2     BA1  UPI0_TX_DP16  SOCKET4677_AZIFS054P001C01  I70

UPI_CPU0_CPU1_P0P1_DP<17>   @S9S_MB_2U_LIB.S9S_MB_2U(SCH_1):UPI_CPU0_CPU1_P0P1_DP<17>
  U1     CP2  UPI1_RX_DP17  SOCKET4677_AZIFS054P001C01  I21
  U2     BC3  UPI0_TX_DP17  SOCKET4677_AZIFS054P001C01  I70

UPI_CPU0_CPU1_P0P1_DP<18>   @S9S_MB_2U_LIB.S9S_MB_2U(SCH_1):UPI_CPU0_CPU1_P0P1_DP<18>
  U1     CM2  UPI1_RX_DP18  SOCKET4677_AZIFS054P001C01  I21
  U2     BE1  UPI0_TX_DP18  SOCKET4677_AZIFS054P001C01  I70

UPI_CPU0_CPU1_P0P1_DP<19>   @S9S_MB_2U_LIB.S9S_MB_2U(SCH_1):UPI_CPU0_CPU1_P0P1_DP<19>
  U1     CK2  UPI1_RX_DP19  SOCKET4677_AZIFS054P001C01  I21
  U2     BG3  UPI0_TX_DP19  SOCKET4677_AZIFS054P001C01  I70

UPI_CPU0_CPU1_P0P1_DP<20>   @S9S_MB_2U_LIB.S9S_MB_2U(SCH_1):UPI_CPU0_CPU1_P0P1_DP<20>
  U1     CG3  UPI1_RX_DP20  SOCKET4677_AZIFS054P001C01  I21
  U2     BK2  UPI0_TX_DN20  SOCKET4677_AZIFS054P001C01  I70

UPI_CPU0_CPU1_P0P1_DP<21>   @S9S_MB_2U_LIB.S9S_MB_2U(SCH_1):UPI_CPU0_CPU1_P0P1_DP<21>
  U1     CE1  UPI1_RX_DP21  SOCKET4677_AZIFS054P001C01  I21
  U2     BM2  UPI0_TX_DN21  SOCKET4677_AZIFS054P001C01  I70

UPI_CPU0_CPU1_P0P1_DP<22>   @S9S_MB_2U_LIB.S9S_MB_2U(SCH_1):UPI_CPU0_CPU1_P0P1_DP<22>
  U1     CC3  UPI1_RX_DP22  SOCKET4677_AZIFS054P001C01  I21
  U2     BR3  UPI0_TX_DN22  SOCKET4677_AZIFS054P001C01  I70

UPI_CPU0_CPU1_P0P1_DP<23>   @S9S_MB_2U_LIB.S9S_MB_2U(SCH_1):UPI_CPU0_CPU1_P0P1_DP<23>
  U1     BY2  UPI1_RX_DP23  SOCKET4677_AZIFS054P001C01  I21
  U2     BU3  UPI0_TX_DP23  SOCKET4677_AZIFS054P001C01  I70

UPI_CPU0_CPU1_P1P0_DN<0>   @S9S_MB_2U_LIB.S9S_MB_2U(SCH_1):UPI_CPU0_CPU1_P1P0_DN<0>
  U1      K6  UPI0_RX_DN0  SOCKET4677_AZIFS054P001C01  I51
  U2     EF6  UPI1_TX_DN0  SOCKET4677_AZIFS054P001C01  I102

UPI_CPU0_CPU1_P1P0_DN<1>   @S9S_MB_2U_LIB.S9S_MB_2U(SCH_1):UPI_CPU0_CPU1_P1P0_DN<1>
  U1      N5  UPI0_RX_DN1  SOCKET4677_AZIFS054P001C01  I51
  U2     EC7  UPI1_TX_DN1  SOCKET4677_AZIFS054P001C01  I102

UPI_CPU0_CPU1_P1P0_DN<2>   @S9S_MB_2U_LIB.S9S_MB_2U(SCH_1):UPI_CPU0_CPU1_P1P0_DN<2>
  U1      P6  UPI0_RX_DN2  SOCKET4677_AZIFS054P001C01  I51
  U2     EB6  UPI1_TX_DN2  SOCKET4677_AZIFS054P001C01  I102

UPI_CPU0_CPU1_P1P0_DN<3>   @S9S_MB_2U_LIB.S9S_MB_2U(SCH_1):UPI_CPU0_CPU1_P1P0_DN<3>
  U1      U5  UPI0_RX_DN3  SOCKET4677_AZIFS054P001C01  I51
  U2     DW7  UPI1_TX_DP3  SOCKET4677_AZIFS054P001C01  I102

UPI_CPU0_CPU1_P1P0_DN<4>   @S9S_MB_2U_LIB.S9S_MB_2U(SCH_1):UPI_CPU0_CPU1_P1P0_DN<4>
  U1      V6  UPI0_RX_DN4  SOCKET4677_AZIFS054P001C01  I51
  U2     DV6  UPI1_TX_DN4  SOCKET4677_AZIFS054P001C01  I102

UPI_CPU0_CPU1_P1P0_DN<5>   @S9S_MB_2U_LIB.S9S_MB_2U(SCH_1):UPI_CPU0_CPU1_P1P0_DN<5>
  U1     AA5  UPI0_RX_DN5  SOCKET4677_AZIFS054P001C01  I51
  U2     DR7  UPI1_TX_DP5  SOCKET4677_AZIFS054P001C01  I102

UPI_CPU0_CPU1_P1P0_DN<6>   @S9S_MB_2U_LIB.S9S_MB_2U(SCH_1):UPI_CPU0_CPU1_P1P0_DN<6>
  U1     AB6  UPI0_RX_DN6  SOCKET4677_AZIFS054P001C01  I51
  U2     DP6  UPI1_TX_DN6  SOCKET4677_AZIFS054P001C01  I102

UPI_CPU0_CPU1_P1P0_DN<7>   @S9S_MB_2U_LIB.S9S_MB_2U(SCH_1):UPI_CPU0_CPU1_P1P0_DN<7>
  U1     AE5  UPI0_RX_DN7  SOCKET4677_AZIFS054P001C01  I51
  U2     DL7  UPI1_TX_DN7  SOCKET4677_AZIFS054P001C01  I102

UPI_CPU0_CPU1_P1P0_DN<8>   @S9S_MB_2U_LIB.S9S_MB_2U(SCH_1):UPI_CPU0_CPU1_P1P0_DN<8>
  U1     AF6  UPI0_RX_DN8  SOCKET4677_AZIFS054P001C01  I51
  U2     DK6  UPI1_TX_DN8  SOCKET4677_AZIFS054P001C01  I102

UPI_CPU0_CPU1_P1P0_DN<9>   @S9S_MB_2U_LIB.S9S_MB_2U(SCH_1):UPI_CPU0_CPU1_P1P0_DN<9>
  U1     AH6  UPI0_RX_DN9  SOCKET4677_AZIFS054P001C01  I51
  U2     DH6  UPI1_TX_DN9  SOCKET4677_AZIFS054P001C01  I102

UPI_CPU0_CPU1_P1P0_DN<10>   @S9S_MB_2U_LIB.S9S_MB_2U(SCH_1):UPI_CPU0_CPU1_P1P0_DN<10>
  U1     AK6  UPI0_RX_DN10  SOCKET4677_AZIFS054P001C01  I51
  U2     DF6  UPI1_TX_DP10  SOCKET4677_AZIFS054P001C01  I102

UPI_CPU0_CPU1_P1P0_DN<11>   @S9S_MB_2U_LIB.S9S_MB_2U(SCH_1):UPI_CPU0_CPU1_P1P0_DN<11>
  U1     AN5  UPI0_RX_DN11  SOCKET4677_AZIFS054P001C01  I51
  U2     DC7  UPI1_TX_DP11  SOCKET4677_AZIFS054P001C01  I102

UPI_CPU0_CPU1_P1P0_DN<12>   @S9S_MB_2U_LIB.S9S_MB_2U(SCH_1):UPI_CPU0_CPU1_P1P0_DN<12>
  U1     AP6  UPI0_RX_DN12  SOCKET4677_AZIFS054P001C01  I51
  U2     DB6  UPI1_TX_DP12  SOCKET4677_AZIFS054P001C01  I102

UPI_CPU0_CPU1_P1P0_DN<13>   @S9S_MB_2U_LIB.S9S_MB_2U(SCH_1):UPI_CPU0_CPU1_P1P0_DN<13>
  U1     AU5  UPI0_RX_DN13  SOCKET4677_AZIFS054P001C01  I51
  U2     CW7  UPI1_TX_DP13  SOCKET4677_AZIFS054P001C01  I102

UPI_CPU0_CPU1_P1P0_DN<14>   @S9S_MB_2U_LIB.S9S_MB_2U(SCH_1):UPI_CPU0_CPU1_P1P0_DN<14>
  U1     AV6  UPI0_RX_DN14  SOCKET4677_AZIFS054P001C01  I51
  U2     CV6  UPI1_TX_DP14  SOCKET4677_AZIFS054P001C01  I102

UPI_CPU0_CPU1_P1P0_DN<15>   @S9S_MB_2U_LIB.S9S_MB_2U(SCH_1):UPI_CPU0_CPU1_P1P0_DN<15>
  U1     BA5  UPI0_RX_DN15  SOCKET4677_AZIFS054P001C01  I51
  U2     CR7  UPI1_TX_DP15  SOCKET4677_AZIFS054P001C01  I102

UPI_CPU0_CPU1_P1P0_DN<16>   @S9S_MB_2U_LIB.S9S_MB_2U(SCH_1):UPI_CPU0_CPU1_P1P0_DN<16>
  U1     BB6  UPI0_RX_DN16  SOCKET4677_AZIFS054P001C01  I51
  U2     CP6  UPI1_TX_DP16  SOCKET4677_AZIFS054P001C01  I102

UPI_CPU0_CPU1_P1P0_DN<17>   @S9S_MB_2U_LIB.S9S_MB_2U(SCH_1):UPI_CPU0_CPU1_P1P0_DN<17>
  U1     BE5  UPI0_RX_DN17  SOCKET4677_AZIFS054P001C01  I51
  U2     CL7  UPI1_TX_DP17  SOCKET4677_AZIFS054P001C01  I102

UPI_CPU0_CPU1_P1P0_DN<18>   @S9S_MB_2U_LIB.S9S_MB_2U(SCH_1):UPI_CPU0_CPU1_P1P0_DN<18>
  U1     BF6  UPI0_RX_DN18  SOCKET4677_AZIFS054P001C01  I51
  U2     CK6  UPI1_TX_DP18  SOCKET4677_AZIFS054P001C01  I102

UPI_CPU0_CPU1_P1P0_DN<19>   @S9S_MB_2U_LIB.S9S_MB_2U(SCH_1):UPI_CPU0_CPU1_P1P0_DN<19>
  U1     BJ5  UPI0_RX_DN19  SOCKET4677_AZIFS054P001C01  I51
  U2     CG7  UPI1_TX_DP19  SOCKET4677_AZIFS054P001C01  I102

UPI_CPU0_CPU1_P1P0_DN<20>   @S9S_MB_2U_LIB.S9S_MB_2U(SCH_1):UPI_CPU0_CPU1_P1P0_DN<20>
  U1     BK6  UPI0_RX_DN20  SOCKET4677_AZIFS054P001C01  I51
  U2     CF6  UPI1_TX_DP20  SOCKET4677_AZIFS054P001C01  I102

UPI_CPU0_CPU1_P1P0_DN<21>   @S9S_MB_2U_LIB.S9S_MB_2U(SCH_1):UPI_CPU0_CPU1_P1P0_DN<21>
  U1     BN5  UPI0_RX_DN21  SOCKET4677_AZIFS054P001C01  I51
  U2     CC7  UPI1_TX_DP21  SOCKET4677_AZIFS054P001C01  I102

UPI_CPU0_CPU1_P1P0_DN<22>   @S9S_MB_2U_LIB.S9S_MB_2U(SCH_1):UPI_CPU0_CPU1_P1P0_DN<22>
  U1     BR7  UPI0_RX_DN22  SOCKET4677_AZIFS054P001C01  I51
  U2     CA5  UPI1_TX_DN22  SOCKET4677_AZIFS054P001C01  I102

UPI_CPU0_CPU1_P1P0_DN<23>   @S9S_MB_2U_LIB.S9S_MB_2U(SCH_1):UPI_CPU0_CPU1_P1P0_DN<23>
  U1     BU5  UPI0_RX_DN23  SOCKET4677_AZIFS054P001C01  I51
  U2     BW7  UPI1_TX_DP23  SOCKET4677_AZIFS054P001C01  I102

UPI_CPU0_CPU1_P1P0_DP<0>   @S9S_MB_2U_LIB.S9S_MB_2U(SCH_1):UPI_CPU0_CPU1_P1P0_DP<0>
  U1      L7  UPI0_RX_DP0  SOCKET4677_AZIFS054P001C01  I51
  U2     EE5  UPI1_TX_DP0  SOCKET4677_AZIFS054P001C01  I102

UPI_CPU0_CPU1_P1P0_DP<1>   @S9S_MB_2U_LIB.S9S_MB_2U(SCH_1):UPI_CPU0_CPU1_P1P0_DP<1>
  U1      M6  UPI0_RX_DP1  SOCKET4677_AZIFS054P001C01  I51
  U2     ED6  UPI1_TX_DP1  SOCKET4677_AZIFS054P001C01  I102

UPI_CPU0_CPU1_P1P0_DP<2>   @S9S_MB_2U_LIB.S9S_MB_2U(SCH_1):UPI_CPU0_CPU1_P1P0_DP<2>
  U1      R7  UPI0_RX_DP2  SOCKET4677_AZIFS054P001C01  I51
  U2     EA5  UPI1_TX_DP2  SOCKET4677_AZIFS054P001C01  I102

UPI_CPU0_CPU1_P1P0_DP<3>   @S9S_MB_2U_LIB.S9S_MB_2U(SCH_1):UPI_CPU0_CPU1_P1P0_DP<3>
  U1      T6  UPI0_RX_DP3  SOCKET4677_AZIFS054P001C01  I51
  U2     DY6  UPI1_TX_DN3  SOCKET4677_AZIFS054P001C01  I102

UPI_CPU0_CPU1_P1P0_DP<4>   @S9S_MB_2U_LIB.S9S_MB_2U(SCH_1):UPI_CPU0_CPU1_P1P0_DP<4>
  U1      W7  UPI0_RX_DP4  SOCKET4677_AZIFS054P001C01  I51
  U2     DU5  UPI1_TX_DP4  SOCKET4677_AZIFS054P001C01  I102

UPI_CPU0_CPU1_P1P0_DP<5>   @S9S_MB_2U_LIB.S9S_MB_2U(SCH_1):UPI_CPU0_CPU1_P1P0_DP<5>
  U1      Y6  UPI0_RX_DP5  SOCKET4677_AZIFS054P001C01  I51
  U2     DT6  UPI1_TX_DN5  SOCKET4677_AZIFS054P001C01  I102

UPI_CPU0_CPU1_P1P0_DP<6>   @S9S_MB_2U_LIB.S9S_MB_2U(SCH_1):UPI_CPU0_CPU1_P1P0_DP<6>
  U1     AC7  UPI0_RX_DP6  SOCKET4677_AZIFS054P001C01  I51
  U2     DN5  UPI1_TX_DP6  SOCKET4677_AZIFS054P001C01  I102

UPI_CPU0_CPU1_P1P0_DP<7>   @S9S_MB_2U_LIB.S9S_MB_2U(SCH_1):UPI_CPU0_CPU1_P1P0_DP<7>
  U1     AD6  UPI0_RX_DP7  SOCKET4677_AZIFS054P001C01  I51
  U2     DM6  UPI1_TX_DP7  SOCKET4677_AZIFS054P001C01  I102

UPI_CPU0_CPU1_P1P0_DP<8>   @S9S_MB_2U_LIB.S9S_MB_2U(SCH_1):UPI_CPU0_CPU1_P1P0_DP<8>
  U1     AG7  UPI0_RX_DP8  SOCKET4677_AZIFS054P001C01  I51
  U2     DJ5  UPI1_TX_DP8  SOCKET4677_AZIFS054P001C01  I102

UPI_CPU0_CPU1_P1P0_DP<9>   @S9S_MB_2U_LIB.S9S_MB_2U(SCH_1):UPI_CPU0_CPU1_P1P0_DP<9>
  U1     AJ5  UPI0_RX_DP9  SOCKET4677_AZIFS054P001C01  I51
  U2     DG7  UPI1_TX_DP9  SOCKET4677_AZIFS054P001C01  I102

UPI_CPU0_CPU1_P1P0_DP<10>   @S9S_MB_2U_LIB.S9S_MB_2U(SCH_1):UPI_CPU0_CPU1_P1P0_DP<10>
  U1     AL7  UPI0_RX_DP10  SOCKET4677_AZIFS054P001C01  I51
  U2     DE5  UPI1_TX_DN10  SOCKET4677_AZIFS054P001C01  I102

UPI_CPU0_CPU1_P1P0_DP<11>   @S9S_MB_2U_LIB.S9S_MB_2U(SCH_1):UPI_CPU0_CPU1_P1P0_DP<11>
  U1     AM6  UPI0_RX_DP11  SOCKET4677_AZIFS054P001C01  I51
  U2     DD6  UPI1_TX_DN11  SOCKET4677_AZIFS054P001C01  I102

UPI_CPU0_CPU1_P1P0_DP<12>   @S9S_MB_2U_LIB.S9S_MB_2U(SCH_1):UPI_CPU0_CPU1_P1P0_DP<12>
  U1     AR7  UPI0_RX_DP12  SOCKET4677_AZIFS054P001C01  I51
  U2     DA5  UPI1_TX_DN12  SOCKET4677_AZIFS054P001C01  I102

UPI_CPU0_CPU1_P1P0_DP<13>   @S9S_MB_2U_LIB.S9S_MB_2U(SCH_1):UPI_CPU0_CPU1_P1P0_DP<13>
  U1     AT6  UPI0_RX_DP13  SOCKET4677_AZIFS054P001C01  I51
  U2     CY6  UPI1_TX_DN13  SOCKET4677_AZIFS054P001C01  I102

UPI_CPU0_CPU1_P1P0_DP<14>   @S9S_MB_2U_LIB.S9S_MB_2U(SCH_1):UPI_CPU0_CPU1_P1P0_DP<14>
  U1     AW7  UPI0_RX_DP14  SOCKET4677_AZIFS054P001C01  I51
  U2     CU5  UPI1_TX_DN14  SOCKET4677_AZIFS054P001C01  I102

UPI_CPU0_CPU1_P1P0_DP<15>   @S9S_MB_2U_LIB.S9S_MB_2U(SCH_1):UPI_CPU0_CPU1_P1P0_DP<15>
  U1     AY6  UPI0_RX_DP15  SOCKET4677_AZIFS054P001C01  I51
  U2     CT6  UPI1_TX_DN15  SOCKET4677_AZIFS054P001C01  I102

UPI_CPU0_CPU1_P1P0_DP<16>   @S9S_MB_2U_LIB.S9S_MB_2U(SCH_1):UPI_CPU0_CPU1_P1P0_DP<16>
  U1     BC7  UPI0_RX_DP16  SOCKET4677_AZIFS054P001C01  I51
  U2     CN5  UPI1_TX_DN16  SOCKET4677_AZIFS054P001C01  I102

UPI_CPU0_CPU1_P1P0_DP<17>   @S9S_MB_2U_LIB.S9S_MB_2U(SCH_1):UPI_CPU0_CPU1_P1P0_DP<17>
  U1     BD6  UPI0_RX_DP17  SOCKET4677_AZIFS054P001C01  I51
  U2     CM6  UPI1_TX_DN17  SOCKET4677_AZIFS054P001C01  I102

UPI_CPU0_CPU1_P1P0_DP<18>   @S9S_MB_2U_LIB.S9S_MB_2U(SCH_1):UPI_CPU0_CPU1_P1P0_DP<18>
  U1     BG7  UPI0_RX_DP18  SOCKET4677_AZIFS054P001C01  I51
  U2     CJ5  UPI1_TX_DN18  SOCKET4677_AZIFS054P001C01  I102

UPI_CPU0_CPU1_P1P0_DP<19>   @S9S_MB_2U_LIB.S9S_MB_2U(SCH_1):UPI_CPU0_CPU1_P1P0_DP<19>
  U1     BH6  UPI0_RX_DP19  SOCKET4677_AZIFS054P001C01  I51
  U2     CH6  UPI1_TX_DN19  SOCKET4677_AZIFS054P001C01  I102

UPI_CPU0_CPU1_P1P0_DP<20>   @S9S_MB_2U_LIB.S9S_MB_2U(SCH_1):UPI_CPU0_CPU1_P1P0_DP<20>
  U1     BL7  UPI0_RX_DP20  SOCKET4677_AZIFS054P001C01  I51
  U2     CE5  UPI1_TX_DN20  SOCKET4677_AZIFS054P001C01  I102

UPI_CPU0_CPU1_P1P0_DP<21>   @S9S_MB_2U_LIB.S9S_MB_2U(SCH_1):UPI_CPU0_CPU1_P1P0_DP<21>
  U1     BM6  UPI0_RX_DP21  SOCKET4677_AZIFS054P001C01  I51
  U2     CD6  UPI1_TX_DN21  SOCKET4677_AZIFS054P001C01  I102

UPI_CPU0_CPU1_P1P0_DP<22>   @S9S_MB_2U_LIB.S9S_MB_2U(SCH_1):UPI_CPU0_CPU1_P1P0_DP<22>
  U1     BP6  UPI0_RX_DP22  SOCKET4677_AZIFS054P001C01  I51
  U2     CB6  UPI1_TX_DP22  SOCKET4677_AZIFS054P001C01  I102

UPI_CPU0_CPU1_P1P0_DP<23>   @S9S_MB_2U_LIB.S9S_MB_2U(SCH_1):UPI_CPU0_CPU1_P1P0_DP<23>
  U1     BT6  UPI0_RX_DP23  SOCKET4677_AZIFS054P001C01  I51
  U2     BY6  UPI1_TX_DN23  SOCKET4677_AZIFS054P001C01  I102

UPI_CPU0_CPU1_P2P2_DN<0>   @S9S_MB_2U_LIB.S9S_MB_2U(SCH_1):UPI_CPU0_CPU1_P2P2_DN<0>
  U1     E80  UPI2_RX_DN0  SOCKET4677_AZIFS054P001C01  I16
  U2     BM71  UPI2_TX_DN23  SOCKET4677_AZIFS054P001C01  I102

UPI_CPU0_CPU1_P2P2_DN<1>   @S9S_MB_2U_LIB.S9S_MB_2U(SCH_1):UPI_CPU0_CPU1_P2P2_DN<1>
  U1     F81  UPI2_RX_DN1  SOCKET4677_AZIFS054P001C01  I16
  U2     BG80  UPI2_TX_DN22  SOCKET4677_AZIFS054P001C01  I102

UPI_CPU0_CPU1_P2P2_DN<2>   @S9S_MB_2U_LIB.S9S_MB_2U(SCH_1):UPI_CPU0_CPU1_P2P2_DN<2>
  U1     G82  UPI2_RX_DN2  SOCKET4677_AZIFS054P001C01  I16
  U2     BF81  UPI2_TX_DN21  SOCKET4677_AZIFS054P001C01  I102

UPI_CPU0_CPU1_P2P2_DN<3>   @S9S_MB_2U_LIB.S9S_MB_2U(SCH_1):UPI_CPU0_CPU1_P2P2_DN<3>
  U1     K79  UPI2_RX_DN3  SOCKET4677_AZIFS054P001C01  I16
  U2     BD79  UPI2_TX_DN20  SOCKET4677_AZIFS054P001C01  I102

UPI_CPU0_CPU1_P2P2_DN<4>   @S9S_MB_2U_LIB.S9S_MB_2U(SCH_1):UPI_CPU0_CPU1_P2P2_DN<4>
  U1     J82  UPI2_RX_DN4  SOCKET4677_AZIFS054P001C01  I16
  U2     BE82  UPI2_TX_DN19  SOCKET4677_AZIFS054P001C01  I102

UPI_CPU0_CPU1_P2P2_DN<5>   @S9S_MB_2U_LIB.S9S_MB_2U(SCH_1):UPI_CPU0_CPU1_P2P2_DN<5>
  U1     L80  UPI2_RX_DN5  SOCKET4677_AZIFS054P001C01  I16
  U2     BC82  UPI2_TX_DN18  SOCKET4677_AZIFS054P001C01  I102

UPI_CPU0_CPU1_P2P2_DN<6>   @S9S_MB_2U_LIB.S9S_MB_2U(SCH_1):UPI_CPU0_CPU1_P2P2_DN<6>
  U1     AC80  UPI2_RX_DN6  SOCKET4677_AZIFS054P001C01  I16
  U2     BA80  UPI2_TX_DN17  SOCKET4677_AZIFS054P001C01  I102

UPI_CPU0_CPU1_P2P2_DN<7>   @S9S_MB_2U_LIB.S9S_MB_2U(SCH_1):UPI_CPU0_CPU1_P2P2_DN<7>
  U1     AD81  UPI2_RX_DN7  SOCKET4677_AZIFS054P001C01  I16
  U2     AV81  UPI2_TX_DN16  SOCKET4677_AZIFS054P001C01  I102

UPI_CPU0_CPU1_P2P2_DN<8>   @S9S_MB_2U_LIB.S9S_MB_2U(SCH_1):UPI_CPU0_CPU1_P2P2_DN<8>
  U1     AF79  UPI2_RX_DN8  SOCKET4677_AZIFS054P001C01  I16
  U2     AT83  UPI2_TX_DN15  SOCKET4677_AZIFS054P001C01  I102

UPI_CPU0_CPU1_P2P2_DN<9>   @S9S_MB_2U_LIB.S9S_MB_2U(SCH_1):UPI_CPU0_CPU1_P2P2_DN<9>
  U1     AE82  UPI2_RX_DN9  SOCKET4677_AZIFS054P001C01  I16
  U2     AR80  UPI2_TX_DN14  SOCKET4677_AZIFS054P001C01  I102

UPI_CPU0_CPU1_P2P2_DN<10>   @S9S_MB_2U_LIB.S9S_MB_2U(SCH_1):UPI_CPU0_CPU1_P2P2_DN<10>
  U1     AJ80  UPI2_RX_DN10  SOCKET4677_AZIFS054P001C01  I16
  U2     AN82  UPI2_TX_DN13  SOCKET4677_AZIFS054P001C01  I102

UPI_CPU0_CPU1_P2P2_DN<11>   @S9S_MB_2U_LIB.S9S_MB_2U(SCH_1):UPI_CPU0_CPU1_P2P2_DN<11>
  U1     AG82  UPI2_RX_DN11  SOCKET4677_AZIFS054P001C01  I16
  U2     AM81  UPI2_TX_DN12  SOCKET4677_AZIFS054P001C01  I102

UPI_CPU0_CPU1_P2P2_DN<12>   @S9S_MB_2U_LIB.S9S_MB_2U(SCH_1):UPI_CPU0_CPU1_P2P2_DN<12>
  U1     BA72  UPI2_RX_DN12  SOCKET4677_AZIFS054P001C01  I16
  U2     AU78  UPI2_TX_DN11  SOCKET4677_AZIFS054P001C01  I102

UPI_CPU0_CPU1_P2P2_DN<13>   @S9S_MB_2U_LIB.S9S_MB_2U(SCH_1):UPI_CPU0_CPU1_P2P2_DN<13>
  U1     AV73  UPI2_RX_DN13  SOCKET4677_AZIFS054P001C01  I16
  U2     AW78  UPI2_TX_DN10  SOCKET4677_AZIFS054P001C01  I102

UPI_CPU0_CPU1_P2P2_DN<14>   @S9S_MB_2U_LIB.S9S_MB_2U(SCH_1):UPI_CPU0_CPU1_P2P2_DN<14>
  U1     AY75  UPI2_RX_DN14  SOCKET4677_AZIFS054P001C01  I16
  U2     Y81  UPI2_TX_DN9  SOCKET4677_AZIFS054P001C01  I102

UPI_CPU0_CPU1_P2P2_DN<15>   @S9S_MB_2U_LIB.S9S_MB_2U(SCH_1):UPI_CPU0_CPU1_P2P2_DN<15>
  U1     BB75  UPI2_RX_DN15  SOCKET4677_AZIFS054P001C01  I16
  U2     V83  UPI2_TX_DN8  SOCKET4677_AZIFS054P001C01  I102

UPI_CPU0_CPU1_P2P2_DN<16>   @S9S_MB_2U_LIB.S9S_MB_2U(SCH_1):UPI_CPU0_CPU1_P2P2_DN<16>
  U1     AW74  UPI2_RX_DN16  SOCKET4677_AZIFS054P001C01  I16
  U2     U80  UPI2_TX_DN7  SOCKET4677_AZIFS054P001C01  I102

UPI_CPU0_CPU1_P2P2_DN<17>   @S9S_MB_2U_LIB.S9S_MB_2U(SCH_1):UPI_CPU0_CPU1_P2P2_DN<17>
  U1     BH75  UPI2_RX_DN17  SOCKET4677_AZIFS054P001C01  I16
  U2     R82  UPI2_TX_DN6  SOCKET4677_AZIFS054P001C01  I102

UPI_CPU0_CPU1_P2P2_DN<18>   @S9S_MB_2U_LIB.S9S_MB_2U(SCH_1):UPI_CPU0_CPU1_P2P2_DN<18>
  U1     BJ76  UPI2_RX_DN18  SOCKET4677_AZIFS054P001C01  I16
  U2     P81  UPI2_TX_DN5  SOCKET4677_AZIFS054P001C01  I102

UPI_CPU0_CPU1_P2P2_DN<19>   @S9S_MB_2U_LIB.S9S_MB_2U(SCH_1):UPI_CPU0_CPU1_P2P2_DN<19>
  U1     BL76  UPI2_RX_DN19  SOCKET4677_AZIFS054P001C01  I16
  U2     H85  UPI2_TX_DN4  SOCKET4677_AZIFS054P001C01  I102

UPI_CPU0_CPU1_P2P2_DN<20>   @S9S_MB_2U_LIB.S9S_MB_2U(SCH_1):UPI_CPU0_CPU1_P2P2_DN<20>
  U1     BG74  UPI2_RX_DN20  SOCKET4677_AZIFS054P001C01  I16
  U2     F87  UPI2_TX_DN3  SOCKET4677_AZIFS054P001C01  I102

UPI_CPU0_CPU1_P2P2_DN<21>   @S9S_MB_2U_LIB.S9S_MB_2U(SCH_1):UPI_CPU0_CPU1_P2P2_DN<21>
  U1     BN74  UPI2_RX_DN21  SOCKET4677_AZIFS054P001C01  I16
  U2     D87  UPI2_TX_DN2  SOCKET4677_AZIFS054P001C01  I102

UPI_CPU0_CPU1_P2P2_DN<22>   @S9S_MB_2U_LIB.S9S_MB_2U(SCH_1):UPI_CPU0_CPU1_P2P2_DN<22>
  U1     BK73  UPI2_RX_DN22  SOCKET4677_AZIFS054P001C01  I16
  U2     E84  UPI2_TX_DN1  SOCKET4677_AZIFS054P001C01  I102

UPI_CPU0_CPU1_P2P2_DN<23>   @S9S_MB_2U_LIB.S9S_MB_2U(SCH_1):UPI_CPU0_CPU1_P2P2_DN<23>
  U1     BD73  UPI2_RX_DN23  SOCKET4677_AZIFS054P001C01  I16
  U2     B85  UPI2_TX_DN0  SOCKET4677_AZIFS054P001C01  I102

UPI_CPU0_CPU1_P2P2_DP<0>   @S9S_MB_2U_LIB.S9S_MB_2U(SCH_1):UPI_CPU0_CPU1_P2P2_DP<0>
  U1     G80  UPI2_RX_DP0  SOCKET4677_AZIFS054P001C01  I16
  U2     BN72  UPI2_TX_DP23  SOCKET4677_AZIFS054P001C01  I102

UPI_CPU0_CPU1_P2P2_DP<1>   @S9S_MB_2U_LIB.S9S_MB_2U(SCH_1):UPI_CPU0_CPU1_P2P2_DP<1>
  U1     E82  UPI2_RX_DP1  SOCKET4677_AZIFS054P001C01  I16
  U2     BE80  UPI2_TX_DP22  SOCKET4677_AZIFS054P001C01  I102

UPI_CPU0_CPU1_P2P2_DP<2>   @S9S_MB_2U_LIB.S9S_MB_2U(SCH_1):UPI_CPU0_CPU1_P2P2_DP<2>
  U1     H83  UPI2_RX_DP2  SOCKET4677_AZIFS054P001C01  I16
  U2     BG82  UPI2_TX_DP21  SOCKET4677_AZIFS054P001C01  I102

UPI_CPU0_CPU1_P2P2_DP<3>   @S9S_MB_2U_LIB.S9S_MB_2U(SCH_1):UPI_CPU0_CPU1_P2P2_DP<3>
  U1     M79  UPI2_RX_DP3  SOCKET4677_AZIFS054P001C01  I16
  U2     BC80  UPI2_TX_DP20  SOCKET4677_AZIFS054P001C01  I102

UPI_CPU0_CPU1_P2P2_DP<4>   @S9S_MB_2U_LIB.S9S_MB_2U(SCH_1):UPI_CPU0_CPU1_P2P2_DP<4>
  U1     L82  UPI2_RX_DP4  SOCKET4677_AZIFS054P001C01  I16
  U2     BD83  UPI2_TX_DP19  SOCKET4677_AZIFS054P001C01  I102

UPI_CPU0_CPU1_P2P2_DP<5>   @S9S_MB_2U_LIB.S9S_MB_2U(SCH_1):UPI_CPU0_CPU1_P2P2_DP<5>
  U1     K81  UPI2_RX_DP5  SOCKET4677_AZIFS054P001C01  I16
  U2     BA82  UPI2_TX_DP18  SOCKET4677_AZIFS054P001C01  I102

UPI_CPU0_CPU1_P2P2_DP<6>   @S9S_MB_2U_LIB.S9S_MB_2U(SCH_1):UPI_CPU0_CPU1_P2P2_DP<6>
  U1     AE80  UPI2_RX_DP6  SOCKET4677_AZIFS054P001C01  I16
  U2     BB81  UPI2_TX_DP17  SOCKET4677_AZIFS054P001C01  I102

UPI_CPU0_CPU1_P2P2_DP<7>   @S9S_MB_2U_LIB.S9S_MB_2U(SCH_1):UPI_CPU0_CPU1_P2P2_DP<7>
  U1     AC82  UPI2_RX_DP7  SOCKET4677_AZIFS054P001C01  I16
  U2     AU82  UPI2_TX_DP16  SOCKET4677_AZIFS054P001C01  I102

UPI_CPU0_CPU1_P2P2_DP<8>   @S9S_MB_2U_LIB.S9S_MB_2U(SCH_1):UPI_CPU0_CPU1_P2P2_DP<8>
  U1     AG80  UPI2_RX_DP8  SOCKET4677_AZIFS054P001C01  I16
  U2     AV83  UPI2_TX_DP15  SOCKET4677_AZIFS054P001C01  I102

UPI_CPU0_CPU1_P2P2_DP<9>   @S9S_MB_2U_LIB.S9S_MB_2U(SCH_1):UPI_CPU0_CPU1_P2P2_DP<9>
  U1     AF83  UPI2_RX_DP9  SOCKET4677_AZIFS054P001C01  I16
  U2     AT81  UPI2_TX_DP14  SOCKET4677_AZIFS054P001C01  I102

UPI_CPU0_CPU1_P2P2_DP<10>   @S9S_MB_2U_LIB.S9S_MB_2U(SCH_1):UPI_CPU0_CPU1_P2P2_DP<10>
  U1     AH81  UPI2_RX_DP10  SOCKET4677_AZIFS054P001C01  I16
  U2     AM83  UPI2_TX_DP13  SOCKET4677_AZIFS054P001C01  I102

UPI_CPU0_CPU1_P2P2_DP<11>   @S9S_MB_2U_LIB.S9S_MB_2U(SCH_1):UPI_CPU0_CPU1_P2P2_DP<11>
  U1     AJ82  UPI2_RX_DP11  SOCKET4677_AZIFS054P001C01  I16
  U2     AP81  UPI2_TX_DP12  SOCKET4677_AZIFS054P001C01  I102

UPI_CPU0_CPU1_P2P2_DP<12>   @S9S_MB_2U_LIB.S9S_MB_2U(SCH_1):UPI_CPU0_CPU1_P2P2_DP<12>
  U1     BB73  UPI2_RX_DP12  SOCKET4677_AZIFS054P001C01  I16
  U2     AV79  UPI2_TX_DP11  SOCKET4677_AZIFS054P001C01  I102

UPI_CPU0_CPU1_P2P2_DP<13>   @S9S_MB_2U_LIB.S9S_MB_2U(SCH_1):UPI_CPU0_CPU1_P2P2_DP<13>
  U1     AY73  UPI2_RX_DP13  SOCKET4677_AZIFS054P001C01  I16
  U2     BA78  UPI2_TX_DP10  SOCKET4677_AZIFS054P001C01  I102

UPI_CPU0_CPU1_P2P2_DP<14>   @S9S_MB_2U_LIB.S9S_MB_2U(SCH_1):UPI_CPU0_CPU1_P2P2_DP<14>
  U1     BA76  UPI2_RX_DP14  SOCKET4677_AZIFS054P001C01  I16
  U2     W82  UPI2_TX_DP9  SOCKET4677_AZIFS054P001C01  I102

UPI_CPU0_CPU1_P2P2_DP<15>   @S9S_MB_2U_LIB.S9S_MB_2U(SCH_1):UPI_CPU0_CPU1_P2P2_DP<15>
  U1     BD75  UPI2_RX_DP15  SOCKET4677_AZIFS054P001C01  I16
  U2     Y83  UPI2_TX_DP8  SOCKET4677_AZIFS054P001C01  I102

UPI_CPU0_CPU1_P2P2_DP<16>   @S9S_MB_2U_LIB.S9S_MB_2U(SCH_1):UPI_CPU0_CPU1_P2P2_DP<16>
  U1     AV75  UPI2_RX_DP16  SOCKET4677_AZIFS054P001C01  I16
  U2     V81  UPI2_TX_DP7  SOCKET4677_AZIFS054P001C01  I102

UPI_CPU0_CPU1_P2P2_DP<17>   @S9S_MB_2U_LIB.S9S_MB_2U(SCH_1):UPI_CPU0_CPU1_P2P2_DP<17>
  U1     BG76  UPI2_RX_DP17  SOCKET4677_AZIFS054P001C01  I16
  U2     P83  UPI2_TX_DP6  SOCKET4677_AZIFS054P001C01  I102

UPI_CPU0_CPU1_P2P2_DP<18>   @S9S_MB_2U_LIB.S9S_MB_2U(SCH_1):UPI_CPU0_CPU1_P2P2_DP<18>
  U1     BK77  UPI2_RX_DP18  SOCKET4677_AZIFS054P001C01  I16
  U2     T81  UPI2_TX_DP5  SOCKET4677_AZIFS054P001C01  I102

UPI_CPU0_CPU1_P2P2_DP<19>   @S9S_MB_2U_LIB.S9S_MB_2U(SCH_1):UPI_CPU0_CPU1_P2P2_DP<19>
  U1     BN76  UPI2_RX_DP19  SOCKET4677_AZIFS054P001C01  I16
  U2     G86  UPI2_TX_DP4  SOCKET4677_AZIFS054P001C01  I102

UPI_CPU0_CPU1_P2P2_DP<20>   @S9S_MB_2U_LIB.S9S_MB_2U(SCH_1):UPI_CPU0_CPU1_P2P2_DP<20>
  U1     BJ74  UPI2_RX_DP20  SOCKET4677_AZIFS054P001C01  I16
  U2     H87  UPI2_TX_DP3  SOCKET4677_AZIFS054P001C01  I102

UPI_CPU0_CPU1_P2P2_DP<21>   @S9S_MB_2U_LIB.S9S_MB_2U(SCH_1):UPI_CPU0_CPU1_P2P2_DP<21>
  U1     BM75  UPI2_RX_DP21  SOCKET4677_AZIFS054P001C01  I16
  U2     E88  UPI2_TX_DP2  SOCKET4677_AZIFS054P001C01  I102

UPI_CPU0_CPU1_P2P2_DP<22>   @S9S_MB_2U_LIB.S9S_MB_2U(SCH_1):UPI_CPU0_CPU1_P2P2_DP<22>
  U1     BL74  UPI2_RX_DP22  SOCKET4677_AZIFS054P001C01  I16
  U2     F85  UPI2_TX_DP1  SOCKET4677_AZIFS054P001C01  I102

UPI_CPU0_CPU1_P2P2_DP<23>   @S9S_MB_2U_LIB.S9S_MB_2U(SCH_1):UPI_CPU0_CPU1_P2P2_DP<23>
  U1     BC74  UPI2_RX_DP23  SOCKET4677_AZIFS054P001C01  I16
  U2     D85  UPI2_TX_DP0  SOCKET4677_AZIFS054P001C01  I102

UPI_CPU0_CPU1_P3P3_DN<0>   @S9S_MB_2U_LIB.S9S_MB_2U(SCH_1):UPI_CPU0_CPU1_P3P3_DN<0>
  U1     EJ80  UPI3_RX_DN0  SOCKET4677_AZIFS054P001C01  I16
  U2     CD73  UPI3_TX_DP23  SOCKET4677_AZIFS054P001C01  I102

UPI_CPU0_CPU1_P3P3_DN<1>   @S9S_MB_2U_LIB.S9S_MB_2U(SCH_1):UPI_CPU0_CPU1_P3P3_DN<1>
  U1     EP81  UPI3_RX_DN1  SOCKET4677_AZIFS054P001C01  I16
  U2     CW74  UPI3_TX_DP22  SOCKET4677_AZIFS054P001C01  I102

UPI_CPU0_CPU1_P3P3_DN<2>   @S9S_MB_2U_LIB.S9S_MB_2U(SCH_1):UPI_CPU0_CPU1_P3P3_DN<2>
  U1     EL82  UPI3_RX_DN2  SOCKET4677_AZIFS054P001C01  I16
  U2     CK75  UPI3_TX_DP21  SOCKET4677_AZIFS054P001C01  I102

UPI_CPU0_CPU1_P3P3_DN<3>   @S9S_MB_2U_LIB.S9S_MB_2U(SCH_1):UPI_CPU0_CPU1_P3P3_DN<3>
  U1     EK81  UPI3_RX_DN3  SOCKET4677_AZIFS054P001C01  I16
  U2     CH75  UPI3_TX_DP20  SOCKET4677_AZIFS054P001C01  I102

UPI_CPU0_CPU1_P3P3_DN<4>   @S9S_MB_2U_LIB.S9S_MB_2U(SCH_1):UPI_CPU0_CPU1_P3P3_DN<4>
  U1     EF81  UPI3_RX_DN4  SOCKET4677_AZIFS054P001C01  I16
  U2     CG76  UPI3_TX_DN19  SOCKET4677_AZIFS054P001C01  I102

UPI_CPU0_CPU1_P3P3_DN<5>   @S9S_MB_2U_LIB.S9S_MB_2U(SCH_1):UPI_CPU0_CPU1_P3P3_DN<5>
  U1     ED83  UPI3_RX_DN5  SOCKET4677_AZIFS054P001C01  I16
  U2     CL76  UPI3_TX_DP18  SOCKET4677_AZIFS054P001C01  I102

UPI_CPU0_CPU1_P3P3_DN<6>   @S9S_MB_2U_LIB.S9S_MB_2U(SCH_1):UPI_CPU0_CPU1_P3P3_DN<6>
  U1     EC80  UPI3_RX_DN6  SOCKET4677_AZIFS054P001C01  I16
  U2     CH77  UPI3_TX_DN17  SOCKET4677_AZIFS054P001C01  I102

UPI_CPU0_CPU1_P3P3_DN<7>   @S9S_MB_2U_LIB.S9S_MB_2U(SCH_1):UPI_CPU0_CPU1_P3P3_DN<7>
  U1     EA82  UPI3_RX_DN7  SOCKET4677_AZIFS054P001C01  I16
  U2     CM77  UPI3_TX_DP16  SOCKET4677_AZIFS054P001C01  I102

UPI_CPU0_CPU1_P3P3_DN<8>   @S9S_MB_2U_LIB.S9S_MB_2U(SCH_1):UPI_CPU0_CPU1_P3P3_DN<8>
  U1     DY81  UPI3_RX_DN8  SOCKET4677_AZIFS054P001C01  I16
  U2     CU74  UPI3_TX_DP15  SOCKET4677_AZIFS054P001C01  I102

UPI_CPU0_CPU1_P3P3_DN<9>   @S9S_MB_2U_LIB.S9S_MB_2U(SCH_1):UPI_CPU0_CPU1_P3P3_DN<9>
  U1     DJ78  UPI3_RX_DN9  SOCKET4677_AZIFS054P001C01  I16
  U2     CT75  UPI3_TX_DN14  SOCKET4677_AZIFS054P001C01  I102

UPI_CPU0_CPU1_P3P3_DN<10>   @S9S_MB_2U_LIB.S9S_MB_2U(SCH_1):UPI_CPU0_CPU1_P3P3_DN<10>
  U1     DG78  UPI3_RX_DN10  SOCKET4677_AZIFS054P001C01  I16
  U2     CU76  UPI3_TX_DN13  SOCKET4677_AZIFS054P001C01  I102

UPI_CPU0_CPU1_P3P3_DN<11>   @S9S_MB_2U_LIB.S9S_MB_2U(SCH_1):UPI_CPU0_CPU1_P3P3_DN<11>
  U1     DH81  UPI3_RX_DN11  SOCKET4677_AZIFS054P001C01  I16
  U2     CW76  UPI3_TX_DN12  SOCKET4677_AZIFS054P001C01  I102

UPI_CPU0_CPU1_P3P3_DN<12>   @S9S_MB_2U_LIB.S9S_MB_2U(SCH_1):UPI_CPU0_CPU1_P3P3_DN<12>
  U1     DF83  UPI3_RX_DN12  SOCKET4677_AZIFS054P001C01  I16
  U2     DN80  UPI3_TX_DP11  SOCKET4677_AZIFS054P001C01  I102

UPI_CPU0_CPU1_P3P3_DN<13>   @S9S_MB_2U_LIB.S9S_MB_2U(SCH_1):UPI_CPU0_CPU1_P3P3_DN<13>
  U1     DE80  UPI3_RX_DN13  SOCKET4677_AZIFS054P001C01  I16
  U2     DM81  UPI3_TX_DN10  SOCKET4677_AZIFS054P001C01  I102

UPI_CPU0_CPU1_P3P3_DN<14>   @S9S_MB_2U_LIB.S9S_MB_2U(SCH_1):UPI_CPU0_CPU1_P3P3_DN<14>
  U1     DC82  UPI3_RX_DN14  SOCKET4677_AZIFS054P001C01  I16
  U2     DN82  UPI3_TX_DN9  SOCKET4677_AZIFS054P001C01  I102

UPI_CPU0_CPU1_P3P3_DN<15>   @S9S_MB_2U_LIB.S9S_MB_2U(SCH_1):UPI_CPU0_CPU1_P3P3_DN<15>
  U1     DB81  UPI3_RX_DN15  SOCKET4677_AZIFS054P001C01  I16
  U2     DR80  UPI3_TX_DP8  SOCKET4677_AZIFS054P001C01  I102

UPI_CPU0_CPU1_P3P3_DN<16>   @S9S_MB_2U_LIB.S9S_MB_2U(SCH_1):UPI_CPU0_CPU1_P3P3_DN<16>
  U1     DF77  UPI3_RX_DN16  SOCKET4677_AZIFS054P001C01  I16
  U2     DU82  UPI3_TX_DP7  SOCKET4677_AZIFS054P001C01  I102

UPI_CPU0_CPU1_P3P3_DN<17>   @S9S_MB_2U_LIB.S9S_MB_2U(SCH_1):UPI_CPU0_CPU1_P3P3_DN<17>
  U1     CU82  UPI3_RX_DN17  SOCKET4677_AZIFS054P001C01  I16
  U2     DU80  UPI3_TX_DN6  SOCKET4677_AZIFS054P001C01  I102

UPI_CPU0_CPU1_P3P3_DN<18>   @S9S_MB_2U_LIB.S9S_MB_2U(SCH_1):UPI_CPU0_CPU1_P3P3_DN<18>
  U1     CR82  UPI3_RX_DN18  SOCKET4677_AZIFS054P001C01  I16
  U2     EL88  UPI3_TX_DP5  SOCKET4677_AZIFS054P001C01  I102

UPI_CPU0_CPU1_P3P3_DN<19>   @S9S_MB_2U_LIB.S9S_MB_2U(SCH_1):UPI_CPU0_CPU1_P3P3_DN<19>
  U1     CW80  UPI3_RX_DN19  SOCKET4677_AZIFS054P001C01  I16
  U2     EJ86  UPI3_TX_DN4  SOCKET4677_AZIFS054P001C01  I102

UPI_CPU0_CPU1_P3P3_DN<20>   @S9S_MB_2U_LIB.S9S_MB_2U(SCH_1):UPI_CPU0_CPU1_P3P3_DN<20>
  U1     CP81  UPI3_RX_DN20  SOCKET4677_AZIFS054P001C01  I16
  U2     EP87  UPI3_TX_DP3  SOCKET4677_AZIFS054P001C01  I102

UPI_CPU0_CPU1_P3P3_DN<21>   @S9S_MB_2U_LIB.S9S_MB_2U(SCH_1):UPI_CPU0_CPU1_P3P3_DN<21>
  U1     CN80  UPI3_RX_DN21  SOCKET4677_AZIFS054P001C01  I16
  U2     EP85  UPI3_TX_DN2  SOCKET4677_AZIFS054P001C01  I102

UPI_CPU0_CPU1_P3P3_DN<22>   @S9S_MB_2U_LIB.S9S_MB_2U(SCH_1):UPI_CPU0_CPU1_P3P3_DN<22>
  U1     CT79  UPI3_RX_DN22  SOCKET4677_AZIFS054P001C01  I16
  U2     EL84  UPI3_TX_DN1  SOCKET4677_AZIFS054P001C01  I102

UPI_CPU0_CPU1_P3P3_DN<23>   @S9S_MB_2U_LIB.S9S_MB_2U(SCH_1):UPI_CPU0_CPU1_P3P3_DN<23>
  U1     DA78  UPI3_RX_DN23  SOCKET4677_AZIFS054P001C01  I16
  U2     EH85  UPI3_TX_DN0  SOCKET4677_AZIFS054P001C01  I102

UPI_CPU0_CPU1_P3P3_DP<0>   @S9S_MB_2U_LIB.S9S_MB_2U(SCH_1):UPI_CPU0_CPU1_P3P3_DP<0>
  U1     EL80  UPI3_RX_DP0  SOCKET4677_AZIFS054P001C01  I16
  U2     CF73  UPI3_TX_DN23  SOCKET4677_AZIFS054P001C01  I102

UPI_CPU0_CPU1_P3P3_DP<1>   @S9S_MB_2U_LIB.S9S_MB_2U(SCH_1):UPI_CPU0_CPU1_P3P3_DP<1>
  U1     ER82  UPI3_RX_DP1  SOCKET4677_AZIFS054P001C01  I16
  U2     CV73  UPI3_TX_DN22  SOCKET4677_AZIFS054P001C01  I102

UPI_CPU0_CPU1_P3P3_DP<2>   @S9S_MB_2U_LIB.S9S_MB_2U(SCH_1):UPI_CPU0_CPU1_P3P3_DP<2>
  U1     EN82  UPI3_RX_DP2  SOCKET4677_AZIFS054P001C01  I16
  U2     CJ74  UPI3_TX_DN21  SOCKET4677_AZIFS054P001C01  I102

UPI_CPU0_CPU1_P3P3_DP<3>   @S9S_MB_2U_LIB.S9S_MB_2U(SCH_1):UPI_CPU0_CPU1_P3P3_DP<3>
  U1     EJ82  UPI3_RX_DP3  SOCKET4677_AZIFS054P001C01  I16
  U2     CF75  UPI3_TX_DN20  SOCKET4677_AZIFS054P001C01  I102

UPI_CPU0_CPU1_P3P3_DP<4>   @S9S_MB_2U_LIB.S9S_MB_2U(SCH_1):UPI_CPU0_CPU1_P3P3_DP<4>
  U1     EE82  UPI3_RX_DP4  SOCKET4677_AZIFS054P001C01  I16
  U2     CF77  UPI3_TX_DP19  SOCKET4677_AZIFS054P001C01  I102

UPI_CPU0_CPU1_P3P3_DP<5>   @S9S_MB_2U_LIB.S9S_MB_2U(SCH_1):UPI_CPU0_CPU1_P3P3_DP<5>
  U1     EF83  UPI3_RX_DP5  SOCKET4677_AZIFS054P001C01  I16
  U2     CM75  UPI3_TX_DN18  SOCKET4677_AZIFS054P001C01  I102

UPI_CPU0_CPU1_P3P3_DP<6>   @S9S_MB_2U_LIB.S9S_MB_2U(SCH_1):UPI_CPU0_CPU1_P3P3_DP<6>
  U1     ED81  UPI3_RX_DP6  SOCKET4677_AZIFS054P001C01  I16
  U2     CJ78  UPI3_TX_DP17  SOCKET4677_AZIFS054P001C01  I102

UPI_CPU0_CPU1_P3P3_DP<7>   @S9S_MB_2U_LIB.S9S_MB_2U(SCH_1):UPI_CPU0_CPU1_P3P3_DP<7>
  U1     DY83  UPI3_RX_DP7  SOCKET4677_AZIFS054P001C01  I16
  U2     CK77  UPI3_TX_DN16  SOCKET4677_AZIFS054P001C01  I102

UPI_CPU0_CPU1_P3P3_DP<8>   @S9S_MB_2U_LIB.S9S_MB_2U(SCH_1):UPI_CPU0_CPU1_P3P3_DP<8>
  U1     EB81  UPI3_RX_DP8  SOCKET4677_AZIFS054P001C01  I16
  U2     CR74  UPI3_TX_DN15  SOCKET4677_AZIFS054P001C01  I102

UPI_CPU0_CPU1_P3P3_DP<9>   @S9S_MB_2U_LIB.S9S_MB_2U(SCH_1):UPI_CPU0_CPU1_P3P3_DP<9>
  U1     DL78  UPI3_RX_DP9  SOCKET4677_AZIFS054P001C01  I16
  U2     CR76  UPI3_TX_DP14  SOCKET4677_AZIFS054P001C01  I102

UPI_CPU0_CPU1_P3P3_DP<10>   @S9S_MB_2U_LIB.S9S_MB_2U(SCH_1):UPI_CPU0_CPU1_P3P3_DP<10>
  U1     DH79  UPI3_RX_DP10  SOCKET4677_AZIFS054P001C01  I16
  U2     CV77  UPI3_TX_DP13  SOCKET4677_AZIFS054P001C01  I102

UPI_CPU0_CPU1_P3P3_DP<11>   @S9S_MB_2U_LIB.S9S_MB_2U(SCH_1):UPI_CPU0_CPU1_P3P3_DP<11>
  U1     DG82  UPI3_RX_DP11  SOCKET4677_AZIFS054P001C01  I16
  U2     DA76  UPI3_TX_DP12  SOCKET4677_AZIFS054P001C01  I102

UPI_CPU0_CPU1_P3P3_DP<12>   @S9S_MB_2U_LIB.S9S_MB_2U(SCH_1):UPI_CPU0_CPU1_P3P3_DP<12>
  U1     DH83  UPI3_RX_DP12  SOCKET4677_AZIFS054P001C01  I16
  U2     DL80  UPI3_TX_DN11  SOCKET4677_AZIFS054P001C01  I102

UPI_CPU0_CPU1_P3P3_DP<13>   @S9S_MB_2U_LIB.S9S_MB_2U(SCH_1):UPI_CPU0_CPU1_P3P3_DP<13>
  U1     DF81  UPI3_RX_DP13  SOCKET4677_AZIFS054P001C01  I16
  U2     DL82  UPI3_TX_DP10  SOCKET4677_AZIFS054P001C01  I102

UPI_CPU0_CPU1_P3P3_DP<14>   @S9S_MB_2U_LIB.S9S_MB_2U(SCH_1):UPI_CPU0_CPU1_P3P3_DP<14>
  U1     DB83  UPI3_RX_DP14  SOCKET4677_AZIFS054P001C01  I16
  U2     DP83  UPI3_TX_DP9  SOCKET4677_AZIFS054P001C01  I102

UPI_CPU0_CPU1_P3P3_DP<15>   @S9S_MB_2U_LIB.S9S_MB_2U(SCH_1):UPI_CPU0_CPU1_P3P3_DP<15>
  U1     DD81  UPI3_RX_DP15  SOCKET4677_AZIFS054P001C01  I16
  U2     DP79  UPI3_TX_DN8  SOCKET4677_AZIFS054P001C01  I102

UPI_CPU0_CPU1_P3P3_DP<16>   @S9S_MB_2U_LIB.S9S_MB_2U(SCH_1):UPI_CPU0_CPU1_P3P3_DP<16>
  U1     DE78  UPI3_RX_DP16  SOCKET4677_AZIFS054P001C01  I16
  U2     DR82  UPI3_TX_DN7  SOCKET4677_AZIFS054P001C01  I102

UPI_CPU0_CPU1_P3P3_DP<17>   @S9S_MB_2U_LIB.S9S_MB_2U(SCH_1):UPI_CPU0_CPU1_P3P3_DP<17>
  U1     CW82  UPI3_RX_DP17  SOCKET4677_AZIFS054P001C01  I16
  U2     DT81  UPI3_TX_DP6  SOCKET4677_AZIFS054P001C01  I102

UPI_CPU0_CPU1_P3P3_DP<18>   @S9S_MB_2U_LIB.S9S_MB_2U(SCH_1):UPI_CPU0_CPU1_P3P3_DP<18>
  U1     CT83  UPI3_RX_DP18  SOCKET4677_AZIFS054P001C01  I16
  U2     EK87  UPI3_TX_DN5  SOCKET4677_AZIFS054P001C01  I102

UPI_CPU0_CPU1_P3P3_DP<19>   @S9S_MB_2U_LIB.S9S_MB_2U(SCH_1):UPI_CPU0_CPU1_P3P3_DP<19>
  U1     CV81  UPI3_RX_DP19  SOCKET4677_AZIFS054P001C01  I16
  U2     EH87  UPI3_TX_DP4  SOCKET4677_AZIFS054P001C01  I102

UPI_CPU0_CPU1_P3P3_DP<20>   @S9S_MB_2U_LIB.S9S_MB_2U(SCH_1):UPI_CPU0_CPU1_P3P3_DP<20>
  U1     CN82  UPI3_RX_DP20  SOCKET4677_AZIFS054P001C01  I16
  U2     EM87  UPI3_TX_DN3  SOCKET4677_AZIFS054P001C01  I102

UPI_CPU0_CPU1_P3P3_DP<21>   @S9S_MB_2U_LIB.S9S_MB_2U(SCH_1):UPI_CPU0_CPU1_P3P3_DP<21>
  U1     CR80  UPI3_RX_DP21  SOCKET4677_AZIFS054P001C01  I16
  U2     EN86  UPI3_TX_DP2  SOCKET4677_AZIFS054P001C01  I102

UPI_CPU0_CPU1_P3P3_DP<22>   @S9S_MB_2U_LIB.S9S_MB_2U(SCH_1):UPI_CPU0_CPU1_P3P3_DP<22>
  U1     CU80  UPI3_RX_DP22  SOCKET4677_AZIFS054P001C01  I16
  U2     EM85  UPI3_TX_DP1  SOCKET4677_AZIFS054P001C01  I102

UPI_CPU0_CPU1_P3P3_DP<23>   @S9S_MB_2U_LIB.S9S_MB_2U(SCH_1):UPI_CPU0_CPU1_P3P3_DP<23>
  U1     DB79  UPI3_RX_DP23  SOCKET4677_AZIFS054P001C01  I16
  U2     EK85  UPI3_TX_DP0  SOCKET4677_AZIFS054P001C01  I102

UPI_CPU1_CPU0_P0P1_DN<0>   @S9S_MB_2U_LIB.S9S_MB_2U(SCH_1):UPI_CPU1_CPU0_P0P1_DN<0>
  U1      K4  UPI0_TX_DN0  SOCKET4677_AZIFS054P001C01  I51
  U2     EH2  UPI1_RX_DN0  SOCKET4677_AZIFS054P001C01  I102

UPI_CPU1_CPU0_P0P1_DN<1>   @S9S_MB_2U_LIB.S9S_MB_2U(SCH_1):UPI_CPU1_CPU0_P0P1_DN<1>
  U1      M2  UPI0_TX_DN1  SOCKET4677_AZIFS054P001C01  I51
  U2     EE3  UPI1_RX_DN1  SOCKET4677_AZIFS054P001C01  I102

UPI_CPU1_CPU0_P0P1_DN<2>   @S9S_MB_2U_LIB.S9S_MB_2U(SCH_1):UPI_CPU1_CPU0_P0P1_DN<2>
  U1      N1  UPI0_TX_DN2  SOCKET4677_AZIFS054P001C01  I51
  U2     EC3  UPI1_RX_DP2  SOCKET4677_AZIFS054P001C01  I102

UPI_CPU1_CPU0_P0P1_DN<3>   @S9S_MB_2U_LIB.S9S_MB_2U(SCH_1):UPI_CPU1_CPU0_P0P1_DN<3>
  U1      T2  UPI0_TX_DN3  SOCKET4677_AZIFS054P001C01  I51
  U2     EA1  UPI1_RX_DN3  SOCKET4677_AZIFS054P001C01  I102

UPI_CPU1_CPU0_P0P1_DN<4>   @S9S_MB_2U_LIB.S9S_MB_2U(SCH_1):UPI_CPU1_CPU0_P0P1_DN<4>
  U1      U1  UPI0_TX_DN4  SOCKET4677_AZIFS054P001C01  I51
  U2     DY2  UPI1_RX_DN4  SOCKET4677_AZIFS054P001C01  I102

UPI_CPU1_CPU0_P0P1_DN<5>   @S9S_MB_2U_LIB.S9S_MB_2U(SCH_1):UPI_CPU1_CPU0_P0P1_DN<5>
  U1      Y2  UPI0_TX_DN5  SOCKET4677_AZIFS054P001C01  I51
  U2     DU1  UPI1_RX_DN5  SOCKET4677_AZIFS054P001C01  I102

UPI_CPU1_CPU0_P0P1_DN<6>   @S9S_MB_2U_LIB.S9S_MB_2U(SCH_1):UPI_CPU1_CPU0_P0P1_DN<6>
  U1     AA1  UPI0_TX_DN6  SOCKET4677_AZIFS054P001C01  I51
  U2     DT2  UPI1_RX_DN6  SOCKET4677_AZIFS054P001C01  I102

UPI_CPU1_CPU0_P0P1_DN<7>   @S9S_MB_2U_LIB.S9S_MB_2U(SCH_1):UPI_CPU1_CPU0_P0P1_DN<7>
  U1     AD2  UPI0_TX_DN7  SOCKET4677_AZIFS054P001C01  I51
  U2     DN1  UPI1_RX_DN7  SOCKET4677_AZIFS054P001C01  I102

UPI_CPU1_CPU0_P0P1_DN<8>   @S9S_MB_2U_LIB.S9S_MB_2U(SCH_1):UPI_CPU1_CPU0_P0P1_DN<8>
  U1     AF2  UPI0_TX_DN8  SOCKET4677_AZIFS054P001C01  I51
  U2     DL3  UPI1_RX_DN8  SOCKET4677_AZIFS054P001C01  I102

UPI_CPU1_CPU0_P0P1_DN<9>   @S9S_MB_2U_LIB.S9S_MB_2U(SCH_1):UPI_CPU1_CPU0_P0P1_DN<9>
  U1     AH2  UPI0_TX_DN9  SOCKET4677_AZIFS054P001C01  I51
  U2     DJ1  UPI1_RX_DN9  SOCKET4677_AZIFS054P001C01  I102

UPI_CPU1_CPU0_P0P1_DN<10>   @S9S_MB_2U_LIB.S9S_MB_2U(SCH_1):UPI_CPU1_CPU0_P0P1_DN<10>
  U1     AK2  UPI0_TX_DN10  SOCKET4677_AZIFS054P001C01  I51
  U2     DG3  UPI1_RX_DN10  SOCKET4677_AZIFS054P001C01  I102

UPI_CPU1_CPU0_P0P1_DN<11>   @S9S_MB_2U_LIB.S9S_MB_2U(SCH_1):UPI_CPU1_CPU0_P0P1_DN<11>
  U1     AM2  UPI0_TX_DN11  SOCKET4677_AZIFS054P001C01  I51
  U2     DE1  UPI1_RX_DN11  SOCKET4677_AZIFS054P001C01  I102

UPI_CPU1_CPU0_P0P1_DN<12>   @S9S_MB_2U_LIB.S9S_MB_2U(SCH_1):UPI_CPU1_CPU0_P0P1_DN<12>
  U1     AP2  UPI0_TX_DN12  SOCKET4677_AZIFS054P001C01  I51
  U2     DC3  UPI1_RX_DP12  SOCKET4677_AZIFS054P001C01  I102

UPI_CPU1_CPU0_P0P1_DN<13>   @S9S_MB_2U_LIB.S9S_MB_2U(SCH_1):UPI_CPU1_CPU0_P0P1_DN<13>
  U1     AT2  UPI0_TX_DN13  SOCKET4677_AZIFS054P001C01  I51
  U2     DB2  UPI1_RX_DN13  SOCKET4677_AZIFS054P001C01  I102

UPI_CPU1_CPU0_P0P1_DN<14>   @S9S_MB_2U_LIB.S9S_MB_2U(SCH_1):UPI_CPU1_CPU0_P0P1_DN<14>
  U1     AU1  UPI0_TX_DN14  SOCKET4677_AZIFS054P001C01  I51
  U2     CY2  UPI1_RX_DN14  SOCKET4677_AZIFS054P001C01  I102

UPI_CPU1_CPU0_P0P1_DN<15>   @S9S_MB_2U_LIB.S9S_MB_2U(SCH_1):UPI_CPU1_CPU0_P0P1_DN<15>
  U1     AY2  UPI0_TX_DN15  SOCKET4677_AZIFS054P001C01  I51
  U2     CV2  UPI1_RX_DN15  SOCKET4677_AZIFS054P001C01  I102

UPI_CPU1_CPU0_P0P1_DN<16>   @S9S_MB_2U_LIB.S9S_MB_2U(SCH_1):UPI_CPU1_CPU0_P0P1_DN<16>
  U1     BB2  UPI0_TX_DN16  SOCKET4677_AZIFS054P001C01  I51
  U2     CR3  UPI1_RX_DN16  SOCKET4677_AZIFS054P001C01  I102

UPI_CPU1_CPU0_P0P1_DN<17>   @S9S_MB_2U_LIB.S9S_MB_2U(SCH_1):UPI_CPU1_CPU0_P0P1_DN<17>
  U1     BD2  UPI0_TX_DN17  SOCKET4677_AZIFS054P001C01  I51
  U2     CP2  UPI1_RX_DP17  SOCKET4677_AZIFS054P001C01  I102

UPI_CPU1_CPU0_P0P1_DN<18>   @S9S_MB_2U_LIB.S9S_MB_2U(SCH_1):UPI_CPU1_CPU0_P0P1_DN<18>
  U1     BF2  UPI0_TX_DN18  SOCKET4677_AZIFS054P001C01  I51
  U2     CL3  UPI1_RX_DN18  SOCKET4677_AZIFS054P001C01  I102

UPI_CPU1_CPU0_P0P1_DN<19>   @S9S_MB_2U_LIB.S9S_MB_2U(SCH_1):UPI_CPU1_CPU0_P0P1_DN<19>
  U1     BH2  UPI0_TX_DN19  SOCKET4677_AZIFS054P001C01  I51
  U2     CK2  UPI1_RX_DP19  SOCKET4677_AZIFS054P001C01  I102

UPI_CPU1_CPU0_P0P1_DN<20>   @S9S_MB_2U_LIB.S9S_MB_2U(SCH_1):UPI_CPU1_CPU0_P0P1_DN<20>
  U1     BK2  UPI0_TX_DN20  SOCKET4677_AZIFS054P001C01  I51
  U2     CG3  UPI1_RX_DP20  SOCKET4677_AZIFS054P001C01  I102

UPI_CPU1_CPU0_P0P1_DN<21>   @S9S_MB_2U_LIB.S9S_MB_2U(SCH_1):UPI_CPU1_CPU0_P0P1_DN<21>
  U1     BM2  UPI0_TX_DN21  SOCKET4677_AZIFS054P001C01  I51
  U2     CF2  UPI1_RX_DN21  SOCKET4677_AZIFS054P001C01  I102

UPI_CPU1_CPU0_P0P1_DN<22>   @S9S_MB_2U_LIB.S9S_MB_2U(SCH_1):UPI_CPU1_CPU0_P0P1_DN<22>
  U1     BR3  UPI0_TX_DN22  SOCKET4677_AZIFS054P001C01  I51
  U2     CC3  UPI1_RX_DP22  SOCKET4677_AZIFS054P001C01  I102

UPI_CPU1_CPU0_P0P1_DN<23>   @S9S_MB_2U_LIB.S9S_MB_2U(SCH_1):UPI_CPU1_CPU0_P0P1_DN<23>
  U1     BT2  UPI0_TX_DN23  SOCKET4677_AZIFS054P001C01  I51
  U2     BY2  UPI1_RX_DP23  SOCKET4677_AZIFS054P001C01  I102

UPI_CPU1_CPU0_P0P1_DP<0>   @S9S_MB_2U_LIB.S9S_MB_2U(SCH_1):UPI_CPU1_CPU0_P0P1_DP<0>
  U1      J3  UPI0_TX_DP0  SOCKET4677_AZIFS054P001C01  I51
  U2     EJ3  UPI1_RX_DP0  SOCKET4677_AZIFS054P001C01  I102

UPI_CPU1_CPU0_P0P1_DP<1>   @S9S_MB_2U_LIB.S9S_MB_2U(SCH_1):UPI_CPU1_CPU0_P0P1_DP<1>
  U1      L3  UPI0_TX_DP1  SOCKET4677_AZIFS054P001C01  I51
  U2     EG3  UPI1_RX_DP1  SOCKET4677_AZIFS054P001C01  I102

UPI_CPU1_CPU0_P0P1_DP<2>   @S9S_MB_2U_LIB.S9S_MB_2U(SCH_1):UPI_CPU1_CPU0_P0P1_DP<2>
  U1      P2  UPI0_TX_DP2  SOCKET4677_AZIFS054P001C01  I51
  U2     ED2  UPI1_RX_DN2  SOCKET4677_AZIFS054P001C01  I102

UPI_CPU1_CPU0_P0P1_DP<3>   @S9S_MB_2U_LIB.S9S_MB_2U(SCH_1):UPI_CPU1_CPU0_P0P1_DP<3>
  U1      R3  UPI0_TX_DP3  SOCKET4677_AZIFS054P001C01  I51
  U2     EB2  UPI1_RX_DP3  SOCKET4677_AZIFS054P001C01  I102

UPI_CPU1_CPU0_P0P1_DP<4>   @S9S_MB_2U_LIB.S9S_MB_2U(SCH_1):UPI_CPU1_CPU0_P0P1_DP<4>
  U1      V2  UPI0_TX_DP4  SOCKET4677_AZIFS054P001C01  I51
  U2     DW3  UPI1_RX_DP4  SOCKET4677_AZIFS054P001C01  I102

UPI_CPU1_CPU0_P0P1_DP<5>   @S9S_MB_2U_LIB.S9S_MB_2U(SCH_1):UPI_CPU1_CPU0_P0P1_DP<5>
  U1      W3  UPI0_TX_DP5  SOCKET4677_AZIFS054P001C01  I51
  U2     DV2  UPI1_RX_DP5  SOCKET4677_AZIFS054P001C01  I102

UPI_CPU1_CPU0_P0P1_DP<6>   @S9S_MB_2U_LIB.S9S_MB_2U(SCH_1):UPI_CPU1_CPU0_P0P1_DP<6>
  U1     AB2  UPI0_TX_DP6  SOCKET4677_AZIFS054P001C01  I51
  U2     DR3  UPI1_RX_DP6  SOCKET4677_AZIFS054P001C01  I102

UPI_CPU1_CPU0_P0P1_DP<7>   @S9S_MB_2U_LIB.S9S_MB_2U(SCH_1):UPI_CPU1_CPU0_P0P1_DP<7>
  U1     AC3  UPI0_TX_DP7  SOCKET4677_AZIFS054P001C01  I51
  U2     DP2  UPI1_RX_DP7  SOCKET4677_AZIFS054P001C01  I102

UPI_CPU1_CPU0_P0P1_DP<8>   @S9S_MB_2U_LIB.S9S_MB_2U(SCH_1):UPI_CPU1_CPU0_P0P1_DP<8>
  U1     AE1  UPI0_TX_DP8  SOCKET4677_AZIFS054P001C01  I51
  U2     DM2  UPI1_RX_DP8  SOCKET4677_AZIFS054P001C01  I102

UPI_CPU1_CPU0_P0P1_DP<9>   @S9S_MB_2U_LIB.S9S_MB_2U(SCH_1):UPI_CPU1_CPU0_P0P1_DP<9>
  U1     AG3  UPI0_TX_DP9  SOCKET4677_AZIFS054P001C01  I51
  U2     DK2  UPI1_RX_DP9  SOCKET4677_AZIFS054P001C01  I102

UPI_CPU1_CPU0_P0P1_DP<10>   @S9S_MB_2U_LIB.S9S_MB_2U(SCH_1):UPI_CPU1_CPU0_P0P1_DP<10>
  U1     AJ1  UPI0_TX_DP10  SOCKET4677_AZIFS054P001C01  I51
  U2     DH2  UPI1_RX_DP10  SOCKET4677_AZIFS054P001C01  I102

UPI_CPU1_CPU0_P0P1_DP<11>   @S9S_MB_2U_LIB.S9S_MB_2U(SCH_1):UPI_CPU1_CPU0_P0P1_DP<11>
  U1     AL3  UPI0_TX_DP11  SOCKET4677_AZIFS054P001C01  I51
  U2     DF2  UPI1_RX_DP11  SOCKET4677_AZIFS054P001C01  I102

UPI_CPU1_CPU0_P0P1_DP<12>   @S9S_MB_2U_LIB.S9S_MB_2U(SCH_1):UPI_CPU1_CPU0_P0P1_DP<12>
  U1     AN1  UPI0_TX_DP12  SOCKET4677_AZIFS054P001C01  I51
  U2     DD2  UPI1_RX_DN12  SOCKET4677_AZIFS054P001C01  I102

UPI_CPU1_CPU0_P0P1_DP<13>   @S9S_MB_2U_LIB.S9S_MB_2U(SCH_1):UPI_CPU1_CPU0_P0P1_DP<13>
  U1     AR3  UPI0_TX_DP13  SOCKET4677_AZIFS054P001C01  I51
  U2     DA1  UPI1_RX_DP13  SOCKET4677_AZIFS054P001C01  I102

UPI_CPU1_CPU0_P0P1_DP<14>   @S9S_MB_2U_LIB.S9S_MB_2U(SCH_1):UPI_CPU1_CPU0_P0P1_DP<14>
  U1     AV2  UPI0_TX_DP14  SOCKET4677_AZIFS054P001C01  I51
  U2     CW3  UPI1_RX_DP14  SOCKET4677_AZIFS054P001C01  I102

UPI_CPU1_CPU0_P0P1_DP<15>   @S9S_MB_2U_LIB.S9S_MB_2U(SCH_1):UPI_CPU1_CPU0_P0P1_DP<15>
  U1     AW3  UPI0_TX_DP15  SOCKET4677_AZIFS054P001C01  I51
  U2     CU1  UPI1_RX_DP15  SOCKET4677_AZIFS054P001C01  I102

UPI_CPU1_CPU0_P0P1_DP<16>   @S9S_MB_2U_LIB.S9S_MB_2U(SCH_1):UPI_CPU1_CPU0_P0P1_DP<16>
  U1     BA1  UPI0_TX_DP16  SOCKET4677_AZIFS054P001C01  I51
  U2     CT2  UPI1_RX_DP16  SOCKET4677_AZIFS054P001C01  I102

UPI_CPU1_CPU0_P0P1_DP<17>   @S9S_MB_2U_LIB.S9S_MB_2U(SCH_1):UPI_CPU1_CPU0_P0P1_DP<17>
  U1     BC3  UPI0_TX_DP17  SOCKET4677_AZIFS054P001C01  I51
  U2     CN1  UPI1_RX_DN17  SOCKET4677_AZIFS054P001C01  I102

UPI_CPU1_CPU0_P0P1_DP<18>   @S9S_MB_2U_LIB.S9S_MB_2U(SCH_1):UPI_CPU1_CPU0_P0P1_DP<18>
  U1     BE1  UPI0_TX_DP18  SOCKET4677_AZIFS054P001C01  I51
  U2     CM2  UPI1_RX_DP18  SOCKET4677_AZIFS054P001C01  I102

UPI_CPU1_CPU0_P0P1_DP<19>   @S9S_MB_2U_LIB.S9S_MB_2U(SCH_1):UPI_CPU1_CPU0_P0P1_DP<19>
  U1     BG3  UPI0_TX_DP19  SOCKET4677_AZIFS054P001C01  I51
  U2     CJ1  UPI1_RX_DN19  SOCKET4677_AZIFS054P001C01  I102

UPI_CPU1_CPU0_P0P1_DP<20>   @S9S_MB_2U_LIB.S9S_MB_2U(SCH_1):UPI_CPU1_CPU0_P0P1_DP<20>
  U1     BJ1  UPI0_TX_DP20  SOCKET4677_AZIFS054P001C01  I51
  U2     CH2  UPI1_RX_DN20  SOCKET4677_AZIFS054P001C01  I102

UPI_CPU1_CPU0_P0P1_DP<21>   @S9S_MB_2U_LIB.S9S_MB_2U(SCH_1):UPI_CPU1_CPU0_P0P1_DP<21>
  U1     BL3  UPI0_TX_DP21  SOCKET4677_AZIFS054P001C01  I51
  U2     CE1  UPI1_RX_DP21  SOCKET4677_AZIFS054P001C01  I102

UPI_CPU1_CPU0_P0P1_DP<22>   @S9S_MB_2U_LIB.S9S_MB_2U(SCH_1):UPI_CPU1_CPU0_P0P1_DP<22>
  U1     BN3  UPI0_TX_DP22  SOCKET4677_AZIFS054P001C01  I51
  U2     CD2  UPI1_RX_DN22  SOCKET4677_AZIFS054P001C01  I102

UPI_CPU1_CPU0_P0P1_DP<23>   @S9S_MB_2U_LIB.S9S_MB_2U(SCH_1):UPI_CPU1_CPU0_P0P1_DP<23>
  U1     BU3  UPI0_TX_DP23  SOCKET4677_AZIFS054P001C01  I51
  U2     CB2  UPI1_RX_DN23  SOCKET4677_AZIFS054P001C01  I102

UPI_CPU1_CPU0_P1P0_DN<0>   @S9S_MB_2U_LIB.S9S_MB_2U(SCH_1):UPI_CPU1_CPU0_P1P0_DN<0>
  U1     EF6  UPI1_TX_DN0  SOCKET4677_AZIFS054P001C01  I21
  U2      K6  UPI0_RX_DN0  SOCKET4677_AZIFS054P001C01  I70

UPI_CPU1_CPU0_P1P0_DN<1>   @S9S_MB_2U_LIB.S9S_MB_2U(SCH_1):UPI_CPU1_CPU0_P1P0_DN<1>
  U1     EC7  UPI1_TX_DN1  SOCKET4677_AZIFS054P001C01  I21
  U2      N5  UPI0_RX_DN1  SOCKET4677_AZIFS054P001C01  I70

UPI_CPU1_CPU0_P1P0_DN<2>   @S9S_MB_2U_LIB.S9S_MB_2U(SCH_1):UPI_CPU1_CPU0_P1P0_DN<2>
  U1     EB6  UPI1_TX_DN2  SOCKET4677_AZIFS054P001C01  I21
  U2      P6  UPI0_RX_DN2  SOCKET4677_AZIFS054P001C01  I70

UPI_CPU1_CPU0_P1P0_DN<3>   @S9S_MB_2U_LIB.S9S_MB_2U(SCH_1):UPI_CPU1_CPU0_P1P0_DN<3>
  U1     DY6  UPI1_TX_DN3  SOCKET4677_AZIFS054P001C01  I21
  U2      T6  UPI0_RX_DP3  SOCKET4677_AZIFS054P001C01  I70

UPI_CPU1_CPU0_P1P0_DN<4>   @S9S_MB_2U_LIB.S9S_MB_2U(SCH_1):UPI_CPU1_CPU0_P1P0_DN<4>
  U1     DV6  UPI1_TX_DN4  SOCKET4677_AZIFS054P001C01  I21
  U2      V6  UPI0_RX_DN4  SOCKET4677_AZIFS054P001C01  I70

UPI_CPU1_CPU0_P1P0_DN<5>   @S9S_MB_2U_LIB.S9S_MB_2U(SCH_1):UPI_CPU1_CPU0_P1P0_DN<5>
  U1     DT6  UPI1_TX_DN5  SOCKET4677_AZIFS054P001C01  I21
  U2      Y6  UPI0_RX_DP5  SOCKET4677_AZIFS054P001C01  I70

UPI_CPU1_CPU0_P1P0_DN<6>   @S9S_MB_2U_LIB.S9S_MB_2U(SCH_1):UPI_CPU1_CPU0_P1P0_DN<6>
  U1     DP6  UPI1_TX_DN6  SOCKET4677_AZIFS054P001C01  I21
  U2     AB6  UPI0_RX_DN6  SOCKET4677_AZIFS054P001C01  I70

UPI_CPU1_CPU0_P1P0_DN<7>   @S9S_MB_2U_LIB.S9S_MB_2U(SCH_1):UPI_CPU1_CPU0_P1P0_DN<7>
  U1     DL7  UPI1_TX_DN7  SOCKET4677_AZIFS054P001C01  I21
  U2     AE5  UPI0_RX_DN7  SOCKET4677_AZIFS054P001C01  I70

UPI_CPU1_CPU0_P1P0_DN<8>   @S9S_MB_2U_LIB.S9S_MB_2U(SCH_1):UPI_CPU1_CPU0_P1P0_DN<8>
  U1     DK6  UPI1_TX_DN8  SOCKET4677_AZIFS054P001C01  I21
  U2     AF6  UPI0_RX_DN8  SOCKET4677_AZIFS054P001C01  I70

UPI_CPU1_CPU0_P1P0_DN<9>   @S9S_MB_2U_LIB.S9S_MB_2U(SCH_1):UPI_CPU1_CPU0_P1P0_DN<9>
  U1     DH6  UPI1_TX_DN9  SOCKET4677_AZIFS054P001C01  I21
  U2     AH6  UPI0_RX_DN9  SOCKET4677_AZIFS054P001C01  I70

UPI_CPU1_CPU0_P1P0_DN<10>   @S9S_MB_2U_LIB.S9S_MB_2U(SCH_1):UPI_CPU1_CPU0_P1P0_DN<10>
  U1     DE5  UPI1_TX_DN10  SOCKET4677_AZIFS054P001C01  I21
  U2     AL7  UPI0_RX_DP10  SOCKET4677_AZIFS054P001C01  I70

UPI_CPU1_CPU0_P1P0_DN<11>   @S9S_MB_2U_LIB.S9S_MB_2U(SCH_1):UPI_CPU1_CPU0_P1P0_DN<11>
  U1     DD6  UPI1_TX_DN11  SOCKET4677_AZIFS054P001C01  I21
  U2     AM6  UPI0_RX_DP11  SOCKET4677_AZIFS054P001C01  I70

UPI_CPU1_CPU0_P1P0_DN<12>   @S9S_MB_2U_LIB.S9S_MB_2U(SCH_1):UPI_CPU1_CPU0_P1P0_DN<12>
  U1     DA5  UPI1_TX_DN12  SOCKET4677_AZIFS054P001C01  I21
  U2     AR7  UPI0_RX_DP12  SOCKET4677_AZIFS054P001C01  I70

UPI_CPU1_CPU0_P1P0_DN<13>   @S9S_MB_2U_LIB.S9S_MB_2U(SCH_1):UPI_CPU1_CPU0_P1P0_DN<13>
  U1     CY6  UPI1_TX_DN13  SOCKET4677_AZIFS054P001C01  I21
  U2     AT6  UPI0_RX_DP13  SOCKET4677_AZIFS054P001C01  I70

UPI_CPU1_CPU0_P1P0_DN<14>   @S9S_MB_2U_LIB.S9S_MB_2U(SCH_1):UPI_CPU1_CPU0_P1P0_DN<14>
  U1     CU5  UPI1_TX_DN14  SOCKET4677_AZIFS054P001C01  I21
  U2     AW7  UPI0_RX_DP14  SOCKET4677_AZIFS054P001C01  I70

UPI_CPU1_CPU0_P1P0_DN<15>   @S9S_MB_2U_LIB.S9S_MB_2U(SCH_1):UPI_CPU1_CPU0_P1P0_DN<15>
  U1     CT6  UPI1_TX_DN15  SOCKET4677_AZIFS054P001C01  I21
  U2     AY6  UPI0_RX_DP15  SOCKET4677_AZIFS054P001C01  I70

UPI_CPU1_CPU0_P1P0_DN<16>   @S9S_MB_2U_LIB.S9S_MB_2U(SCH_1):UPI_CPU1_CPU0_P1P0_DN<16>
  U1     CN5  UPI1_TX_DN16  SOCKET4677_AZIFS054P001C01  I21
  U2     BC7  UPI0_RX_DP16  SOCKET4677_AZIFS054P001C01  I70

UPI_CPU1_CPU0_P1P0_DN<17>   @S9S_MB_2U_LIB.S9S_MB_2U(SCH_1):UPI_CPU1_CPU0_P1P0_DN<17>
  U1     CM6  UPI1_TX_DN17  SOCKET4677_AZIFS054P001C01  I21
  U2     BD6  UPI0_RX_DP17  SOCKET4677_AZIFS054P001C01  I70

UPI_CPU1_CPU0_P1P0_DN<18>   @S9S_MB_2U_LIB.S9S_MB_2U(SCH_1):UPI_CPU1_CPU0_P1P0_DN<18>
  U1     CJ5  UPI1_TX_DN18  SOCKET4677_AZIFS054P001C01  I21
  U2     BG7  UPI0_RX_DP18  SOCKET4677_AZIFS054P001C01  I70

UPI_CPU1_CPU0_P1P0_DN<19>   @S9S_MB_2U_LIB.S9S_MB_2U(SCH_1):UPI_CPU1_CPU0_P1P0_DN<19>
  U1     CH6  UPI1_TX_DN19  SOCKET4677_AZIFS054P001C01  I21
  U2     BH6  UPI0_RX_DP19  SOCKET4677_AZIFS054P001C01  I70

UPI_CPU1_CPU0_P1P0_DN<20>   @S9S_MB_2U_LIB.S9S_MB_2U(SCH_1):UPI_CPU1_CPU0_P1P0_DN<20>
  U1     CE5  UPI1_TX_DN20  SOCKET4677_AZIFS054P001C01  I21
  U2     BL7  UPI0_RX_DP20  SOCKET4677_AZIFS054P001C01  I70

UPI_CPU1_CPU0_P1P0_DN<21>   @S9S_MB_2U_LIB.S9S_MB_2U(SCH_1):UPI_CPU1_CPU0_P1P0_DN<21>
  U1     CD6  UPI1_TX_DN21  SOCKET4677_AZIFS054P001C01  I21
  U2     BM6  UPI0_RX_DP21  SOCKET4677_AZIFS054P001C01  I70

UPI_CPU1_CPU0_P1P0_DN<22>   @S9S_MB_2U_LIB.S9S_MB_2U(SCH_1):UPI_CPU1_CPU0_P1P0_DN<22>
  U1     CA5  UPI1_TX_DN22  SOCKET4677_AZIFS054P001C01  I21
  U2     BR7  UPI0_RX_DN22  SOCKET4677_AZIFS054P001C01  I70

UPI_CPU1_CPU0_P1P0_DN<23>   @S9S_MB_2U_LIB.S9S_MB_2U(SCH_1):UPI_CPU1_CPU0_P1P0_DN<23>
  U1     BY6  UPI1_TX_DN23  SOCKET4677_AZIFS054P001C01  I21
  U2     BT6  UPI0_RX_DP23  SOCKET4677_AZIFS054P001C01  I70

UPI_CPU1_CPU0_P1P0_DP<0>   @S9S_MB_2U_LIB.S9S_MB_2U(SCH_1):UPI_CPU1_CPU0_P1P0_DP<0>
  U1     EE5  UPI1_TX_DP0  SOCKET4677_AZIFS054P001C01  I21
  U2      L7  UPI0_RX_DP0  SOCKET4677_AZIFS054P001C01  I70

UPI_CPU1_CPU0_P1P0_DP<1>   @S9S_MB_2U_LIB.S9S_MB_2U(SCH_1):UPI_CPU1_CPU0_P1P0_DP<1>
  U1     ED6  UPI1_TX_DP1  SOCKET4677_AZIFS054P001C01  I21
  U2      M6  UPI0_RX_DP1  SOCKET4677_AZIFS054P001C01  I70

UPI_CPU1_CPU0_P1P0_DP<2>   @S9S_MB_2U_LIB.S9S_MB_2U(SCH_1):UPI_CPU1_CPU0_P1P0_DP<2>
  U1     EA5  UPI1_TX_DP2  SOCKET4677_AZIFS054P001C01  I21
  U2      R7  UPI0_RX_DP2  SOCKET4677_AZIFS054P001C01  I70

UPI_CPU1_CPU0_P1P0_DP<3>   @S9S_MB_2U_LIB.S9S_MB_2U(SCH_1):UPI_CPU1_CPU0_P1P0_DP<3>
  U1     DW7  UPI1_TX_DP3  SOCKET4677_AZIFS054P001C01  I21
  U2      U5  UPI0_RX_DN3  SOCKET4677_AZIFS054P001C01  I70

UPI_CPU1_CPU0_P1P0_DP<4>   @S9S_MB_2U_LIB.S9S_MB_2U(SCH_1):UPI_CPU1_CPU0_P1P0_DP<4>
  U1     DU5  UPI1_TX_DP4  SOCKET4677_AZIFS054P001C01  I21
  U2      W7  UPI0_RX_DP4  SOCKET4677_AZIFS054P001C01  I70

UPI_CPU1_CPU0_P1P0_DP<5>   @S9S_MB_2U_LIB.S9S_MB_2U(SCH_1):UPI_CPU1_CPU0_P1P0_DP<5>
  U1     DR7  UPI1_TX_DP5  SOCKET4677_AZIFS054P001C01  I21
  U2     AA5  UPI0_RX_DN5  SOCKET4677_AZIFS054P001C01  I70

UPI_CPU1_CPU0_P1P0_DP<6>   @S9S_MB_2U_LIB.S9S_MB_2U(SCH_1):UPI_CPU1_CPU0_P1P0_DP<6>
  U1     DN5  UPI1_TX_DP6  SOCKET4677_AZIFS054P001C01  I21
  U2     AC7  UPI0_RX_DP6  SOCKET4677_AZIFS054P001C01  I70

UPI_CPU1_CPU0_P1P0_DP<7>   @S9S_MB_2U_LIB.S9S_MB_2U(SCH_1):UPI_CPU1_CPU0_P1P0_DP<7>
  U1     DM6  UPI1_TX_DP7  SOCKET4677_AZIFS054P001C01  I21
  U2     AD6  UPI0_RX_DP7  SOCKET4677_AZIFS054P001C01  I70

UPI_CPU1_CPU0_P1P0_DP<8>   @S9S_MB_2U_LIB.S9S_MB_2U(SCH_1):UPI_CPU1_CPU0_P1P0_DP<8>
  U1     DJ5  UPI1_TX_DP8  SOCKET4677_AZIFS054P001C01  I21
  U2     AG7  UPI0_RX_DP8  SOCKET4677_AZIFS054P001C01  I70

UPI_CPU1_CPU0_P1P0_DP<9>   @S9S_MB_2U_LIB.S9S_MB_2U(SCH_1):UPI_CPU1_CPU0_P1P0_DP<9>
  U1     DG7  UPI1_TX_DP9  SOCKET4677_AZIFS054P001C01  I21
  U2     AJ5  UPI0_RX_DP9  SOCKET4677_AZIFS054P001C01  I70

UPI_CPU1_CPU0_P1P0_DP<10>   @S9S_MB_2U_LIB.S9S_MB_2U(SCH_1):UPI_CPU1_CPU0_P1P0_DP<10>
  U1     DF6  UPI1_TX_DP10  SOCKET4677_AZIFS054P001C01  I21
  U2     AK6  UPI0_RX_DN10  SOCKET4677_AZIFS054P001C01  I70

UPI_CPU1_CPU0_P1P0_DP<11>   @S9S_MB_2U_LIB.S9S_MB_2U(SCH_1):UPI_CPU1_CPU0_P1P0_DP<11>
  U1     DC7  UPI1_TX_DP11  SOCKET4677_AZIFS054P001C01  I21
  U2     AN5  UPI0_RX_DN11  SOCKET4677_AZIFS054P001C01  I70

UPI_CPU1_CPU0_P1P0_DP<12>   @S9S_MB_2U_LIB.S9S_MB_2U(SCH_1):UPI_CPU1_CPU0_P1P0_DP<12>
  U1     DB6  UPI1_TX_DP12  SOCKET4677_AZIFS054P001C01  I21
  U2     AP6  UPI0_RX_DN12  SOCKET4677_AZIFS054P001C01  I70

UPI_CPU1_CPU0_P1P0_DP<13>   @S9S_MB_2U_LIB.S9S_MB_2U(SCH_1):UPI_CPU1_CPU0_P1P0_DP<13>
  U1     CW7  UPI1_TX_DP13  SOCKET4677_AZIFS054P001C01  I21
  U2     AU5  UPI0_RX_DN13  SOCKET4677_AZIFS054P001C01  I70

UPI_CPU1_CPU0_P1P0_DP<14>   @S9S_MB_2U_LIB.S9S_MB_2U(SCH_1):UPI_CPU1_CPU0_P1P0_DP<14>
  U1     CV6  UPI1_TX_DP14  SOCKET4677_AZIFS054P001C01  I21
  U2     AV6  UPI0_RX_DN14  SOCKET4677_AZIFS054P001C01  I70

UPI_CPU1_CPU0_P1P0_DP<15>   @S9S_MB_2U_LIB.S9S_MB_2U(SCH_1):UPI_CPU1_CPU0_P1P0_DP<15>
  U1     CR7  UPI1_TX_DP15  SOCKET4677_AZIFS054P001C01  I21
  U2     BA5  UPI0_RX_DN15  SOCKET4677_AZIFS054P001C01  I70

UPI_CPU1_CPU0_P1P0_DP<16>   @S9S_MB_2U_LIB.S9S_MB_2U(SCH_1):UPI_CPU1_CPU0_P1P0_DP<16>
  U1     CP6  UPI1_TX_DP16  SOCKET4677_AZIFS054P001C01  I21
  U2     BB6  UPI0_RX_DN16  SOCKET4677_AZIFS054P001C01  I70

UPI_CPU1_CPU0_P1P0_DP<17>   @S9S_MB_2U_LIB.S9S_MB_2U(SCH_1):UPI_CPU1_CPU0_P1P0_DP<17>
  U1     CL7  UPI1_TX_DP17  SOCKET4677_AZIFS054P001C01  I21
  U2     BE5  UPI0_RX_DN17  SOCKET4677_AZIFS054P001C01  I70

UPI_CPU1_CPU0_P1P0_DP<18>   @S9S_MB_2U_LIB.S9S_MB_2U(SCH_1):UPI_CPU1_CPU0_P1P0_DP<18>
  U1     CK6  UPI1_TX_DP18  SOCKET4677_AZIFS054P001C01  I21
  U2     BF6  UPI0_RX_DN18  SOCKET4677_AZIFS054P001C01  I70

UPI_CPU1_CPU0_P1P0_DP<19>   @S9S_MB_2U_LIB.S9S_MB_2U(SCH_1):UPI_CPU1_CPU0_P1P0_DP<19>
  U1     CG7  UPI1_TX_DP19  SOCKET4677_AZIFS054P001C01  I21
  U2     BJ5  UPI0_RX_DN19  SOCKET4677_AZIFS054P001C01  I70

UPI_CPU1_CPU0_P1P0_DP<20>   @S9S_MB_2U_LIB.S9S_MB_2U(SCH_1):UPI_CPU1_CPU0_P1P0_DP<20>
  U1     CF6  UPI1_TX_DP20  SOCKET4677_AZIFS054P001C01  I21
  U2     BK6  UPI0_RX_DN20  SOCKET4677_AZIFS054P001C01  I70

UPI_CPU1_CPU0_P1P0_DP<21>   @S9S_MB_2U_LIB.S9S_MB_2U(SCH_1):UPI_CPU1_CPU0_P1P0_DP<21>
  U1     CC7  UPI1_TX_DP21  SOCKET4677_AZIFS054P001C01  I21
  U2     BN5  UPI0_RX_DN21  SOCKET4677_AZIFS054P001C01  I70

UPI_CPU1_CPU0_P1P0_DP<22>   @S9S_MB_2U_LIB.S9S_MB_2U(SCH_1):UPI_CPU1_CPU0_P1P0_DP<22>
  U1     CB6  UPI1_TX_DP22  SOCKET4677_AZIFS054P001C01  I21
  U2     BP6  UPI0_RX_DP22  SOCKET4677_AZIFS054P001C01  I70

UPI_CPU1_CPU0_P1P0_DP<23>   @S9S_MB_2U_LIB.S9S_MB_2U(SCH_1):UPI_CPU1_CPU0_P1P0_DP<23>
  U1     BW7  UPI1_TX_DP23  SOCKET4677_AZIFS054P001C01  I21
  U2     BU5  UPI0_RX_DN23  SOCKET4677_AZIFS054P001C01  I70

UPI_CPU1_CPU0_P2P2_DN<0>   @S9S_MB_2U_LIB.S9S_MB_2U(SCH_1):UPI_CPU1_CPU0_P2P2_DN<0>
  U1     B85  UPI2_TX_DN0  SOCKET4677_AZIFS054P001C01  I16
  U2     BC74  UPI2_RX_DP23  SOCKET4677_AZIFS054P001C01  I102

UPI_CPU1_CPU0_P2P2_DN<1>   @S9S_MB_2U_LIB.S9S_MB_2U(SCH_1):UPI_CPU1_CPU0_P2P2_DN<1>
  U1     E84  UPI2_TX_DN1  SOCKET4677_AZIFS054P001C01  I16
  U2     BK73  UPI2_RX_DN22  SOCKET4677_AZIFS054P001C01  I102

UPI_CPU1_CPU0_P2P2_DN<2>   @S9S_MB_2U_LIB.S9S_MB_2U(SCH_1):UPI_CPU1_CPU0_P2P2_DN<2>
  U1     D87  UPI2_TX_DN2  SOCKET4677_AZIFS054P001C01  I16
  U2     BM75  UPI2_RX_DP21  SOCKET4677_AZIFS054P001C01  I102

UPI_CPU1_CPU0_P2P2_DN<3>   @S9S_MB_2U_LIB.S9S_MB_2U(SCH_1):UPI_CPU1_CPU0_P2P2_DN<3>
  U1     F87  UPI2_TX_DN3  SOCKET4677_AZIFS054P001C01  I16
  U2     BJ74  UPI2_RX_DP20  SOCKET4677_AZIFS054P001C01  I102

UPI_CPU1_CPU0_P2P2_DN<4>   @S9S_MB_2U_LIB.S9S_MB_2U(SCH_1):UPI_CPU1_CPU0_P2P2_DN<4>
  U1     H85  UPI2_TX_DN4  SOCKET4677_AZIFS054P001C01  I16
  U2     BN76  UPI2_RX_DP19  SOCKET4677_AZIFS054P001C01  I102

UPI_CPU1_CPU0_P2P2_DN<5>   @S9S_MB_2U_LIB.S9S_MB_2U(SCH_1):UPI_CPU1_CPU0_P2P2_DN<5>
  U1     P81  UPI2_TX_DN5  SOCKET4677_AZIFS054P001C01  I16
  U2     BJ76  UPI2_RX_DN18  SOCKET4677_AZIFS054P001C01  I102

UPI_CPU1_CPU0_P2P2_DN<6>   @S9S_MB_2U_LIB.S9S_MB_2U(SCH_1):UPI_CPU1_CPU0_P2P2_DN<6>
  U1     R82  UPI2_TX_DN6  SOCKET4677_AZIFS054P001C01  I16
  U2     BH75  UPI2_RX_DN17  SOCKET4677_AZIFS054P001C01  I102

UPI_CPU1_CPU0_P2P2_DN<7>   @S9S_MB_2U_LIB.S9S_MB_2U(SCH_1):UPI_CPU1_CPU0_P2P2_DN<7>
  U1     U80  UPI2_TX_DN7  SOCKET4677_AZIFS054P001C01  I16
  U2     AV75  UPI2_RX_DP16  SOCKET4677_AZIFS054P001C01  I102

UPI_CPU1_CPU0_P2P2_DN<8>   @S9S_MB_2U_LIB.S9S_MB_2U(SCH_1):UPI_CPU1_CPU0_P2P2_DN<8>
  U1     V83  UPI2_TX_DN8  SOCKET4677_AZIFS054P001C01  I16
  U2     BD75  UPI2_RX_DP15  SOCKET4677_AZIFS054P001C01  I102

UPI_CPU1_CPU0_P2P2_DN<9>   @S9S_MB_2U_LIB.S9S_MB_2U(SCH_1):UPI_CPU1_CPU0_P2P2_DN<9>
  U1     Y81  UPI2_TX_DN9  SOCKET4677_AZIFS054P001C01  I16
  U2     AY75  UPI2_RX_DN14  SOCKET4677_AZIFS054P001C01  I102

UPI_CPU1_CPU0_P2P2_DN<10>   @S9S_MB_2U_LIB.S9S_MB_2U(SCH_1):UPI_CPU1_CPU0_P2P2_DN<10>
  U1     AW78  UPI2_TX_DN10  SOCKET4677_AZIFS054P001C01  I16
  U2     AV73  UPI2_RX_DN13  SOCKET4677_AZIFS054P001C01  I102

UPI_CPU1_CPU0_P2P2_DN<11>   @S9S_MB_2U_LIB.S9S_MB_2U(SCH_1):UPI_CPU1_CPU0_P2P2_DN<11>
  U1     AU78  UPI2_TX_DN11  SOCKET4677_AZIFS054P001C01  I16
  U2     BB73  UPI2_RX_DP12  SOCKET4677_AZIFS054P001C01  I102

UPI_CPU1_CPU0_P2P2_DN<12>   @S9S_MB_2U_LIB.S9S_MB_2U(SCH_1):UPI_CPU1_CPU0_P2P2_DN<12>
  U1     AM81  UPI2_TX_DN12  SOCKET4677_AZIFS054P001C01  I16
  U2     AJ82  UPI2_RX_DP11  SOCKET4677_AZIFS054P001C01  I102

UPI_CPU1_CPU0_P2P2_DN<13>   @S9S_MB_2U_LIB.S9S_MB_2U(SCH_1):UPI_CPU1_CPU0_P2P2_DN<13>
  U1     AN82  UPI2_TX_DN13  SOCKET4677_AZIFS054P001C01  I16
  U2     AJ80  UPI2_RX_DN10  SOCKET4677_AZIFS054P001C01  I102

UPI_CPU1_CPU0_P2P2_DN<14>   @S9S_MB_2U_LIB.S9S_MB_2U(SCH_1):UPI_CPU1_CPU0_P2P2_DN<14>
  U1     AR80  UPI2_TX_DN14  SOCKET4677_AZIFS054P001C01  I16
  U2     AF83  UPI2_RX_DP9  SOCKET4677_AZIFS054P001C01  I102

UPI_CPU1_CPU0_P2P2_DN<15>   @S9S_MB_2U_LIB.S9S_MB_2U(SCH_1):UPI_CPU1_CPU0_P2P2_DN<15>
  U1     AT83  UPI2_TX_DN15  SOCKET4677_AZIFS054P001C01  I16
  U2     AG80  UPI2_RX_DP8  SOCKET4677_AZIFS054P001C01  I102

UPI_CPU1_CPU0_P2P2_DN<16>   @S9S_MB_2U_LIB.S9S_MB_2U(SCH_1):UPI_CPU1_CPU0_P2P2_DN<16>
  U1     AV81  UPI2_TX_DN16  SOCKET4677_AZIFS054P001C01  I16
  U2     AC82  UPI2_RX_DP7  SOCKET4677_AZIFS054P001C01  I102

UPI_CPU1_CPU0_P2P2_DN<17>   @S9S_MB_2U_LIB.S9S_MB_2U(SCH_1):UPI_CPU1_CPU0_P2P2_DN<17>
  U1     BA80  UPI2_TX_DN17  SOCKET4677_AZIFS054P001C01  I16
  U2     AC80  UPI2_RX_DN6  SOCKET4677_AZIFS054P001C01  I102

UPI_CPU1_CPU0_P2P2_DN<18>   @S9S_MB_2U_LIB.S9S_MB_2U(SCH_1):UPI_CPU1_CPU0_P2P2_DN<18>
  U1     BC82  UPI2_TX_DN18  SOCKET4677_AZIFS054P001C01  I16
  U2     L80  UPI2_RX_DN5  SOCKET4677_AZIFS054P001C01  I102

UPI_CPU1_CPU0_P2P2_DN<19>   @S9S_MB_2U_LIB.S9S_MB_2U(SCH_1):UPI_CPU1_CPU0_P2P2_DN<19>
  U1     BE82  UPI2_TX_DN19  SOCKET4677_AZIFS054P001C01  I16
  U2     J82  UPI2_RX_DN4  SOCKET4677_AZIFS054P001C01  I102

UPI_CPU1_CPU0_P2P2_DN<20>   @S9S_MB_2U_LIB.S9S_MB_2U(SCH_1):UPI_CPU1_CPU0_P2P2_DN<20>
  U1     BD79  UPI2_TX_DN20  SOCKET4677_AZIFS054P001C01  I16
  U2     K79  UPI2_RX_DN3  SOCKET4677_AZIFS054P001C01  I102

UPI_CPU1_CPU0_P2P2_DN<21>   @S9S_MB_2U_LIB.S9S_MB_2U(SCH_1):UPI_CPU1_CPU0_P2P2_DN<21>
  U1     BF81  UPI2_TX_DN21  SOCKET4677_AZIFS054P001C01  I16
  U2     G82  UPI2_RX_DN2  SOCKET4677_AZIFS054P001C01  I102

UPI_CPU1_CPU0_P2P2_DN<22>   @S9S_MB_2U_LIB.S9S_MB_2U(SCH_1):UPI_CPU1_CPU0_P2P2_DN<22>
  U1     BG80  UPI2_TX_DN22  SOCKET4677_AZIFS054P001C01  I16
  U2     E82  UPI2_RX_DP1  SOCKET4677_AZIFS054P001C01  I102

UPI_CPU1_CPU0_P2P2_DN<23>   @S9S_MB_2U_LIB.S9S_MB_2U(SCH_1):UPI_CPU1_CPU0_P2P2_DN<23>
  U1     BM71  UPI2_TX_DN23  SOCKET4677_AZIFS054P001C01  I16
  U2     E80  UPI2_RX_DN0  SOCKET4677_AZIFS054P001C01  I102

UPI_CPU1_CPU0_P2P2_DP<0>   @S9S_MB_2U_LIB.S9S_MB_2U(SCH_1):UPI_CPU1_CPU0_P2P2_DP<0>
  U1     D85  UPI2_TX_DP0  SOCKET4677_AZIFS054P001C01  I16
  U2     BD73  UPI2_RX_DN23  SOCKET4677_AZIFS054P001C01  I102

UPI_CPU1_CPU0_P2P2_DP<1>   @S9S_MB_2U_LIB.S9S_MB_2U(SCH_1):UPI_CPU1_CPU0_P2P2_DP<1>
  U1     F85  UPI2_TX_DP1  SOCKET4677_AZIFS054P001C01  I16
  U2     BL74  UPI2_RX_DP22  SOCKET4677_AZIFS054P001C01  I102

UPI_CPU1_CPU0_P2P2_DP<2>   @S9S_MB_2U_LIB.S9S_MB_2U(SCH_1):UPI_CPU1_CPU0_P2P2_DP<2>
  U1     E88  UPI2_TX_DP2  SOCKET4677_AZIFS054P001C01  I16
  U2     BN74  UPI2_RX_DN21  SOCKET4677_AZIFS054P001C01  I102

UPI_CPU1_CPU0_P2P2_DP<3>   @S9S_MB_2U_LIB.S9S_MB_2U(SCH_1):UPI_CPU1_CPU0_P2P2_DP<3>
  U1     H87  UPI2_TX_DP3  SOCKET4677_AZIFS054P001C01  I16
  U2     BG74  UPI2_RX_DN20  SOCKET4677_AZIFS054P001C01  I102

UPI_CPU1_CPU0_P2P2_DP<4>   @S9S_MB_2U_LIB.S9S_MB_2U(SCH_1):UPI_CPU1_CPU0_P2P2_DP<4>
  U1     G86  UPI2_TX_DP4  SOCKET4677_AZIFS054P001C01  I16
  U2     BL76  UPI2_RX_DN19  SOCKET4677_AZIFS054P001C01  I102

UPI_CPU1_CPU0_P2P2_DP<5>   @S9S_MB_2U_LIB.S9S_MB_2U(SCH_1):UPI_CPU1_CPU0_P2P2_DP<5>
  U1     T81  UPI2_TX_DP5  SOCKET4677_AZIFS054P001C01  I16
  U2     BK77  UPI2_RX_DP18  SOCKET4677_AZIFS054P001C01  I102

UPI_CPU1_CPU0_P2P2_DP<6>   @S9S_MB_2U_LIB.S9S_MB_2U(SCH_1):UPI_CPU1_CPU0_P2P2_DP<6>
  U1     P83  UPI2_TX_DP6  SOCKET4677_AZIFS054P001C01  I16
  U2     BG76  UPI2_RX_DP17  SOCKET4677_AZIFS054P001C01  I102

UPI_CPU1_CPU0_P2P2_DP<7>   @S9S_MB_2U_LIB.S9S_MB_2U(SCH_1):UPI_CPU1_CPU0_P2P2_DP<7>
  U1     V81  UPI2_TX_DP7  SOCKET4677_AZIFS054P001C01  I16
  U2     AW74  UPI2_RX_DN16  SOCKET4677_AZIFS054P001C01  I102

UPI_CPU1_CPU0_P2P2_DP<8>   @S9S_MB_2U_LIB.S9S_MB_2U(SCH_1):UPI_CPU1_CPU0_P2P2_DP<8>
  U1     Y83  UPI2_TX_DP8  SOCKET4677_AZIFS054P001C01  I16
  U2     BB75  UPI2_RX_DN15  SOCKET4677_AZIFS054P001C01  I102

UPI_CPU1_CPU0_P2P2_DP<9>   @S9S_MB_2U_LIB.S9S_MB_2U(SCH_1):UPI_CPU1_CPU0_P2P2_DP<9>
  U1     W82  UPI2_TX_DP9  SOCKET4677_AZIFS054P001C01  I16
  U2     BA76  UPI2_RX_DP14  SOCKET4677_AZIFS054P001C01  I102

UPI_CPU1_CPU0_P2P2_DP<10>   @S9S_MB_2U_LIB.S9S_MB_2U(SCH_1):UPI_CPU1_CPU0_P2P2_DP<10>
  U1     BA78  UPI2_TX_DP10  SOCKET4677_AZIFS054P001C01  I16
  U2     AY73  UPI2_RX_DP13  SOCKET4677_AZIFS054P001C01  I102

UPI_CPU1_CPU0_P2P2_DP<11>   @S9S_MB_2U_LIB.S9S_MB_2U(SCH_1):UPI_CPU1_CPU0_P2P2_DP<11>
  U1     AV79  UPI2_TX_DP11  SOCKET4677_AZIFS054P001C01  I16
  U2     BA72  UPI2_RX_DN12  SOCKET4677_AZIFS054P001C01  I102

UPI_CPU1_CPU0_P2P2_DP<12>   @S9S_MB_2U_LIB.S9S_MB_2U(SCH_1):UPI_CPU1_CPU0_P2P2_DP<12>
  U1     AP81  UPI2_TX_DP12  SOCKET4677_AZIFS054P001C01  I16
  U2     AG82  UPI2_RX_DN11  SOCKET4677_AZIFS054P001C01  I102

UPI_CPU1_CPU0_P2P2_DP<13>   @S9S_MB_2U_LIB.S9S_MB_2U(SCH_1):UPI_CPU1_CPU0_P2P2_DP<13>
  U1     AM83  UPI2_TX_DP13  SOCKET4677_AZIFS054P001C01  I16
  U2     AH81  UPI2_RX_DP10  SOCKET4677_AZIFS054P001C01  I102

UPI_CPU1_CPU0_P2P2_DP<14>   @S9S_MB_2U_LIB.S9S_MB_2U(SCH_1):UPI_CPU1_CPU0_P2P2_DP<14>
  U1     AT81  UPI2_TX_DP14  SOCKET4677_AZIFS054P001C01  I16
  U2     AE82  UPI2_RX_DN9  SOCKET4677_AZIFS054P001C01  I102

UPI_CPU1_CPU0_P2P2_DP<15>   @S9S_MB_2U_LIB.S9S_MB_2U(SCH_1):UPI_CPU1_CPU0_P2P2_DP<15>
  U1     AV83  UPI2_TX_DP15  SOCKET4677_AZIFS054P001C01  I16
  U2     AF79  UPI2_RX_DN8  SOCKET4677_AZIFS054P001C01  I102

UPI_CPU1_CPU0_P2P2_DP<16>   @S9S_MB_2U_LIB.S9S_MB_2U(SCH_1):UPI_CPU1_CPU0_P2P2_DP<16>
  U1     AU82  UPI2_TX_DP16  SOCKET4677_AZIFS054P001C01  I16
  U2     AD81  UPI2_RX_DN7  SOCKET4677_AZIFS054P001C01  I102

UPI_CPU1_CPU0_P2P2_DP<17>   @S9S_MB_2U_LIB.S9S_MB_2U(SCH_1):UPI_CPU1_CPU0_P2P2_DP<17>
  U1     BB81  UPI2_TX_DP17  SOCKET4677_AZIFS054P001C01  I16
  U2     AE80  UPI2_RX_DP6  SOCKET4677_AZIFS054P001C01  I102

UPI_CPU1_CPU0_P2P2_DP<18>   @S9S_MB_2U_LIB.S9S_MB_2U(SCH_1):UPI_CPU1_CPU0_P2P2_DP<18>
  U1     BA82  UPI2_TX_DP18  SOCKET4677_AZIFS054P001C01  I16
  U2     K81  UPI2_RX_DP5  SOCKET4677_AZIFS054P001C01  I102

UPI_CPU1_CPU0_P2P2_DP<19>   @S9S_MB_2U_LIB.S9S_MB_2U(SCH_1):UPI_CPU1_CPU0_P2P2_DP<19>
  U1     BD83  UPI2_TX_DP19  SOCKET4677_AZIFS054P001C01  I16
  U2     L82  UPI2_RX_DP4  SOCKET4677_AZIFS054P001C01  I102

UPI_CPU1_CPU0_P2P2_DP<20>   @S9S_MB_2U_LIB.S9S_MB_2U(SCH_1):UPI_CPU1_CPU0_P2P2_DP<20>
  U1     BC80  UPI2_TX_DP20  SOCKET4677_AZIFS054P001C01  I16
  U2     M79  UPI2_RX_DP3  SOCKET4677_AZIFS054P001C01  I102

UPI_CPU1_CPU0_P2P2_DP<21>   @S9S_MB_2U_LIB.S9S_MB_2U(SCH_1):UPI_CPU1_CPU0_P2P2_DP<21>
  U1     BG82  UPI2_TX_DP21  SOCKET4677_AZIFS054P001C01  I16
  U2     H83  UPI2_RX_DP2  SOCKET4677_AZIFS054P001C01  I102

UPI_CPU1_CPU0_P2P2_DP<22>   @S9S_MB_2U_LIB.S9S_MB_2U(SCH_1):UPI_CPU1_CPU0_P2P2_DP<22>
  U1     BE80  UPI2_TX_DP22  SOCKET4677_AZIFS054P001C01  I16
  U2     F81  UPI2_RX_DN1  SOCKET4677_AZIFS054P001C01  I102

UPI_CPU1_CPU0_P2P2_DP<23>   @S9S_MB_2U_LIB.S9S_MB_2U(SCH_1):UPI_CPU1_CPU0_P2P2_DP<23>
  U1     BN72  UPI2_TX_DP23  SOCKET4677_AZIFS054P001C01  I16
  U2     G80  UPI2_RX_DP0  SOCKET4677_AZIFS054P001C01  I102

UPI_CPU1_CPU0_P3P3_DN<0>   @S9S_MB_2U_LIB.S9S_MB_2U(SCH_1):UPI_CPU1_CPU0_P3P3_DN<0>
  U1     EH85  UPI3_TX_DN0  SOCKET4677_AZIFS054P001C01  I16
  U2     DA78  UPI3_RX_DN23  SOCKET4677_AZIFS054P001C01  I102

UPI_CPU1_CPU0_P3P3_DN<1>   @S9S_MB_2U_LIB.S9S_MB_2U(SCH_1):UPI_CPU1_CPU0_P3P3_DN<1>
  U1     EL84  UPI3_TX_DN1  SOCKET4677_AZIFS054P001C01  I16
  U2     CT79  UPI3_RX_DN22  SOCKET4677_AZIFS054P001C01  I102

UPI_CPU1_CPU0_P3P3_DN<2>   @S9S_MB_2U_LIB.S9S_MB_2U(SCH_1):UPI_CPU1_CPU0_P3P3_DN<2>
  U1     EP85  UPI3_TX_DN2  SOCKET4677_AZIFS054P001C01  I16
  U2     CN80  UPI3_RX_DN21  SOCKET4677_AZIFS054P001C01  I102

UPI_CPU1_CPU0_P3P3_DN<3>   @S9S_MB_2U_LIB.S9S_MB_2U(SCH_1):UPI_CPU1_CPU0_P3P3_DN<3>
  U1     EP87  UPI3_TX_DP3  SOCKET4677_AZIFS054P001C01  I16
  U2     CP81  UPI3_RX_DN20  SOCKET4677_AZIFS054P001C01  I102

UPI_CPU1_CPU0_P3P3_DN<4>   @S9S_MB_2U_LIB.S9S_MB_2U(SCH_1):UPI_CPU1_CPU0_P3P3_DN<4>
  U1     EJ86  UPI3_TX_DN4  SOCKET4677_AZIFS054P001C01  I16
  U2     CW80  UPI3_RX_DN19  SOCKET4677_AZIFS054P001C01  I102

UPI_CPU1_CPU0_P3P3_DN<5>   @S9S_MB_2U_LIB.S9S_MB_2U(SCH_1):UPI_CPU1_CPU0_P3P3_DN<5>
  U1     EK87  UPI3_TX_DN5  SOCKET4677_AZIFS054P001C01  I16
  U2     CR82  UPI3_RX_DN18  SOCKET4677_AZIFS054P001C01  I102

UPI_CPU1_CPU0_P3P3_DN<6>   @S9S_MB_2U_LIB.S9S_MB_2U(SCH_1):UPI_CPU1_CPU0_P3P3_DN<6>
  U1     DU80  UPI3_TX_DN6  SOCKET4677_AZIFS054P001C01  I16
  U2     CU82  UPI3_RX_DN17  SOCKET4677_AZIFS054P001C01  I102

UPI_CPU1_CPU0_P3P3_DN<7>   @S9S_MB_2U_LIB.S9S_MB_2U(SCH_1):UPI_CPU1_CPU0_P3P3_DN<7>
  U1     DR82  UPI3_TX_DN7  SOCKET4677_AZIFS054P001C01  I16
  U2     DF77  UPI3_RX_DN16  SOCKET4677_AZIFS054P001C01  I102

UPI_CPU1_CPU0_P3P3_DN<8>   @S9S_MB_2U_LIB.S9S_MB_2U(SCH_1):UPI_CPU1_CPU0_P3P3_DN<8>
  U1     DP79  UPI3_TX_DN8  SOCKET4677_AZIFS054P001C01  I16
  U2     DB81  UPI3_RX_DN15  SOCKET4677_AZIFS054P001C01  I102

UPI_CPU1_CPU0_P3P3_DN<9>   @S9S_MB_2U_LIB.S9S_MB_2U(SCH_1):UPI_CPU1_CPU0_P3P3_DN<9>
  U1     DN82  UPI3_TX_DN9  SOCKET4677_AZIFS054P001C01  I16
  U2     DC82  UPI3_RX_DN14  SOCKET4677_AZIFS054P001C01  I102

UPI_CPU1_CPU0_P3P3_DN<10>   @S9S_MB_2U_LIB.S9S_MB_2U(SCH_1):UPI_CPU1_CPU0_P3P3_DN<10>
  U1     DM81  UPI3_TX_DN10  SOCKET4677_AZIFS054P001C01  I16
  U2     DE80  UPI3_RX_DN13  SOCKET4677_AZIFS054P001C01  I102

UPI_CPU1_CPU0_P3P3_DN<11>   @S9S_MB_2U_LIB.S9S_MB_2U(SCH_1):UPI_CPU1_CPU0_P3P3_DN<11>
  U1     DN80  UPI3_TX_DP11  SOCKET4677_AZIFS054P001C01  I16
  U2     DF83  UPI3_RX_DN12  SOCKET4677_AZIFS054P001C01  I102

UPI_CPU1_CPU0_P3P3_DN<12>   @S9S_MB_2U_LIB.S9S_MB_2U(SCH_1):UPI_CPU1_CPU0_P3P3_DN<12>
  U1     CW76  UPI3_TX_DN12  SOCKET4677_AZIFS054P001C01  I16
  U2     DH81  UPI3_RX_DN11  SOCKET4677_AZIFS054P001C01  I102

UPI_CPU1_CPU0_P3P3_DN<13>   @S9S_MB_2U_LIB.S9S_MB_2U(SCH_1):UPI_CPU1_CPU0_P3P3_DN<13>
  U1     CU76  UPI3_TX_DN13  SOCKET4677_AZIFS054P001C01  I16
  U2     DG78  UPI3_RX_DN10  SOCKET4677_AZIFS054P001C01  I102

UPI_CPU1_CPU0_P3P3_DN<14>   @S9S_MB_2U_LIB.S9S_MB_2U(SCH_1):UPI_CPU1_CPU0_P3P3_DN<14>
  U1     CT75  UPI3_TX_DN14  SOCKET4677_AZIFS054P001C01  I16
  U2     DJ78  UPI3_RX_DN9  SOCKET4677_AZIFS054P001C01  I102

UPI_CPU1_CPU0_P3P3_DN<15>   @S9S_MB_2U_LIB.S9S_MB_2U(SCH_1):UPI_CPU1_CPU0_P3P3_DN<15>
  U1     CU74  UPI3_TX_DP15  SOCKET4677_AZIFS054P001C01  I16
  U2     DY81  UPI3_RX_DN8  SOCKET4677_AZIFS054P001C01  I102

UPI_CPU1_CPU0_P3P3_DN<16>   @S9S_MB_2U_LIB.S9S_MB_2U(SCH_1):UPI_CPU1_CPU0_P3P3_DN<16>
  U1     CM77  UPI3_TX_DP16  SOCKET4677_AZIFS054P001C01  I16
  U2     EA82  UPI3_RX_DN7  SOCKET4677_AZIFS054P001C01  I102

UPI_CPU1_CPU0_P3P3_DN<17>   @S9S_MB_2U_LIB.S9S_MB_2U(SCH_1):UPI_CPU1_CPU0_P3P3_DN<17>
  U1     CH77  UPI3_TX_DN17  SOCKET4677_AZIFS054P001C01  I16
  U2     EC80  UPI3_RX_DN6  SOCKET4677_AZIFS054P001C01  I102

UPI_CPU1_CPU0_P3P3_DN<18>   @S9S_MB_2U_LIB.S9S_MB_2U(SCH_1):UPI_CPU1_CPU0_P3P3_DN<18>
  U1     CL76  UPI3_TX_DP18  SOCKET4677_AZIFS054P001C01  I16
  U2     ED83  UPI3_RX_DN5  SOCKET4677_AZIFS054P001C01  I102

UPI_CPU1_CPU0_P3P3_DN<19>   @S9S_MB_2U_LIB.S9S_MB_2U(SCH_1):UPI_CPU1_CPU0_P3P3_DN<19>
  U1     CG76  UPI3_TX_DN19  SOCKET4677_AZIFS054P001C01  I16
  U2     EF81  UPI3_RX_DN4  SOCKET4677_AZIFS054P001C01  I102

UPI_CPU1_CPU0_P3P3_DN<20>   @S9S_MB_2U_LIB.S9S_MB_2U(SCH_1):UPI_CPU1_CPU0_P3P3_DN<20>
  U1     CF75  UPI3_TX_DN20  SOCKET4677_AZIFS054P001C01  I16
  U2     EK81  UPI3_RX_DN3  SOCKET4677_AZIFS054P001C01  I102

UPI_CPU1_CPU0_P3P3_DN<21>   @S9S_MB_2U_LIB.S9S_MB_2U(SCH_1):UPI_CPU1_CPU0_P3P3_DN<21>
  U1     CK75  UPI3_TX_DP21  SOCKET4677_AZIFS054P001C01  I16
  U2     EL82  UPI3_RX_DN2  SOCKET4677_AZIFS054P001C01  I102

UPI_CPU1_CPU0_P3P3_DN<22>   @S9S_MB_2U_LIB.S9S_MB_2U(SCH_1):UPI_CPU1_CPU0_P3P3_DN<22>
  U1     CW74  UPI3_TX_DP22  SOCKET4677_AZIFS054P001C01  I16
  U2     EP81  UPI3_RX_DN1  SOCKET4677_AZIFS054P001C01  I102

UPI_CPU1_CPU0_P3P3_DN<23>   @S9S_MB_2U_LIB.S9S_MB_2U(SCH_1):UPI_CPU1_CPU0_P3P3_DN<23>
  U1     CD73  UPI3_TX_DP23  SOCKET4677_AZIFS054P001C01  I16
  U2     EJ80  UPI3_RX_DN0  SOCKET4677_AZIFS054P001C01  I102

UPI_CPU1_CPU0_P3P3_DP<0>   @S9S_MB_2U_LIB.S9S_MB_2U(SCH_1):UPI_CPU1_CPU0_P3P3_DP<0>
  U1     EK85  UPI3_TX_DP0  SOCKET4677_AZIFS054P001C01  I16
  U2     DB79  UPI3_RX_DP23  SOCKET4677_AZIFS054P001C01  I102

UPI_CPU1_CPU0_P3P3_DP<1>   @S9S_MB_2U_LIB.S9S_MB_2U(SCH_1):UPI_CPU1_CPU0_P3P3_DP<1>
  U1     EM85  UPI3_TX_DP1  SOCKET4677_AZIFS054P001C01  I16
  U2     CU80  UPI3_RX_DP22  SOCKET4677_AZIFS054P001C01  I102

UPI_CPU1_CPU0_P3P3_DP<2>   @S9S_MB_2U_LIB.S9S_MB_2U(SCH_1):UPI_CPU1_CPU0_P3P3_DP<2>
  U1     EN86  UPI3_TX_DP2  SOCKET4677_AZIFS054P001C01  I16
  U2     CR80  UPI3_RX_DP21  SOCKET4677_AZIFS054P001C01  I102

UPI_CPU1_CPU0_P3P3_DP<3>   @S9S_MB_2U_LIB.S9S_MB_2U(SCH_1):UPI_CPU1_CPU0_P3P3_DP<3>
  U1     EM87  UPI3_TX_DN3  SOCKET4677_AZIFS054P001C01  I16
  U2     CN82  UPI3_RX_DP20  SOCKET4677_AZIFS054P001C01  I102

UPI_CPU1_CPU0_P3P3_DP<4>   @S9S_MB_2U_LIB.S9S_MB_2U(SCH_1):UPI_CPU1_CPU0_P3P3_DP<4>
  U1     EH87  UPI3_TX_DP4  SOCKET4677_AZIFS054P001C01  I16
  U2     CV81  UPI3_RX_DP19  SOCKET4677_AZIFS054P001C01  I102

UPI_CPU1_CPU0_P3P3_DP<5>   @S9S_MB_2U_LIB.S9S_MB_2U(SCH_1):UPI_CPU1_CPU0_P3P3_DP<5>
  U1     EL88  UPI3_TX_DP5  SOCKET4677_AZIFS054P001C01  I16
  U2     CT83  UPI3_RX_DP18  SOCKET4677_AZIFS054P001C01  I102

UPI_CPU1_CPU0_P3P3_DP<6>   @S9S_MB_2U_LIB.S9S_MB_2U(SCH_1):UPI_CPU1_CPU0_P3P3_DP<6>
  U1     DT81  UPI3_TX_DP6  SOCKET4677_AZIFS054P001C01  I16
  U2     CW82  UPI3_RX_DP17  SOCKET4677_AZIFS054P001C01  I102

UPI_CPU1_CPU0_P3P3_DP<7>   @S9S_MB_2U_LIB.S9S_MB_2U(SCH_1):UPI_CPU1_CPU0_P3P3_DP<7>
  U1     DU82  UPI3_TX_DP7  SOCKET4677_AZIFS054P001C01  I16
  U2     DE78  UPI3_RX_DP16  SOCKET4677_AZIFS054P001C01  I102

UPI_CPU1_CPU0_P3P3_DP<8>   @S9S_MB_2U_LIB.S9S_MB_2U(SCH_1):UPI_CPU1_CPU0_P3P3_DP<8>
  U1     DR80  UPI3_TX_DP8  SOCKET4677_AZIFS054P001C01  I16
  U2     DD81  UPI3_RX_DP15  SOCKET4677_AZIFS054P001C01  I102

UPI_CPU1_CPU0_P3P3_DP<9>   @S9S_MB_2U_LIB.S9S_MB_2U(SCH_1):UPI_CPU1_CPU0_P3P3_DP<9>
  U1     DP83  UPI3_TX_DP9  SOCKET4677_AZIFS054P001C01  I16
  U2     DB83  UPI3_RX_DP14  SOCKET4677_AZIFS054P001C01  I102

UPI_CPU1_CPU0_P3P3_DP<10>   @S9S_MB_2U_LIB.S9S_MB_2U(SCH_1):UPI_CPU1_CPU0_P3P3_DP<10>
  U1     DL82  UPI3_TX_DP10  SOCKET4677_AZIFS054P001C01  I16
  U2     DF81  UPI3_RX_DP13  SOCKET4677_AZIFS054P001C01  I102

UPI_CPU1_CPU0_P3P3_DP<11>   @S9S_MB_2U_LIB.S9S_MB_2U(SCH_1):UPI_CPU1_CPU0_P3P3_DP<11>
  U1     DL80  UPI3_TX_DN11  SOCKET4677_AZIFS054P001C01  I16
  U2     DH83  UPI3_RX_DP12  SOCKET4677_AZIFS054P001C01  I102

UPI_CPU1_CPU0_P3P3_DP<12>   @S9S_MB_2U_LIB.S9S_MB_2U(SCH_1):UPI_CPU1_CPU0_P3P3_DP<12>
  U1     DA76  UPI3_TX_DP12  SOCKET4677_AZIFS054P001C01  I16
  U2     DG82  UPI3_RX_DP11  SOCKET4677_AZIFS054P001C01  I102

UPI_CPU1_CPU0_P3P3_DP<13>   @S9S_MB_2U_LIB.S9S_MB_2U(SCH_1):UPI_CPU1_CPU0_P3P3_DP<13>
  U1     CV77  UPI3_TX_DP13  SOCKET4677_AZIFS054P001C01  I16
  U2     DH79  UPI3_RX_DP10  SOCKET4677_AZIFS054P001C01  I102

UPI_CPU1_CPU0_P3P3_DP<14>   @S9S_MB_2U_LIB.S9S_MB_2U(SCH_1):UPI_CPU1_CPU0_P3P3_DP<14>
  U1     CR76  UPI3_TX_DP14  SOCKET4677_AZIFS054P001C01  I16
  U2     DL78  UPI3_RX_DP9  SOCKET4677_AZIFS054P001C01  I102

UPI_CPU1_CPU0_P3P3_DP<15>   @S9S_MB_2U_LIB.S9S_MB_2U(SCH_1):UPI_CPU1_CPU0_P3P3_DP<15>
  U1     CR74  UPI3_TX_DN15  SOCKET4677_AZIFS054P001C01  I16
  U2     EB81  UPI3_RX_DP8  SOCKET4677_AZIFS054P001C01  I102

UPI_CPU1_CPU0_P3P3_DP<16>   @S9S_MB_2U_LIB.S9S_MB_2U(SCH_1):UPI_CPU1_CPU0_P3P3_DP<16>
  U1     CK77  UPI3_TX_DN16  SOCKET4677_AZIFS054P001C01  I16
  U2     DY83  UPI3_RX_DP7  SOCKET4677_AZIFS054P001C01  I102

UPI_CPU1_CPU0_P3P3_DP<17>   @S9S_MB_2U_LIB.S9S_MB_2U(SCH_1):UPI_CPU1_CPU0_P3P3_DP<17>
  U1     CJ78  UPI3_TX_DP17  SOCKET4677_AZIFS054P001C01  I16
  U2     ED81  UPI3_RX_DP6  SOCKET4677_AZIFS054P001C01  I102

UPI_CPU1_CPU0_P3P3_DP<18>   @S9S_MB_2U_LIB.S9S_MB_2U(SCH_1):UPI_CPU1_CPU0_P3P3_DP<18>
  U1     CM75  UPI3_TX_DN18  SOCKET4677_AZIFS054P001C01  I16
  U2     EF83  UPI3_RX_DP5  SOCKET4677_AZIFS054P001C01  I102

UPI_CPU1_CPU0_P3P3_DP<19>   @S9S_MB_2U_LIB.S9S_MB_2U(SCH_1):UPI_CPU1_CPU0_P3P3_DP<19>
  U1     CF77  UPI3_TX_DP19  SOCKET4677_AZIFS054P001C01  I16
  U2     EE82  UPI3_RX_DP4  SOCKET4677_AZIFS054P001C01  I102

UPI_CPU1_CPU0_P3P3_DP<20>   @S9S_MB_2U_LIB.S9S_MB_2U(SCH_1):UPI_CPU1_CPU0_P3P3_DP<20>
  U1     CH75  UPI3_TX_DP20  SOCKET4677_AZIFS054P001C01  I16
  U2     EJ82  UPI3_RX_DP3  SOCKET4677_AZIFS054P001C01  I102

UPI_CPU1_CPU0_P3P3_DP<21>   @S9S_MB_2U_LIB.S9S_MB_2U(SCH_1):UPI_CPU1_CPU0_P3P3_DP<21>
  U1     CJ74  UPI3_TX_DN21  SOCKET4677_AZIFS054P001C01  I16
  U2     EN82  UPI3_RX_DP2  SOCKET4677_AZIFS054P001C01  I102

UPI_CPU1_CPU0_P3P3_DP<22>   @S9S_MB_2U_LIB.S9S_MB_2U(SCH_1):UPI_CPU1_CPU0_P3P3_DP<22>
  U1     CV73  UPI3_TX_DN22  SOCKET4677_AZIFS054P001C01  I16
  U2     ER82  UPI3_RX_DP1  SOCKET4677_AZIFS054P001C01  I102

UPI_CPU1_CPU0_P3P3_DP<23>   @S9S_MB_2U_LIB.S9S_MB_2U(SCH_1):UPI_CPU1_CPU0_P3P3_DP<23>
  U1     CF73  UPI3_TX_DN23  SOCKET4677_AZIFS054P001C01  I16
  U2     EL80  UPI3_RX_DP0  SOCKET4677_AZIFS054P001C01  I102

USB2_0_DN       @S9S_MB_2U_LIB.S9S_MB_2U(SCH_1):USB2_0_DN
  J41    B57  PETP12  SCONN168_623403212  I115
  U4     AR42  USB2N_0  EMMITSBURG_REV0P9  I11

USB2_0_DP       @S9S_MB_2U_LIB.S9S_MB_2U(SCH_1):USB2_0_DP
  J41    B56  PETN12  SCONN168_623403212  I115
  U4     AR40  USB2P_0  EMMITSBURG_REV0P9  I11

USB2_1_DN       @S9S_MB_2U_LIB.S9S_MB_2U(SCH_1):USB2_1_DN
  L9       4      4  Q_INDUCTOR4P_12   I4
  R470     1      A  Q_RES        I3
  U4     AP43  USB2N_1  EMMITSBURG_REV0P9  I11

USB2_1_DP       @S9S_MB_2U_LIB.S9S_MB_2U(SCH_1):USB2_1_DP
  L9       1      1  Q_INDUCTOR4P_12   I4
  R469     1      A  Q_RES        I5
  U4     AP41  USB2P_1  EMMITSBURG_REV0P9  I11

USB2_1_F_DN     @S9S_MB_2U_LIB.S9S_MB_2U(SCH_1):USB2_1_F_DN
  J48      2     D-  CONN9_2UB3903013101F  I39
  L9       3      3  Q_INDUCTOR4P_12   I4
  R470     2      B  Q_RES        I3

USB2_1_F_DP     @S9S_MB_2U_LIB.S9S_MB_2U(SCH_1):USB2_1_F_DP
  J48      3     D+  CONN9_2UB3903013101F  I39
  L9       2      2  Q_INDUCTOR4P_12   I4
  R469     2      B  Q_RES        I5

USB2_3_DN       @S9S_MB_2U_LIB.S9S_MB_2U(SCH_1):USB2_3_DN
  R444     2      B  Q_RES       I350
  U4     AN42  USB2N_3  EMMITSBURG_REV0P9  I11

USB2_3_DP       @S9S_MB_2U_LIB.S9S_MB_2U(SCH_1):USB2_3_DP
  R445     2      B  Q_RES       I349
  U4     AN40  USB2P_3  EMMITSBURG_REV0P9  I11

USB2_4_DN       @S9S_MB_2U_LIB.S9S_MB_2U(SCH_1):USB2_4_DN
  R2130    1      A  Q_RES       I322
  U4     AU42  USB2N_4  EMMITSBURG_REV0P9  I11

USB2_4_DP       @S9S_MB_2U_LIB.S9S_MB_2U(SCH_1):USB2_4_DP
  R2131    1      A  Q_RES       I323
  U4     AU40  USB2P_4  EMMITSBURG_REV0P9  I11

USB2_5_DN       @S9S_MB_2U_LIB.S9S_MB_2U(SCH_1):USB2_5_DN
  R2149    2      B  Q_RES       I460
  U4     AL43  USB2N_5  EMMITSBURG_REV0P9  I11

USB2_5_DP       @S9S_MB_2U_LIB.S9S_MB_2U(SCH_1):USB2_5_DP
  R2150    2      B  Q_RES       I457
  U4     AL41  USB2P_5  EMMITSBURG_REV0P9  I11

USB2_8_DN       @S9S_MB_2U_LIB.S9S_MB_2U(SCH_1):USB2_8_DN
  J41    B54  PETP11  SCONN168_623403212  I115
  U4     AW42  USB2N_8  EMMITSBURG_REV0P9  I11

USB2_8_DP       @S9S_MB_2U_LIB.S9S_MB_2U(SCH_1):USB2_8_DP
  J41    B53  PETN11  SCONN168_623403212  I115
  U4     AW40  USB2P_8  EMMITSBURG_REV0P9  I11

USB2_9_DN       @S9S_MB_2U_LIB.S9S_MB_2U(SCH_1):USB2_9_DN
  J41    B51  PETP10  SCONN168_623403212  I115
  U4     AJ43  USB2N_9  EMMITSBURG_REV0P9  I11

USB2_9_DP       @S9S_MB_2U_LIB.S9S_MB_2U(SCH_1):USB2_9_DP
  J41    B50  PETN10  SCONN168_623403212  I115
  U4     AJ41  USB2P_9  EMMITSBURG_REV0P9  I11

USB3_9_RX_DN    @S9S_MB_2U_LIB.S9S_MB_2U(SCH_1):USB3_9_RX_DN
  L6       1      1  Q_INDUCTOR4P_12  I18
  R466     1      A  Q_RES       I20
  U4     R40  SATA_9_PCIE3_9_USB3_9_RXN  EMMITSBURG_REV0P9  I119

USB3_9_RX_DN_FB   @S9S_MB_2U_LIB.S9S_MB_2U(SCH_1):USB3_9_RX_DN_FB
  J48      5  SSRX-  CONN9_2UB3903013101F  I39
  L6       2      2  Q_INDUCTOR4P_12  I18
  R466     2      B  Q_RES       I20

USB3_9_RX_DP    @S9S_MB_2U_LIB.S9S_MB_2U(SCH_1):USB3_9_RX_DP
  L6       4      4  Q_INDUCTOR4P_12  I18
  R468     1      A  Q_RES       I19
  U4     R42  SATA_9_PCIE3_9_USB3_9_RXP  EMMITSBURG_REV0P9  I119

USB3_9_RX_DP_FB   @S9S_MB_2U_LIB.S9S_MB_2U(SCH_1):USB3_9_RX_DP_FB
  J48      6  SSRX+  CONN9_2UB3903013101F  I39
  L6       3      3  Q_INDUCTOR4P_12  I18
  R468     2      B  Q_RES       I19

USB3_9_TX_DN    @S9S_MB_2U_LIB.S9S_MB_2U(SCH_1):USB3_9_TX_DN
  C565     1      A  Q_CAP       I23
  U4     AE32  SATA_9_PCIE3_9_USB3_9_TXN  EMMITSBURG_REV0P9  I119

USB3_9_TX_DN_C   @S9S_MB_2U_LIB.S9S_MB_2U(SCH_1):USB3_9_TX_DN_C
  C565     2      B  Q_CAP       I23
  L5       1      1  Q_INDUCTOR4P_12  I22
  R464     1      A  Q_RES       I27

USB3_9_TX_DN_FB   @S9S_MB_2U_LIB.S9S_MB_2U(SCH_1):USB3_9_TX_DN_FB
  J48      8  SSTX-  CONN9_2UB3903013101F  I39
  L5       2      2  Q_INDUCTOR4P_12  I22
  R464     2      B  Q_RES       I27

USB3_9_TX_DP    @S9S_MB_2U_LIB.S9S_MB_2U(SCH_1):USB3_9_TX_DP
  C566     1      A  Q_CAP       I17
  U4     AG32  SATA_9_PCIE3_9_USB3_9_TXP  EMMITSBURG_REV0P9  I119

USB3_9_TX_DP_C   @S9S_MB_2U_LIB.S9S_MB_2U(SCH_1):USB3_9_TX_DP_C
  C566     2      B  Q_CAP       I17
  L5       4      4  Q_INDUCTOR4P_12  I22
  R465     1      A  Q_RES       I21

USB3_9_TX_DP_FB   @S9S_MB_2U_LIB.S9S_MB_2U(SCH_1):USB3_9_TX_DP_FB
  J48      9  SSTX+  CONN9_2UB3903013101F  I39
  L5       3      3  Q_INDUCTOR4P_12  I22
  R465     2      B  Q_RES       I21

USB_OC1_REAR_N   @S9S_MB_2U_LIB.S9S_MB_2U(SCH_1):USB_OC1_REAR_N
  R1827    2      B  Q_RES       I193
  U122    B9  DIFFIO_RX_T16P  10M04SAU324I7G  I155

USB_OC1_REAR_R_N   @S9S_MB_2U_LIB.S9S_MB_2U(SCH_1):USB_OC1_REAR_R_N
  R1827    1      A  Q_RES       I193
  R1828    1      A  Q_RES       I188
  U4     BG32  GPPC_B_6_USB2_OCB_1  EMMITSBURG_REV0P9  I93

USB_OC2_INT_N   @S9S_MB_2U_LIB.S9S_MB_2U(SCH_1):USB_OC2_INT_N
  R463     2      B  Q_RES       I29
  R471     1      A  Q_RES       I30
  U27      4  FAULT_N  TPS2553DBVR1  I24

USB_OC2_INT_R_N   @S9S_MB_2U_LIB.S9S_MB_2U(SCH_1):USB_OC2_INT_R_N
  R471     2      B  Q_RES       I30
  U4     BG30  GPPC_B_7_USB2_OCB_2  EMMITSBURG_REV0P9  I93

VDD3            @S9S_MB_2U_LIB.S9S_MB_2U(SCH_1):VDD3
  C1581    1      A  Q_CAP       I124
  C1587    1      A  Q_CAP       I99
  R2072    1      A  Q_RES       I130
  R2073    1      A  Q_RES       I137
  R2084    1      A  Q_RES       I102
  R2085    1      A  Q_RES       I103
  U81     21   VDD3  MP5981GLUZ  I66
  U107    21   VDD3  MP5981GLUZ  I113

VIRTUAL_RESEAT   @S9S_MB_2U_LIB.S9S_MB_2U(SCH_1):VIRTUAL_RESEAT
  J41    OCP_A14  RBT_CLK_IN  SCONN168_623403212  I115
  U122    G7  DIFFIO_RX_L9N  10M04SAU324I7G  I93

VIRTUAL_RESEAT_FPGA_N   @S9S_MB_2U_LIB.S9S_MB_2U(SCH_1):VIRTUAL_RESEAT_FPGA_N
  R1853    2      B  Q_RES       I248
  R2135    1      A  Q_RES       I53

VIRTUAL_RESEAT_FPGA_R_N   @S9S_MB_2U_LIB.S9S_MB_2U(SCH_1):VIRTUAL_RESEAT_FPGA_R_N
  R1853    1      A  Q_RES       I248
  U122    H2  DIFFIO_RX_L10N  10M04SAU324I7G  I93

VOL_SEN_ADDR    @S9S_MB_2U_LIB.S9S_MB_2U(SCH_1):VOL_SEN_ADDR
  R1784    2      B  Q_RES       I14
  R1785    1      A  Q_RES       I17
  U105     1   ADDR  ADS1015IDGSR   I1

VOL_SEN_ALERT   @S9S_MB_2U_LIB.S9S_MB_2U(SCH_1):VOL_SEN_ALERT
  R1794    2      B  Q_RES       I10
  R2070    1      A  Q_RES       I437
  U105     2  ALRET_RDY  ADS1015IDGSR   I1

VOL_SEN_ALERT_R   @S9S_MB_2U_LIB.S9S_MB_2U(SCH_1):VOL_SEN_ALERT_R
  R2070    2      B  Q_RES       I437
  U122   B13  DIFFIO_RX_T7N  10M04SAU324I7G  I155

VR_P3V3_EN_D_R   @S9S_MB_2U_LIB.S9S_MB_2U(SCH_1):VR_P3V3_EN_D_R
  PQ2      4      4  MOSFET_NCH_1D3S  I90
  U79      7  G1/G2  SLG55221120010VTR  I62

VR_P5V_EN       @S9S_MB_2U_LIB.S9S_MB_2U(SCH_1):VR_P5V_EN
  Q37      2     G1  MOSFET_NCH_DUAL  I75
  R1607    2      B  Q_RES       I85
  R1640    2      B  Q_RES       I84
  R1641    1      A  Q_RES       I74

VR_P5V_EN_D_R   @S9S_MB_2U_LIB.S9S_MB_2U(SCH_1):VR_P5V_EN_D_R
  C1226    1      A  Q_CAP       I78
  PQ1      4      4  MOSFET_NCH_1D3S  I91
  R1642    2      B  Q_RES       I87
  R1654    1      A  Q_RES       I77

VR_P5V_EN_D_R1   @S9S_MB_2U_LIB.S9S_MB_2U(SCH_1):VR_P5V_EN_D_R1
  Q37      3     D2  MOSFET_NCH_DUAL  I76
  R1654    2      B  Q_RES       I77

VR_P5V_EN_N     @S9S_MB_2U_LIB.S9S_MB_2U(SCH_1):VR_P5V_EN_N
  Q37      5     G2  MOSFET_NCH_DUAL  I76
  Q37      6     D1  MOSFET_NCH_DUAL  I75
  R1643    2      B  Q_RES       I86

VSENSE_PVCCD_HV_CPU0_DN   @S9S_MB_2U_LIB.S9S_MB_2U(SCH_1):VSENSE_PVCCD_HV_CPU0_DN
  PC627    2      B  Q_CAP       I18
  PR591    1      A  Q_RES       I78
  PU35    22  RGND0  ISL69260IRAZT  I51
  U2     BN11  VSS_VCCD_HV_SENSE  SOCKET4677_AZIFS054P001C01   I1

VSENSE_PVCCD_HV_CPU0_DP   @S9S_MB_2U_LIB.S9S_MB_2U(SCH_1):VSENSE_PVCCD_HV_CPU0_DP
  PJ54     1      1  Q_SHORT     I79
  PR592    1      A  Q_RES       I33
  U2     BU11  VCCD_HV_SENSE  SOCKET4677_AZIFS054P001C01   I1

VSENSE_PVCCD_HV_CPU1_DN   @S9S_MB_2U_LIB.S9S_MB_2U(SCH_1):VSENSE_PVCCD_HV_CPU1_DN
  PC389    2      B  Q_CAP       I248
  PR558    1      A  Q_RES       I206
  PU18    22  RGND0  ISL69260IRAZT  I243
  U1     BN11  VSS_VCCD_HV_SENSE  SOCKET4677_AZIFS054P001C01  I16

VSENSE_PVCCD_HV_CPU1_DP   @S9S_MB_2U_LIB.S9S_MB_2U(SCH_1):VSENSE_PVCCD_HV_CPU1_DP
  PJ48     1      1  Q_SHORT     I207
  PR559    1      A  Q_RES       I223
  U1     BU11  VCCD_HV_SENSE  SOCKET4677_AZIFS054P001C01  I16

VSENSE_PVCCFA_EHV_CPU0_DN   @S9S_MB_2U_LIB.S9S_MB_2U(SCH_1):VSENSE_PVCCFA_EHV_CPU0_DN
  PC216    2      B  Q_CAP       I46
  PR520    1      A  Q_RES        I8
  PU5     31  RGND1  ISL69260IRAZT  I51
  U2     BA11  VSS_VCCFA_EHV_SENSE  SOCKET4677_AZIFS054P001C01   I1

VSENSE_PVCCFA_EHV_CPU0_DP   @S9S_MB_2U_LIB.S9S_MB_2U(SCH_1):VSENSE_PVCCFA_EHV_CPU0_DP
  PJ46     1      1  Q_SHORT      I9
  PR522    1      A  Q_RES       I10
  U2     AU11  VCCFA_EHV_SENSE  SOCKET4677_AZIFS054P001C01   I1

VSENSE_PVCCFA_EHV_CPU1_DN   @S9S_MB_2U_LIB.S9S_MB_2U(SCH_1):VSENSE_PVCCFA_EHV_CPU1_DN
  PC469    2      B  Q_CAP       I64
  PR567    1      A  Q_RES       I19
  PU22    31  RGND1  ISL69260IRAZT  I61
  U1     BA11  VSS_VCCFA_EHV_SENSE  SOCKET4677_AZIFS054P001C01  I16

VSENSE_PVCCFA_EHV_CPU1_DP   @S9S_MB_2U_LIB.S9S_MB_2U(SCH_1):VSENSE_PVCCFA_EHV_CPU1_DP
  PJ51     1      1  Q_SHORT     I20
  PR569    1      A  Q_RES       I21
  U1     AU11  VCCFA_EHV_SENSE  SOCKET4677_AZIFS054P001C01  I16

VSENSE_PVCCFA_EHV_FIVRA_CPU0_DN   @S9S_MB_2U_LIB.S9S_MB_2U(SCH_1):VSENSE_PVCCFA_EHV_FIVRA_CPU0_DN
  PC594    2      B  Q_CAP       I56
  PR586    1      A  Q_RES       I16
  PU14    39  RGND1  RAA229126GNPHA0  I48
  U2     AT85  VSS_VCCFA_EHV_FIVRA_SENSE  SOCKET4677_AZIFS054P001C01   I1

VSENSE_PVCCFA_EHV_FIVRA_CPU0_DP   @S9S_MB_2U_LIB.S9S_MB_2U(SCH_1):VSENSE_PVCCFA_EHV_FIVRA_CPU0_DP
  PJ53     1      1  Q_SHORT     I19
  PR587    1      A  Q_RES       I20
  U2     AY85  VCCFA_EHV_FIVRA_SENSE  SOCKET4677_AZIFS054P001C01   I1

VSENSE_PVCCFA_EHV_FIVRA_CPU1_DN   @S9S_MB_2U_LIB.S9S_MB_2U(SCH_1):VSENSE_PVCCFA_EHV_FIVRA_CPU1_DN
  PC422    2      B  Q_CAP       I219
  PR560    1      A  Q_RES       I171
  PU29    39  RGND1  RAA229126GNPHA0  I211
  U1     AT85  VSS_VCCFA_EHV_FIVRA_SENSE  SOCKET4677_AZIFS054P001C01  I16

VSENSE_PVCCFA_EHV_FIVRA_CPU1_DP   @S9S_MB_2U_LIB.S9S_MB_2U(SCH_1):VSENSE_PVCCFA_EHV_FIVRA_CPU1_DP
  PJ49     1      1  Q_SHORT     I174
  PR561    1      A  Q_RES       I175
  U1     AY85  VCCFA_EHV_FIVRA_SENSE  SOCKET4677_AZIFS054P001C01  I16

VSENSE_PVCCINFAON_CPU0_DN   @S9S_MB_2U_LIB.S9S_MB_2U(SCH_1):VSENSE_PVCCINFAON_CPU0_DN
  PC215    2      B  Q_CAP       I47
  PR519    1      A  Q_RES       I11
  PU5     22  RGND0  ISL69260IRAZT  I51
  U2     CE11  VSS_VCCINFAON_SENSE  SOCKET4677_AZIFS054P001C01   I1

VSENSE_PVCCINFAON_CPU0_DP   @S9S_MB_2U_LIB.S9S_MB_2U(SCH_1):VSENSE_PVCCINFAON_CPU0_DP
  PJ45     1      1  Q_SHORT     I15
  PR521    1      A  Q_RES       I16
  U2     CA11  VCCINFAON_SENSE  SOCKET4677_AZIFS054P001C01   I1

VSENSE_PVCCINFAON_CPU1_DN   @S9S_MB_2U_LIB.S9S_MB_2U(SCH_1):VSENSE_PVCCINFAON_CPU1_DN
  PC468    2      B  Q_CAP       I65
  PR566    1      A  Q_RES       I22
  PU22    22  RGND0  ISL69260IRAZT  I61
  U1     CE11  VSS_VCCINFAON_SENSE  SOCKET4677_AZIFS054P001C01  I16

VSENSE_PVCCINFAON_CPU1_DP   @S9S_MB_2U_LIB.S9S_MB_2U(SCH_1):VSENSE_PVCCINFAON_CPU1_DP
  PJ50     1      1  Q_SHORT     I33
  PR568    1      A  Q_RES       I98
  U1     CA11  VCCINFAON_SENSE  SOCKET4677_AZIFS054P001C01  I16

VSENSE_PVCCIN_CPU0_DN   @S9S_MB_2U_LIB.S9S_MB_2U(SCH_1):VSENSE_PVCCIN_CPU0_DN
  PC331    2      B  Q_CAP       I62
  PR527    1      A  Q_RES       I21
  PU14    26  RGND0  RAA229126GNPHA0  I48
  U2     BC90  VSS_VCCIN_SENSE  SOCKET4677_AZIFS054P001C01   I1

VSENSE_PVCCIN_CPU0_DP   @S9S_MB_2U_LIB.S9S_MB_2U(SCH_1):VSENSE_PVCCIN_CPU0_DP
  PJ47     1      1  Q_SHORT     I30
  PR531    1      A  Q_RES       I31
  U2     BD87  VCCIN_SENSE  SOCKET4677_AZIFS054P001C01   I1

VSENSE_PVCCIN_CPU1_DN   @S9S_MB_2U_LIB.S9S_MB_2U(SCH_1):VSENSE_PVCCIN_CPU1_DN
  PC549    2      B  Q_CAP       I240
  PR574    1      A  Q_RES       I176
  PU29    26  RGND0  RAA229126GNPHA0  I211
  U1     BC90  VSS_VCCIN_SENSE  SOCKET4677_AZIFS054P001C01  I16

VSENSE_PVCCIN_CPU1_DP   @S9S_MB_2U_LIB.S9S_MB_2U(SCH_1):VSENSE_PVCCIN_CPU1_DP
  PJ52     1      1  Q_SHORT     I187
  PR578    1      A  Q_RES       I188
  U1     BD87  VCCIN_SENSE  SOCKET4677_AZIFS054P001C01  I16

XTAL_CLK_GEN1_25M_X1   @S9S_MB_2U_LIB.S9S_MB_2U(SCH_1):XTAL_CLK_GEN1_25M_X1
  R1724    2      B  Q_RES       I287
  U13    A13  XIN_CLKIN  9SQ440NQQI8  I180

XTAL_CLK_GEN1_25M_X1_R   @S9S_MB_2U_LIB.S9S_MB_2U(SCH_1):XTAL_CLK_GEN1_25M_X1_R
  C113     1      A  Q_CAP       I186
  R1724    1      A  Q_RES       I287
  Y2       1      1  Q_XTAL_4P_13  I185

XTAL_CLK_GEN1_25M_X2   @S9S_MB_2U_LIB.S9S_MB_2U(SCH_1):XTAL_CLK_GEN1_25M_X2
  C118     1      A  Q_CAP       I183
  U13    B11   XOUT  9SQ440NQQI8  I180
  Y2       3      3  Q_XTAL_4P_13  I185

XTAL_PCH_25M_IN   @S9S_MB_2U_LIB.S9S_MB_2U(SCH_1):XTAL_PCH_25M_IN
  R1720    2      B  Q_RES       I103
  U4     B23  XTAL_IN  EMMITSBURG_REV0P9  I78

XTAL_PCH_25M_IN_R   @S9S_MB_2U_LIB.S9S_MB_2U(SCH_1):XTAL_PCH_25M_IN_R
  C103     1      A  Q_CAP       I77
  R1316    1      A  Q_RES       I92
  R1720    1      A  Q_RES       I103
  Y3       1     X1  Q_XTAL_4P_13BI_24GND  I75

XTAL_PCH_25M_OUT   @S9S_MB_2U_LIB.S9S_MB_2U(SCH_1):XTAL_PCH_25M_OUT
  C104     1      A  Q_CAP       I76
  R1316    2      B  Q_RES       I92
  U4     D23  XTAL_OUT  EMMITSBURG_REV0P9  I78
  Y3       3     X2  Q_XTAL_4P_13BI_24GND  I75

XTAL_PCH_RTC1   @S9S_MB_2U_LIB.S9S_MB_2U(SCH_1):XTAL_PCH_RTC1
  C1508    1      A  Q_CAP       I17
  R120     2      B  Q_RES       I74
  U4     BE6  RTCX1  EMMITSBURG_REV0P9  I78
  Y1       2      2  Q_CRYSTAL   I11

XTAL_PCH_RTC2   @S9S_MB_2U_LIB.S9S_MB_2U(SCH_1):XTAL_PCH_RTC2
  R1721    2      B  Q_RES       I104
  U4     BF7  RTCX2  EMMITSBURG_REV0P9  I78

XTAL_PCH_RTC2_R   @S9S_MB_2U_LIB.S9S_MB_2U(SCH_1):XTAL_PCH_RTC2_R
  C1507    1      A  Q_CAP       I10
  R120     1      A  Q_RES       I74
  R1721    1      A  Q_RES       I104
  Y1       1      1  Q_CRYSTAL   I11
END OF SIGNAL CROSS REFERENCE
**** Part Type 'SCHOTTKY_AC' ('SCHOTTKY_AC-SX34F,SMLF,IC,BC00A') ****
**** Part Type 'SCONN140_G64V3431BHR' ('SCONN140_G64V3431BHR-SCONN140_A') ****
**** Part Type 'SCONN140_G64V3431BHR' ('SCONN140_G64V3431BHR-SCONN140_B') ****
**** Part Type 'SCONN168_623403212' ('SCONN168_623403212-SCONN168_6-A') ****
**** Part Type 'SCONN280_ME1028040102011' ('SCONN280_ME1028040102011-SCONNA') ****
**** Part Type 'SCONN288_ADR50001P003C01' ('SCONN288_ADR50001P003C01-SCONNA') ****
**** Part Type 'SCONN288_ADR50001P013C01' ('SCONN288_ADR50001P013C01-SCONNA') ****
**** Part Type 'SCONN60_QSH03001LDAKTR' ('SCONN60_QSH03001LDAKTR-SCONN60A') ****
**** Part Type 'SCONN75K_APCI0155P004A' ('SCONN75K_APCI0155P004A-SCONN75A') ****
**** Part Type 'SCONN84_123318136' ('SCONN84_123318136-SCONN84_1-23A') ****
**** Part Type 'SLG55221120010VTR' ('SLG55221120010VTR-SLG55221-120A') ****
**** Part Type 'SN74LVC1G07DCKR' ('SN74LVC1G07DCKR-SN74LVC1G07DCKA') ****
**** Part Type 'SN74LVC1G08DBVR' ('SN74LVC1G08DBVR_SMLF-SN74LVC1GA') ****
**** Part Type 'SN74LVC1G17DCKR' ('SN74LVC1G17DCKR-SN74LVC1G17DCKA') ****
**** Part Type 'SN74LVC2G07DCKR' ('SN74LVC2G07DCKR_SMLF-SN74LVC2GA') ****
**** Part Type 'SN74LVC2G17DCKR' ('SN74LVC2G17DCKR-SN74LVC2G17DCKA') ****
**** Part Type 'SOCKET4677_AZIFS054P001C01' ('SOCKET4677_AZIFS054P001C01-SOCA') ****
**** Part Type 'SW8S_DHNF04FTVTR' ('SW8S_DHNF04FTVTR-SW8S_DHNF04FTA') ****
**** Part Type 'TDR_3P_TH2' ('TDR_3P_TH2-EMPTY,N_A') ****
**** Part Type 'TMP75AIDR' ('TMP75AIDR-TMP75AIDR,SMLF,IC,ALA') ****
**** Part Type 'TPS2553DBVR1' ('TPS2553DBVR1-TPS2553DBVR-1,SMLA') ****
**** Part Type 'TPS259520DSGR' ('TPS259520DSGR-TPS259520DSGR,SMA') ****
**** Part Type 'TPS259540DSGR' ('TPS259540DSGR-TPS259540DSGR,SMA') ****
**** Part Type 'TPS259824ONRGER' ('TPS259824ONRGER-TPS259824ONRGEA') ****
**** Part Type 'TPS3897PDRYR' ('TPS3897PDRYR-TPS3897PDRYR,SMLFA') ****
**** Part Type 'TP_TDR_4P_FTS' ('TP_TDR_4P_FTS_TH-TP_TDR_4P_DIPA') ****
**** Part Type 'TP' ('TP_TP-NA,TP30') ****
**** Part Type 'TS3A24157RSER' ('TS3A24157RSER-TS3A24157RSER,SMA') ****

END.
